G04 ================== begin FILE IDENTIFICATION RECORD ==================*
G04 Layout Name:  9127_F0T_Expander_BD_F_v02_0110_1240.brd*
G04 Film Name:    gnd7*
G04 File Format:  Gerber RS274X*
G04 File Origin:  Cadence Allegro 17.2-S081*
G04 Origin Date:  Wed Jan 11 16:06:30 2023*
G04 *
G04 Layer:  DRAWING FORMAT/TITLE_BLOCK_A*
G04 Layer:  PIN/SPECIAL_DRILL*
G04 Layer:  VIA CLASS/GND7*
G04 Layer:  PIN/GND7*
G04 Layer:  MANUFACTURING/PHOTOPLOT_OUTLINE*
G04 Layer:  ETCH/GND7*
G04 Layer:  DRAWING FORMAT/TITLE_BLOCK*
G04 Layer:  DRAWING FORMAT/TITLE_DATA_GND7*
G04 *
G04 Offset:    (0.00 0.00)*
G04 Mirror:    No*
G04 Mode:      Negative*
G04 Rotation:  0*
G04 FullContactRelief:  No*
G04 UndefLineWidth:     6.00*
G04 ================== end FILE IDENTIFICATION RECORD ====================*
%FSLAX25Y25*MOIN*%
%IR0*IPPOS*OFA0.00000B0.00000*MIA0B0*SFA1.00000B1.00000*%
%ADD15C,.03*%
%ADD53C,.06*%
%ADD23C,.024*%
%ADD54C,.061*%
%ADD33C,.0322*%
%ADD45C,.071*%
%ADD41C,.026*%
%AMMACRO28*
4,1,36,0.0,.01,
-.001736,.009848,
-.00342,.009397,
-.005,.00866,
-.006428,.00766,
-.00766,.006428,
-.00866,.005,
-.009397,.00342,
-.009848,.001736,
-.01,0.0,
-.009848,-.001736,
-.009397,-.00342,
-.00866,-.005,
-.00766,-.006428,
-.006428,-.00766,
-.005,-.00866,
-.00342,-.009397,
-.001736,-.009848,
0.0,-.01,
.001736,-.009848,
.00342,-.009397,
.005,-.00866,
.006428,-.00766,
.00766,-.006428,
.00866,-.005,
.009397,-.00342,
.009848,-.001736,
.01,0.0,
.009848,.001736,
.009397,.00342,
.00866,.005,
.00766,.006428,
.006428,.00766,
.005,.00866,
.00342,.009397,
.001736,.009848,
0.0,.01,
0.0*
%
%ADD28MACRO28*%
%ADD51C,.082*%
%ADD43C,.028*%
%AMMACRO38*
4,1,20,-.0075,-.05555,
-.0075,-.06273,
-.013677,-.060878,
-.019439,-.057981,
-.024611,-.054127,
-.029034,-.049434,
-.032576,-.044045,
-.035127,-.038122,
-.036612,-.031846,
-.037,-.0265,
-.037,-.0075,
-.03,-.0075,
-.03,-.0265,
-.029544,-.03171,
-.028191,-.036762,
-.02598,-.041502,
-.022981,-.045786,
-.019282,-.049484,
-.014998,-.052484,
-.010258,-.054694,
-.0075,-.05555,
270.*
4,1,20,.0075,-.06273,
.0075,-.05555,
.01243,-.053806,
.016983,-.051232,
.02102,-.047906,
.024418,-.043931,
.027073,-.039425,
.028906,-.034527,
.029861,-.029385,
.03,-.0265,
.03,-.0075,
.037,-.0075,
.037,-.0265,
.036438,-.032925,
.034769,-.039154,
.032043,-.044999,
.028344,-.050282,
.023784,-.054842,
.018501,-.058541,
.012656,-.061266,
.0075,-.06273,
270.*
4,1,20,-.0075,.06273,
-.0075,.05555,
-.01243,.053806,
-.016983,.051232,
-.02102,.047906,
-.024418,.043931,
-.027073,.039425,
-.028906,.034527,
-.029861,.029385,
-.03,.0265,
-.03,.0075,
-.037,.0075,
-.037,.0265,
-.036438,.032925,
-.034769,.039154,
-.032043,.044999,
-.028344,.050282,
-.023784,.054842,
-.018501,.058541,
-.012656,.061266,
-.0075,.06273,
270.*
4,1,20,.0075,.05555,
.0075,.06273,
.013677,.060878,
.019439,.057981,
.024611,.054127,
.029034,.049434,
.032576,.044045,
.035127,.038122,
.036612,.031846,
.037,.0265,
.037,.0075,
.03,.0075,
.03,.0265,
.029544,.03171,
.028191,.036762,
.02598,.041502,
.022981,.045786,
.019282,.049484,
.014998,.052484,
.010258,.054694,
.0075,.05555,
270.*
%
%ADD38MACRO38*%
%AMMACRO30*
4,1,36,.0025,0.0,
.002462,.000434,
.002349,.000855,
.002165,.00125,
.001915,.001607,
.001607,.001915,
.00125,.002165,
.000855,.002349,
.000434,.002462,
0.0,.0025,
-.000434,.002462,
-.000855,.002349,
-.00125,.002165,
-.001607,.001915,
-.001915,.001607,
-.002165,.00125,
-.002349,.000855,
-.002462,.000434,
-.0025,0.0,
-.002462,-.000434,
-.002349,-.000855,
-.002165,-.00125,
-.001915,-.001607,
-.001607,-.001915,
-.00125,-.002165,
-.000855,-.002349,
-.000434,-.002462,
0.0,-.0025,
.000434,-.002462,
.000855,-.002349,
.00125,-.002165,
.001607,-.001915,
.001915,-.001607,
.002165,-.00125,
.002349,-.000855,
.002462,-.000434,
.0025,0.0,
315.*
%
%ADD30MACRO30*%
%AMMACRO14*
4,1,36,.0025,0.0,
.002462,.000434,
.002349,.000855,
.002165,.00125,
.001915,.001607,
.001607,.001915,
.00125,.002165,
.000855,.002349,
.000434,.002462,
0.0,.0025,
-.000434,.002462,
-.000855,.002349,
-.00125,.002165,
-.001607,.001915,
-.001915,.001607,
-.002165,.00125,
-.002349,.000855,
-.002462,.000434,
-.0025,0.0,
-.002462,-.000434,
-.002349,-.000855,
-.002165,-.00125,
-.001915,-.001607,
-.001607,-.001915,
-.00125,-.002165,
-.000855,-.002349,
-.000434,-.002462,
0.0,-.0025,
.000434,-.002462,
.000855,-.002349,
.00125,-.002165,
.001607,-.001915,
.001915,-.001607,
.002165,-.00125,
.002349,-.000855,
.002462,-.000434,
.0025,0.0,
180.*
%
%ADD14MACRO14*%
%AMMACRO10*
4,1,36,.0025,0.0,
.002462,.000434,
.002349,.000855,
.002165,.00125,
.001915,.001607,
.001607,.001915,
.00125,.002165,
.000855,.002349,
.000434,.002462,
0.0,.0025,
-.000434,.002462,
-.000855,.002349,
-.00125,.002165,
-.001607,.001915,
-.001915,.001607,
-.002165,.00125,
-.002349,.000855,
-.002462,.000434,
-.0025,0.0,
-.002462,-.000434,
-.002349,-.000855,
-.002165,-.00125,
-.001915,-.001607,
-.001607,-.001915,
-.00125,-.002165,
-.000855,-.002349,
-.000434,-.002462,
0.0,-.0025,
.000434,-.002462,
.000855,-.002349,
.00125,-.002165,
.001607,-.001915,
.001915,-.001607,
.002165,-.00125,
.002349,-.000855,
.002462,-.000434,
.0025,0.0,
270.*
%
%ADD10MACRO10*%
%AMMACRO46*
4,1,36,-.0025,0.0,
-.002462,.000434,
-.002349,.000855,
-.002165,.00125,
-.001915,.001607,
-.001607,.001915,
-.00125,.002165,
-.000855,.002349,
-.000434,.002462,
0.0,.0025,
.000434,.002462,
.000855,.002349,
.00125,.002165,
.001607,.001915,
.001915,.001607,
.002165,.00125,
.002349,.000855,
.002462,.000434,
.0025,0.0,
.002462,-.000434,
.002349,-.000855,
.002165,-.00125,
.001915,-.001607,
.001607,-.001915,
.00125,-.002165,
.000855,-.002349,
.000434,-.002462,
0.0,-.0025,
-.000434,-.002462,
-.000855,-.002349,
-.00125,-.002165,
-.001607,-.001915,
-.001915,-.001607,
-.002165,-.00125,
-.002349,-.000855,
-.002462,-.000434,
-.0025,0.0,
180.*
%
%ADD46MACRO46*%
%AMMACRO36*
4,1,36,.003,0.0,
.002954,.000521,
.002819,.001026,
.002598,.0015,
.002298,.001928,
.001928,.002298,
.0015,.002598,
.001026,.002819,
.000521,.002954,
0.0,.003,
-.000521,.002954,
-.001026,.002819,
-.0015,.002598,
-.001928,.002298,
-.002298,.001928,
-.002598,.0015,
-.002819,.001026,
-.002954,.000521,
-.003,0.0,
-.002954,-.000521,
-.002819,-.001026,
-.002598,-.0015,
-.002298,-.001928,
-.001928,-.002298,
-.0015,-.002598,
-.001026,-.002819,
-.000521,-.002954,
0.0,-.003,
.000521,-.002954,
.001026,-.002819,
.0015,-.002598,
.001928,-.002298,
.002298,-.001928,
.002598,-.0015,
.002819,-.001026,
.002954,-.000521,
.003,0.0,
270.*
%
%ADD36MACRO36*%
%AMMACRO25*
4,1,36,.003,0.0,
.002954,.000521,
.002819,.001026,
.002598,.0015,
.002298,.001928,
.001928,.002298,
.0015,.002598,
.001026,.002819,
.000521,.002954,
0.0,.003,
-.000521,.002954,
-.001026,.002819,
-.0015,.002598,
-.001928,.002298,
-.002298,.001928,
-.002598,.0015,
-.002819,.001026,
-.002954,.000521,
-.003,0.0,
-.002954,-.000521,
-.002819,-.001026,
-.002598,-.0015,
-.002298,-.001928,
-.001928,-.002298,
-.0015,-.002598,
-.001026,-.002819,
-.000521,-.002954,
0.0,-.003,
.000521,-.002954,
.001026,-.002819,
.0015,-.002598,
.001928,-.002298,
.002298,-.001928,
.002598,-.0015,
.002819,-.001026,
.002954,-.000521,
.003,0.0,
180.*
%
%ADD25MACRO25*%
%ADD22C,.074*%
%AMMACRO42*
4,1,36,-.003,0.0,
-.002954,.000521,
-.002819,.001026,
-.002598,.0015,
-.002298,.001928,
-.001928,.002298,
-.0015,.002598,
-.001026,.002819,
-.000521,.002954,
0.0,.003,
.000521,.002954,
.001026,.002819,
.0015,.002598,
.001928,.002298,
.002298,.001928,
.002598,.0015,
.002819,.001026,
.002954,.000521,
.003,0.0,
.002954,-.000521,
.002819,-.001026,
.002598,-.0015,
.002298,-.001928,
.001928,-.002298,
.0015,-.002598,
.001026,-.002819,
.000521,-.002954,
0.0,-.003,
-.000521,-.002954,
-.001026,-.002819,
-.0015,-.002598,
-.001928,-.002298,
-.002298,-.001928,
-.002598,-.0015,
-.002819,-.001026,
-.002954,-.000521,
-.003,0.0,
180.*
%
%ADD42MACRO42*%
%ADD26C,.0435*%
%ADD34C,.0257*%
%ADD58C,.087*%
%ADD18C,.0277*%
%AMMACRO44*
4,1,18,.09673,.06845,
.107147,.050613,
.114308,.031238,
.117996,.010914,
.118098,-.009741,
.114613,-.030101,
.107644,-.049546,
.097406,-.067485,
.09673,-.06845,
.10175,-.07347,
.112962,-.054685,
.120742,-.034239,
.124853,-.012752,
.125171,.009122,
.121685,.030719,
.114502,.051383,
.10384,.070486,
.10175,.07347,
.09673,.06845,
90.*
4,1,18,.06845,-.09673,
.050613,-.107147,
.031238,-.114308,
.010914,-.117996,
-.009741,-.118098,
-.030101,-.114613,
-.049546,-.107644,
-.067485,-.097406,
-.06845,-.09673,
-.07347,-.10175,
-.054685,-.112962,
-.034239,-.120742,
-.012752,-.124853,
.009122,-.125171,
.030719,-.121685,
.051383,-.114502,
.070486,-.10384,
.07347,-.10175,
.06845,-.09673,
90.*
4,1,18,-.09673,-.06845,
-.107147,-.050613,
-.114308,-.031238,
-.117996,-.010914,
-.118098,.009741,
-.114613,.030101,
-.107644,.049546,
-.097406,.067485,
-.09673,.06845,
-.10175,.07347,
-.112962,.054685,
-.120742,.034239,
-.124853,.012752,
-.125171,-.009122,
-.121685,-.030719,
-.114502,-.051383,
-.10384,-.070486,
-.10175,-.07347,
-.09673,-.06845,
90.*
4,1,18,-.06845,.09673,
-.050613,.107147,
-.031238,.114308,
-.010914,.117996,
.009741,.118098,
.030101,.114613,
.049546,.107644,
.067485,.097406,
.06845,.09673,
.07347,.10175,
.054685,.112962,
.034239,.120742,
.012752,.124853,
-.009122,.125171,
-.030719,.121685,
-.051383,.114502,
-.070486,.10384,
-.07347,.10175,
-.06845,.09673,
90.*
%
%ADD44MACRO44*%
%AMMACRO11*
4,1,15,.06231,.03403,
.067273,.022693,
.070191,.010666,
.070977,-.001684,
.069606,-.013984,
.066121,-.025858,
.06231,-.03403,
.06745,-.03917,
.073227,-.026862,
.076779,-.013739,
.077998,-.000197,
.076848,.01335,
.073362,.026492,
.067647,.038828,
.06745,.03917,
.06231,.03403,
0.0*
4,1,15,.03403,-.06231,
.022693,-.067273,
.010666,-.070191,
-.001684,-.070977,
-.013984,-.069606,
-.025858,-.066121,
-.03403,-.06231,
-.03917,-.06745,
-.026862,-.073227,
-.013739,-.076779,
-.000197,-.077998,
.01335,-.076848,
.026492,-.073362,
.038828,-.067647,
.03917,-.06745,
.03403,-.06231,
0.0*
4,1,15,-.06231,-.03403,
-.067273,-.022693,
-.070191,-.010666,
-.070977,.001684,
-.069606,.013984,
-.066121,.025858,
-.06231,.03403,
-.06745,.03917,
-.073227,.026862,
-.076779,.013739,
-.077998,.000197,
-.076848,-.01335,
-.073362,-.026492,
-.067647,-.038828,
-.06745,-.03917,
-.06231,-.03403,
0.0*
4,1,15,-.03403,.06231,
-.022693,.067273,
-.010666,.070191,
.001684,.070977,
.013984,.069606,
.025858,.066121,
.03403,.06231,
.03917,.06745,
.026862,.073227,
.013739,.076779,
.000197,.077998,
-.01335,.076848,
-.026492,.073362,
-.038828,.067647,
-.03917,.06745,
-.03403,.06231,
0.0*
%
%ADD11MACRO11*%
%ADD20C,.099*%
%AMMACRO19*
4,1,18,.09673,.06845,
.107147,.050613,
.114308,.031238,
.117996,.010914,
.118098,-.009741,
.114613,-.030101,
.107644,-.049546,
.097406,-.067485,
.09673,-.06845,
.10175,-.07347,
.112962,-.054685,
.120742,-.034239,
.124853,-.012752,
.125171,.009122,
.121685,.030719,
.114502,.051383,
.10384,.070486,
.10175,.07347,
.09673,.06845,
0.0*
4,1,18,.06845,-.09673,
.050613,-.107147,
.031238,-.114308,
.010914,-.117996,
-.009741,-.118098,
-.030101,-.114613,
-.049546,-.107644,
-.067485,-.097406,
-.06845,-.09673,
-.07347,-.10175,
-.054685,-.112962,
-.034239,-.120742,
-.012752,-.124853,
.009122,-.125171,
.030719,-.121685,
.051383,-.114502,
.070486,-.10384,
.07347,-.10175,
.06845,-.09673,
0.0*
4,1,18,-.09673,-.06845,
-.107147,-.050613,
-.114308,-.031238,
-.117996,-.010914,
-.118098,.009741,
-.114613,.030101,
-.107644,.049546,
-.097406,.067485,
-.09673,.06845,
-.10175,.07347,
-.112962,.054685,
-.120742,.034239,
-.124853,.012752,
-.125171,-.009122,
-.121685,-.030719,
-.114502,-.051383,
-.10384,-.070486,
-.10175,-.07347,
-.09673,-.06845,
0.0*
4,1,18,-.06845,.09673,
-.050613,.107147,
-.031238,.114308,
-.010914,.117996,
.009741,.118098,
.030101,.114613,
.049546,.107644,
.067485,.097406,
.06845,.09673,
.07347,.10175,
.054685,.112962,
.034239,.120742,
.012752,.124853,
-.009122,.125171,
-.030719,.121685,
-.051383,.114502,
-.070486,.10384,
-.07347,.10175,
-.06845,.09673,
0.0*
%
%ADD19MACRO19*%
%ADD32C,.0299*%
%AMMACRO61*
4,1,19,-.0075,-.03785,
-.011528,-.036185,
-.015205,-.033846,
-.01842,-.030904,
-.021075,-.027448,
-.02309,-.023584,
-.024404,-.019428,
-.024975,-.015108,
-.025,-.014,
-.025,-.0075,
-.018,-.0075,
-.018,-.014,
-.017727,-.017125,
-.016915,-.020155,
-.015589,-.022998,
-.01379,-.025567,
-.011572,-.027785,
-.009002,-.029584,
-.0075,-.03036,
-.0075,-.03785,
180.*
4,1,19,.0075,-.03785,
.0075,-.03036,
.010227,-.02881,
.012643,-.02681,
.014676,-.024421,
.016262,-.021715,
.017355,-.018774,
.017921,-.015689,
.018,-.014,
.018,-.0075,
.025,-.0075,
.025,-.014,
.02462,-.018342,
.023492,-.022551,
.02165,-.026501,
.019151,-.030071,
.016069,-.033153,
.012499,-.035652,
.008549,-.037494,
.0075,-.03785,
180.*
4,1,19,-.025,.0075,
-.025,.014,
-.02462,.018342,
-.023492,.022551,
-.02165,.026501,
-.019151,.030071,
-.016069,.033153,
-.012499,.035652,
-.008549,.037494,
-.0075,.03785,
-.0075,.03036,
-.010227,.02881,
-.012643,.02681,
-.014676,.024421,
-.016262,.021715,
-.017355,.018774,
-.017921,.015689,
-.018,.014,
-.018,.0075,
-.025,.0075,
180.*
4,1,19,.018,.0075,
.018,.014,
.017727,.017125,
.016915,.020155,
.015589,.022998,
.01379,.025567,
.011572,.027785,
.009002,.029584,
.0075,.03036,
.0075,.03785,
.011528,.036185,
.015205,.033846,
.01842,.030904,
.021075,.027448,
.02309,.023584,
.024404,.019428,
.024975,.015108,
.025,.014,
.025,.0075,
.018,.0075,
180.*
%
%ADD61MACRO61*%
%AMMACRO37*
4,1,16,.02584,.01524,
.028094,.010521,
.029494,.005483,
.029998,.000278,
.029591,-.004935,
.028284,-.009999,
.026118,-.014758,
.02584,-.01524,
.03092,-.02032,
.033979,-.014642,
.036005,-.008519,
.036938,-.002138,
.036748,.004309,
.035441,.010625,
.033058,.016618,
.03092,.02032,
.02584,.01524,
0.0*
4,1,16,.01524,-.02584,
.010521,-.028094,
.005483,-.029494,
.000278,-.029998,
-.004935,-.029591,
-.009999,-.028284,
-.014758,-.026118,
-.01524,-.02584,
-.02032,-.03092,
-.014642,-.033979,
-.008519,-.036005,
-.002138,-.036938,
.004309,-.036748,
.010625,-.035441,
.016618,-.033058,
.02032,-.03092,
.01524,-.02584,
0.0*
4,1,16,-.02584,-.01524,
-.028094,-.010521,
-.029494,-.005483,
-.029998,-.000278,
-.029591,.004935,
-.028284,.009999,
-.026118,.014758,
-.02584,.01524,
-.03092,.02032,
-.033979,.014642,
-.036005,.008519,
-.036938,.002138,
-.036748,-.004309,
-.035441,-.010625,
-.033058,-.016618,
-.03092,-.02032,
-.02584,-.01524,
0.0*
4,1,16,-.01524,.02584,
-.010521,.028094,
-.005483,.029494,
-.000278,.029998,
.004935,.029591,
.009999,.028284,
.014758,.026118,
.01524,.02584,
.02032,.03092,
.014642,.033979,
.008519,.036005,
.002138,.036938,
-.004309,.036748,
-.010625,.035441,
-.016618,.033058,
-.02032,.03092,
-.01524,.02584,
0.0*
%
%ADD37MACRO37*%
%AMMACRO50*
4,1,15,.02142,.01082,
.022973,.006936,
.023829,.002841,
.02396,-.00134,
.023364,-.00548,
.022057,-.009454,
.02142,-.01082,
.02657,-.01597,
.02894,-.011114,
.03043,-.005919,
.030995,-.000545,
.030619,.004845,
.029313,.010088,
.027115,.015025,
.02657,.01597,
.02142,.01082,
90.*
4,1,15,.01082,-.02142,
.006936,-.022973,
.002841,-.023829,
-.00134,-.02396,
-.00548,-.023364,
-.009454,-.022057,
-.01082,-.02142,
-.01597,-.02657,
-.011114,-.02894,
-.005919,-.03043,
-.000545,-.030995,
.004845,-.030619,
.010088,-.029313,
.015025,-.027115,
.01597,-.02657,
.01082,-.02142,
90.*
4,1,15,-.02142,-.01082,
-.022973,-.006936,
-.023829,-.002841,
-.02396,.00134,
-.023364,.00548,
-.022057,.009454,
-.02142,.01082,
-.02657,.01597,
-.02894,.011114,
-.03043,.005919,
-.030995,.000545,
-.030619,-.004845,
-.029313,-.010088,
-.027115,-.015025,
-.02657,-.01597,
-.02142,-.01082,
90.*
4,1,15,-.01082,.02142,
-.006936,.022973,
-.002841,.023829,
.00134,.02396,
.00548,.023364,
.009454,.022057,
.01082,.02142,
.01597,.02657,
.011114,.02894,
.005919,.03043,
.000545,.030995,
-.004845,.030619,
-.010088,.029313,
-.015025,.027115,
-.01597,.02657,
-.01082,.02142,
90.*
%
%ADD50MACRO50*%
%AMMACRO48*
4,1,18,.07103,.05689,
.07983,.043691,
.086204,.029165,
.089959,.013753,
.09098,-.002077,
.089237,-.017844,
.084783,-.033069,
.077753,-.047289,
.07103,-.05689,
.07601,-.06186,
.085597,-.047721,
.092583,-.032132,
.096757,-.015567,
.09799,.001471,
.096246,.018464,
.091577,.034897,
.084126,.050269,
.07601,.06186,
.07103,.05689,
90.*
4,1,18,.05689,-.07103,
.043691,-.07983,
.029165,-.086204,
.013753,-.089959,
-.002077,-.09098,
-.017844,-.089237,
-.033069,-.084783,
-.047289,-.077753,
-.05689,-.07103,
-.06186,-.07601,
-.047721,-.085597,
-.032132,-.092583,
-.015567,-.096757,
.001471,-.09799,
.018464,-.096246,
.034897,-.091577,
.050269,-.084126,
.06186,-.07601,
.05689,-.07103,
90.*
4,1,18,-.07103,-.05689,
-.07983,-.043691,
-.086204,-.029165,
-.089959,-.013753,
-.09098,.002077,
-.089237,.017844,
-.084783,.033069,
-.077753,.047289,
-.07103,.05689,
-.07601,.06186,
-.085597,.047721,
-.092583,.032132,
-.096757,.015567,
-.09799,-.001471,
-.096246,-.018464,
-.091577,-.034897,
-.084126,-.050269,
-.07601,-.06186,
-.07103,-.05689,
90.*
4,1,18,-.05689,.07103,
-.043691,.07983,
-.029165,.086204,
-.013753,.089959,
.002077,.09098,
.017844,.089237,
.033069,.084783,
.047289,.077753,
.05689,.07103,
.06186,.07601,
.047721,.085597,
.032132,.092583,
.015567,.096757,
-.001471,.09799,
-.018464,.096246,
-.034897,.091577,
-.050269,.084126,
-.06186,.07601,
-.05689,.07103,
90.*
%
%ADD48MACRO48*%
%AMMACRO62*
4,1,19,-.0075,-.04535,
-.011528,-.043685,
-.015205,-.041346,
-.01842,-.038404,
-.021075,-.034948,
-.02309,-.031084,
-.024404,-.026928,
-.024975,-.022608,
-.025,-.0215,
-.025,-.0075,
-.018,-.0075,
-.018,-.0215,
-.017727,-.024625,
-.016915,-.027655,
-.015589,-.030498,
-.01379,-.033067,
-.011572,-.035285,
-.009002,-.037084,
-.0075,-.03786,
-.0075,-.04535,
180.*
4,1,19,.0075,-.04535,
.0075,-.03786,
.010227,-.03631,
.012643,-.03431,
.014676,-.031921,
.016262,-.029215,
.017355,-.026274,
.017921,-.023189,
.018,-.0215,
.018,-.0075,
.025,-.0075,
.025,-.0215,
.02462,-.025842,
.023492,-.030051,
.02165,-.034001,
.019151,-.037571,
.016069,-.040653,
.012499,-.043152,
.008549,-.044994,
.0075,-.04535,
180.*
4,1,19,-.025,.0075,
-.025,.0215,
-.02462,.025842,
-.023492,.030051,
-.02165,.034001,
-.019151,.037571,
-.016069,.040653,
-.012499,.043152,
-.008549,.044994,
-.0075,.04535,
-.0075,.03786,
-.010227,.03631,
-.012643,.03431,
-.014676,.031921,
-.016262,.029215,
-.017355,.026274,
-.017921,.023189,
-.018,.0215,
-.018,.0075,
-.025,.0075,
180.*
4,1,19,.018,.0075,
.018,.0215,
.017727,.024625,
.016915,.027655,
.015589,.030498,
.01379,.033067,
.011572,.035285,
.009002,.037084,
.0075,.03786,
.0075,.04535,
.011528,.043685,
.015205,.041346,
.01842,.038404,
.021075,.034948,
.02309,.031084,
.024404,.026928,
.024975,.022608,
.025,.0215,
.025,.0075,
.018,.0075,
180.*
%
%ADD62MACRO62*%
%AMMACRO55*
4,1,15,.02475,.01414,
.026829,.009627,
.028094,.004822,
.028504,-.000129,
.028049,-.005077,
.026741,-.009871,
.02475,-.01414,
.02984,-.01923,
.032726,-.013756,
.034617,-.007864,
.035457,-.001734,
.03522,.00445,
.033912,.010498,
.031574,.016227,
.02984,.01923,
.02475,.01414,
0.0*
4,1,15,.01414,-.02475,
.009627,-.026829,
.004822,-.028094,
-.000129,-.028504,
-.005077,-.028049,
-.009871,-.026741,
-.01414,-.02475,
-.01923,-.02984,
-.013756,-.032726,
-.007864,-.034617,
-.001734,-.035457,
.00445,-.03522,
.010498,-.033912,
.016227,-.031574,
.01923,-.02984,
.01414,-.02475,
0.0*
4,1,15,-.02475,-.01414,
-.026829,-.009627,
-.028094,-.004822,
-.028504,.000129,
-.028049,.005077,
-.026741,.009871,
-.02475,.01414,
-.02984,.01923,
-.032726,.013756,
-.034617,.007864,
-.035457,.001734,
-.03522,-.00445,
-.033912,-.010498,
-.031574,-.016227,
-.02984,-.01923,
-.02475,-.01414,
0.0*
4,1,15,-.01414,.02475,
-.009627,.026829,
-.004822,.028094,
.000129,.028504,
.005077,.028049,
.009871,.026741,
.01414,.02475,
.01923,.02984,
.013756,.032726,
.007864,.034617,
.001734,.035457,
-.00445,.03522,
-.010498,.033912,
-.016227,.031574,
-.01923,.02984,
-.01414,.02475,
0.0*
%
%ADD55MACRO55*%
%AMMACRO59*
4,1,15,.03682,.01914,
.039584,.012455,
.041146,.005393,
.041457,-.001834,
.040509,-.009005,
.03833,-.015903,
.03682,-.01914,
.04197,-.0243,
.045552,-.016643,
.04775,-.00848,
.048497,-.000059,
.047771,.008363,
.045593,.016531,
.042029,.024197,
.04197,.0243,
.03682,.01914,
90.*
4,1,15,.01914,-.03682,
.012455,-.039584,
.005393,-.041146,
-.001834,-.041457,
-.009005,-.040509,
-.015903,-.03833,
-.01914,-.03682,
-.0243,-.04197,
-.016643,-.045552,
-.00848,-.04775,
-.000059,-.048497,
.008363,-.047771,
.016531,-.045593,
.024197,-.042029,
.0243,-.04197,
.01914,-.03682,
90.*
4,1,15,-.03682,-.01914,
-.039584,-.012455,
-.041146,-.005393,
-.041457,.001834,
-.040509,.009005,
-.03833,.015903,
-.03682,.01914,
-.04197,.0243,
-.045552,.016643,
-.04775,.00848,
-.048497,.000059,
-.047771,-.008363,
-.045593,-.016531,
-.042029,-.024197,
-.04197,-.0243,
-.03682,-.01914,
90.*
4,1,15,-.01914,.03682,
-.012455,.039584,
-.005393,.041146,
.001834,.041457,
.009005,.040509,
.015903,.03833,
.01914,.03682,
.0243,.04197,
.016643,.045552,
.00848,.04775,
.000059,.048497,
-.008363,.047771,
-.016531,.045593,
-.024197,.042029,
-.0243,.04197,
-.01914,.03682,
90.*
%
%ADD59MACRO59*%
%AMMACRO60*
4,1,15,-.03682,.01914,
-.039584,.012455,
-.041146,.005393,
-.041457,-.001834,
-.040509,-.009005,
-.03833,-.015903,
-.03682,-.01914,
-.04197,-.0243,
-.045552,-.016643,
-.04775,-.00848,
-.048497,-.000059,
-.047771,.008363,
-.045593,.016531,
-.042029,.024197,
-.04197,.0243,
-.03682,.01914,
90.*
4,1,15,-.01914,-.03682,
-.012455,-.039584,
-.005393,-.041146,
.001834,-.041457,
.009005,-.040509,
.015903,-.03833,
.01914,-.03682,
.0243,-.04197,
.016643,-.045552,
.00848,-.04775,
.000059,-.048497,
-.008363,-.047771,
-.016531,-.045593,
-.024197,-.042029,
-.0243,-.04197,
-.01914,-.03682,
90.*
4,1,15,.03682,-.01914,
.039584,-.012455,
.041146,-.005393,
.041457,.001834,
.040509,.009005,
.03833,.015903,
.03682,.01914,
.04197,.0243,
.045552,.016643,
.04775,.00848,
.048497,.000059,
.047771,-.008363,
.045593,-.016531,
.042029,-.024197,
.04197,-.0243,
.03682,-.01914,
90.*
4,1,15,.01914,.03682,
.012455,.039584,
.005393,.041146,
-.001834,.041457,
-.009005,.040509,
-.015903,.03833,
-.01914,.03682,
-.0243,.04197,
-.016643,.045552,
-.00848,.04775,
-.000059,.048497,
.008363,.047771,
.016531,.045593,
.024197,.042029,
.0243,.04197,
.01914,.03682,
90.*
%
%ADD60MACRO60*%
%ADD63C,.142*%
%ADD13C,.125*%
%ADD29C,.208*%
%ADD47C,.164*%
%ADD17C,.155*%
%ADD39C,.256*%
%AMMACRO31*
4,1,36,0.0,.0085,
.001476,.008371,
.002907,.007987,
.00425,.007361,
.005464,.006511,
.006511,.005464,
.007361,.00425,
.007987,.002907,
.008371,.001476,
.0085,0.0,
.008371,-.001476,
.007987,-.002907,
.007361,-.00425,
.006511,-.005464,
.005464,-.006511,
.00425,-.007361,
.002907,-.007987,
.001476,-.008371,
0.0,-.0085,
-.001476,-.008371,
-.002907,-.007987,
-.00425,-.007361,
-.005464,-.006511,
-.006511,-.005464,
-.007361,-.00425,
-.007987,-.002907,
-.008371,-.001476,
-.0085,0.0,
-.008371,.001476,
-.007987,.002907,
-.007361,.00425,
-.006511,.005464,
-.005464,.006511,
-.00425,.007361,
-.002907,.007987,
-.001476,.008371,
0.0,.0085,
180.*
%
%ADD31MACRO31*%
%AMMACRO49*
4,1,36,0.0,.0185,
-.003212,.018219,
-.006327,.017384,
-.00925,.016021,
-.011892,.014172,
-.014172,.011892,
-.016021,.00925,
-.017384,.006327,
-.018219,.003212,
-.0185,0.0,
-.018219,-.003212,
-.017384,-.006327,
-.016021,-.00925,
-.014172,-.011892,
-.011892,-.014172,
-.00925,-.016021,
-.006327,-.017384,
-.003212,-.018219,
0.0,-.0185,
.003212,-.018219,
.006327,-.017384,
.00925,-.016021,
.011892,-.014172,
.014172,-.011892,
.016021,-.00925,
.017384,-.006327,
.018219,-.003212,
.0185,0.0,
.018219,.003212,
.017384,.006327,
.016021,.00925,
.014172,.011892,
.011892,.014172,
.00925,.016021,
.006327,.017384,
.003212,.018219,
0.0,.0185,
270.*
%
%ADD49MACRO49*%
%AMMACRO21*
4,1,20,-.0075,-.05555,
-.0075,-.06273,
-.013677,-.060878,
-.019439,-.057981,
-.024611,-.054127,
-.029034,-.049434,
-.032576,-.044045,
-.035127,-.038122,
-.036612,-.031846,
-.037,-.0265,
-.037,-.0075,
-.03,-.0075,
-.03,-.0265,
-.029544,-.03171,
-.028191,-.036762,
-.02598,-.041502,
-.022981,-.045786,
-.019282,-.049484,
-.014998,-.052484,
-.010258,-.054694,
-.0075,-.05555,
90.*
4,1,20,.0075,-.06273,
.0075,-.05555,
.01243,-.053806,
.016983,-.051232,
.02102,-.047906,
.024418,-.043931,
.027073,-.039425,
.028906,-.034527,
.029861,-.029385,
.03,-.0265,
.03,-.0075,
.037,-.0075,
.037,-.0265,
.036438,-.032925,
.034769,-.039154,
.032043,-.044999,
.028344,-.050282,
.023784,-.054842,
.018501,-.058541,
.012656,-.061266,
.0075,-.06273,
90.*
4,1,20,-.0075,.06273,
-.0075,.05555,
-.01243,.053806,
-.016983,.051232,
-.02102,.047906,
-.024418,.043931,
-.027073,.039425,
-.028906,.034527,
-.029861,.029385,
-.03,.0265,
-.03,.0075,
-.037,.0075,
-.037,.0265,
-.036438,.032925,
-.034769,.039154,
-.032043,.044999,
-.028344,.050282,
-.023784,.054842,
-.018501,.058541,
-.012656,.061266,
-.0075,.06273,
90.*
4,1,20,.0075,.05555,
.0075,.06273,
.013677,.060878,
.019439,.057981,
.024611,.054127,
.029034,.049434,
.032576,.044045,
.035127,.038122,
.036612,.031846,
.037,.0265,
.037,.0075,
.03,.0075,
.03,.0265,
.029544,.03171,
.028191,.036762,
.02598,.041502,
.022981,.045786,
.019282,.049484,
.014998,.052484,
.010258,.054694,
.0075,.05555,
90.*
%
%ADD21MACRO21*%
%AMMACRO16*
4,1,36,.0025,0.0,
.002462,.000434,
.002349,.000855,
.002165,.00125,
.001915,.001607,
.001607,.001915,
.00125,.002165,
.000855,.002349,
.000434,.002462,
0.0,.0025,
-.000434,.002462,
-.000855,.002349,
-.00125,.002165,
-.001607,.001915,
-.001915,.001607,
-.002165,.00125,
-.002349,.000855,
-.002462,.000434,
-.0025,0.0,
-.002462,-.000434,
-.002349,-.000855,
-.002165,-.00125,
-.001915,-.001607,
-.001607,-.001915,
-.00125,-.002165,
-.000855,-.002349,
-.000434,-.002462,
0.0,-.0025,
.000434,-.002462,
.000855,-.002349,
.00125,-.002165,
.001607,-.001915,
.001915,-.001607,
.002165,-.00125,
.002349,-.000855,
.002462,-.000434,
.0025,0.0,
90.*
%
%ADD16MACRO16*%
%AMMACRO35*
4,1,36,.003,0.0,
.002954,.000521,
.002819,.001026,
.002598,.0015,
.002298,.001928,
.001928,.002298,
.0015,.002598,
.001026,.002819,
.000521,.002954,
0.0,.003,
-.000521,.002954,
-.001026,.002819,
-.0015,.002598,
-.001928,.002298,
-.002298,.001928,
-.002598,.0015,
-.002819,.001026,
-.002954,.000521,
-.003,0.0,
-.002954,-.000521,
-.002819,-.001026,
-.002598,-.0015,
-.002298,-.001928,
-.001928,-.002298,
-.0015,-.002598,
-.001026,-.002819,
-.000521,-.002954,
0.0,-.003,
.000521,-.002954,
.001026,-.002819,
.0015,-.002598,
.001928,-.002298,
.002298,-.001928,
.002598,-.0015,
.002819,-.001026,
.002954,-.000521,
.003,0.0,
90.*
%
%ADD35MACRO35*%
%AMMACRO12*
4,1,36,.0025,0.0,
.002462,.000434,
.002349,.000855,
.002165,.00125,
.001915,.001607,
.001607,.001915,
.00125,.002165,
.000855,.002349,
.000434,.002462,
0.0,.0025,
-.000434,.002462,
-.000855,.002349,
-.00125,.002165,
-.001607,.001915,
-.001915,.001607,
-.002165,.00125,
-.002349,.000855,
-.002462,.000434,
-.0025,0.0,
-.002462,-.000434,
-.002349,-.000855,
-.002165,-.00125,
-.001915,-.001607,
-.001607,-.001915,
-.00125,-.002165,
-.000855,-.002349,
-.000434,-.002462,
0.0,-.0025,
.000434,-.002462,
.000855,-.002349,
.00125,-.002165,
.001607,-.001915,
.001915,-.001607,
.002165,-.00125,
.002349,-.000855,
.002462,-.000434,
.0025,0.0,
0.0*
%
%ADD12MACRO12*%
%AMMACRO52*
4,1,36,-.0025,0.0,
-.002462,.000434,
-.002349,.000855,
-.002165,.00125,
-.001915,.001607,
-.001607,.001915,
-.00125,.002165,
-.000855,.002349,
-.000434,.002462,
0.0,.0025,
.000434,.002462,
.000855,.002349,
.00125,.002165,
.001607,.001915,
.001915,.001607,
.002165,.00125,
.002349,.000855,
.002462,.000434,
.0025,0.0,
.002462,-.000434,
.002349,-.000855,
.002165,-.00125,
.001915,-.001607,
.001607,-.001915,
.00125,-.002165,
.000855,-.002349,
.000434,-.002462,
0.0,-.0025,
-.000434,-.002462,
-.000855,-.002349,
-.00125,-.002165,
-.001607,-.001915,
-.001915,-.001607,
-.002165,-.00125,
-.002349,-.000855,
-.002462,-.000434,
-.0025,0.0,
0.0*
%
%ADD52MACRO52*%
%AMMACRO27*
4,1,36,.003,0.0,
.002954,.000521,
.002819,.001026,
.002598,.0015,
.002298,.001928,
.001928,.002298,
.0015,.002598,
.001026,.002819,
.000521,.002954,
0.0,.003,
-.000521,.002954,
-.001026,.002819,
-.0015,.002598,
-.001928,.002298,
-.002298,.001928,
-.002598,.0015,
-.002819,.001026,
-.002954,.000521,
-.003,0.0,
-.002954,-.000521,
-.002819,-.001026,
-.002598,-.0015,
-.002298,-.001928,
-.001928,-.002298,
-.0015,-.002598,
-.001026,-.002819,
-.000521,-.002954,
0.0,-.003,
.000521,-.002954,
.001026,-.002819,
.0015,-.002598,
.001928,-.002298,
.002298,-.001928,
.002598,-.0015,
.002819,-.001026,
.002954,-.000521,
.003,0.0,
0.0*
%
%ADD27MACRO27*%
%AMMACRO24*
4,1,36,-.003,0.0,
-.002954,.000521,
-.002819,.001026,
-.002598,.0015,
-.002298,.001928,
-.001928,.002298,
-.0015,.002598,
-.001026,.002819,
-.000521,.002954,
0.0,.003,
.000521,.002954,
.001026,.002819,
.0015,.002598,
.001928,.002298,
.002298,.001928,
.002598,.0015,
.002819,.001026,
.002954,.000521,
.003,0.0,
.002954,-.000521,
.002819,-.001026,
.002598,-.0015,
.002298,-.001928,
.001928,-.002298,
.0015,-.002598,
.001026,-.002819,
.000521,-.002954,
0.0,-.003,
-.000521,-.002954,
-.001026,-.002819,
-.0015,-.002598,
-.001928,-.002298,
-.002298,-.001928,
-.002598,-.0015,
-.002819,-.001026,
-.002954,-.000521,
-.003,0.0,
0.0*
%
%ADD24MACRO24*%
%AMMACRO40*
4,1,16,.02584,.01524,
.028094,.010521,
.029494,.005483,
.029998,.000278,
.029591,-.004935,
.028284,-.009999,
.026118,-.014758,
.02584,-.01524,
.03092,-.02032,
.033979,-.014642,
.036005,-.008519,
.036938,-.002138,
.036748,.004309,
.035441,.010625,
.033058,.016618,
.03092,.02032,
.02584,.01524,
180.*
4,1,16,.01524,-.02584,
.010521,-.028094,
.005483,-.029494,
.000278,-.029998,
-.004935,-.029591,
-.009999,-.028284,
-.014758,-.026118,
-.01524,-.02584,
-.02032,-.03092,
-.014642,-.033979,
-.008519,-.036005,
-.002138,-.036938,
.004309,-.036748,
.010625,-.035441,
.016618,-.033058,
.02032,-.03092,
.01524,-.02584,
180.*
4,1,16,-.02584,-.01524,
-.028094,-.010521,
-.029494,-.005483,
-.029998,-.000278,
-.029591,.004935,
-.028284,.009999,
-.026118,.014758,
-.02584,.01524,
-.03092,.02032,
-.033979,.014642,
-.036005,.008519,
-.036938,.002138,
-.036748,-.004309,
-.035441,-.010625,
-.033058,-.016618,
-.03092,-.02032,
-.02584,-.01524,
180.*
4,1,16,-.01524,.02584,
-.010521,.028094,
-.005483,.029494,
-.000278,.029998,
.004935,.029591,
.009999,.028284,
.014758,.026118,
.01524,.02584,
.02032,.03092,
.014642,.033979,
.008519,.036005,
.002138,.036938,
-.004309,.036748,
-.010625,.035441,
-.016618,.033058,
-.02032,.03092,
-.01524,.02584,
180.*
%
%ADD40MACRO40*%
%AMMACRO56*
4,1,15,.03682,.01914,
.039584,.012455,
.041146,.005393,
.041457,-.001834,
.040509,-.009005,
.03833,-.015903,
.03682,-.01914,
.04197,-.0243,
.045552,-.016643,
.04775,-.00848,
.048497,-.000059,
.047771,.008363,
.045593,.016531,
.042029,.024197,
.04197,.0243,
.03682,.01914,
270.*
4,1,15,.01914,-.03682,
.012455,-.039584,
.005393,-.041146,
-.001834,-.041457,
-.009005,-.040509,
-.015903,-.03833,
-.01914,-.03682,
-.0243,-.04197,
-.016643,-.045552,
-.00848,-.04775,
-.000059,-.048497,
.008363,-.047771,
.016531,-.045593,
.024197,-.042029,
.0243,-.04197,
.01914,-.03682,
270.*
4,1,15,-.03682,-.01914,
-.039584,-.012455,
-.041146,-.005393,
-.041457,.001834,
-.040509,.009005,
-.03833,.015903,
-.03682,.01914,
-.04197,.0243,
-.045552,.016643,
-.04775,.00848,
-.048497,.000059,
-.047771,-.008363,
-.045593,-.016531,
-.042029,-.024197,
-.04197,-.0243,
-.03682,-.01914,
270.*
4,1,15,-.01914,.03682,
-.012455,.039584,
-.005393,.041146,
.001834,.041457,
.009005,.040509,
.015903,.03833,
.01914,.03682,
.0243,.04197,
.016643,.045552,
.00848,.04775,
.000059,.048497,
-.008363,.047771,
-.016531,.045593,
-.024197,.042029,
-.0243,.04197,
-.01914,.03682,
270.*
%
%ADD56MACRO56*%
%AMMACRO57*
4,1,15,-.03682,.01914,
-.039584,.012455,
-.041146,.005393,
-.041457,-.001834,
-.040509,-.009005,
-.03833,-.015903,
-.03682,-.01914,
-.04197,-.0243,
-.045552,-.016643,
-.04775,-.00848,
-.048497,-.000059,
-.047771,.008363,
-.045593,.016531,
-.042029,.024197,
-.04197,.0243,
-.03682,.01914,
270.*
4,1,15,-.01914,-.03682,
-.012455,-.039584,
-.005393,-.041146,
.001834,-.041457,
.009005,-.040509,
.015903,-.03833,
.01914,-.03682,
.0243,-.04197,
.016643,-.045552,
.00848,-.04775,
.000059,-.048497,
-.008363,-.047771,
-.016531,-.045593,
-.024197,-.042029,
-.0243,-.04197,
-.01914,-.03682,
270.*
4,1,15,.03682,-.01914,
.039584,-.012455,
.041146,-.005393,
.041457,.001834,
.040509,.009005,
.03833,.015903,
.03682,.01914,
.04197,.0243,
.045552,.016643,
.04775,.00848,
.048497,.000059,
.047771,-.008363,
.045593,-.016531,
.042029,-.024197,
.04197,-.0243,
.03682,-.01914,
270.*
4,1,15,.01914,.03682,
.012455,.039584,
.005393,.041146,
-.001834,.041457,
-.009005,.040509,
-.015903,.03833,
-.01914,.03682,
-.0243,.04197,
-.016643,.045552,
-.00848,.04775,
-.000059,.048497,
.008363,.047771,
.016531,.045593,
.024197,.042029,
.0243,.04197,
.01914,.03682,
270.*
%
%ADD57MACRO57*%
%ADD64C,.006*%
%ADD76C,.03006*%
%ADD80C,.07005*%
%ADD73C,.08404*%
%ADD66C,.07306*%
%ADD79C,.09208*%
%ADD74C,.07606*%
%ADD72C,.08408*%
%ADD78C,.07608*%
%ADD71C,.08409*%
%ADD70O,.1621X.2251*%
%ADD69O,.03604X.07004*%
%ADD67O,.03006X.06406*%
%ADD81C,.16206*%
%ADD68O,.03606X.07006*%
%ADD77C,.17406*%
%ADD65C,.16506*%
%ADD75C,.21786*%
G75*
%LPD*%
G75*
G36*
G01X-1490433Y-1677216D02*
X4496476D01*
Y3837819D01*
X-1490433D01*
Y-1677216D01*
G37*
%LPC*%
G75*
G36*
G01X1725453Y40717D02*
X1733327D01*
G02X1739201Y34843I0J-5874D01*
G01Y0D01*
G03X1749075Y-9874I9874J0D01*
G01X1833071D01*
G02X1838945Y-15748I0J-5874D01*
G01Y-95109D01*
G02X1833071Y-100983I-5874J0D01*
G01X630370D01*
G02X624496Y-95109I0J5874D01*
G01Y-32983D01*
G03X614622Y-23109I-9874J0D01*
G01X68874D01*
G03X59000Y-32983I0J-9874D01*
G01Y-95109D01*
G02X53126Y-100983I-5874J0D01*
G01X7874D01*
G02X2000Y-95109I0J5874D01*
G01Y-15748D01*
G02X7874Y-9874I5874J0D01*
G01X31358D01*
G03X41232Y0I0J9874D01*
G01Y34843D01*
G02X47106Y40717I5874J0D01*
G01X54980D01*
G02X60854Y34843I0J-5874D01*
G01Y0D01*
G03X70728Y-9874I9874J0D01*
G01X133720D01*
G03X143594Y0I0J9874D01*
G01Y34843D01*
G02X149468Y40717I5874J0D01*
G01X157343D01*
G02X163217Y34843I0J-5874D01*
G01Y0D01*
G03X173091Y-9874I9874J0D01*
G01X236083D01*
G03X245957Y0I0J9874D01*
G01Y34843D01*
G02X251831Y40717I5874J0D01*
G01X259705D01*
G02X265579Y34843I0J-5874D01*
G01Y0D01*
G03X275453Y-9874I9874J0D01*
G01X338445D01*
G03X348319Y0I0J9874D01*
G01Y34843D01*
G02X354193Y40717I5874J0D01*
G01X362067D01*
G02X367941Y34843I0J-5874D01*
G01Y0D01*
G03X377815Y-9874I9874J0D01*
G01X488445D01*
G03X498319Y0I0J9874D01*
G01Y34843D01*
G02X504193Y40717I5874J0D01*
G01X512067D01*
G02X517941Y34843I0J-5874D01*
G01Y0D01*
G03X527815Y-9874I9874J0D01*
G01X590807D01*
G03X600681Y0I0J9874D01*
G01Y34843D01*
G02X606555Y40717I5874J0D01*
G01X614429D01*
G02X620303Y34843I0J-5874D01*
G01Y0D01*
G03X630177Y-9874I9874J0D01*
G01X693169D01*
G03X703043Y0I0J9874D01*
G01Y34843D01*
G02X708917Y40717I5874J0D01*
G01X716791D01*
G02X722665Y34843I0J-5874D01*
G01Y0D01*
G03X732539Y-9874I9874J0D01*
G01X795531D01*
G03X805405Y0I0J9874D01*
G01Y34843D01*
G02X811279Y40717I5874J0D01*
G01X819154D01*
G02X825028Y34843I0J-5874D01*
G01Y0D01*
G03X834902Y-9874I9874J0D01*
G01X945531D01*
G03X955405Y0I0J9874D01*
G01Y34843D01*
G02X961279Y40717I5874J0D01*
G01X969154D01*
G02X975028Y34843I0J-5874D01*
G01Y0D01*
G03X984902Y-9874I9874J0D01*
G01X1047894D01*
G03X1057768Y0I0J9874D01*
G01Y34843D01*
G02X1063642Y40717I5874J0D01*
G01X1071516D01*
G02X1077390Y34843I0J-5874D01*
G01Y0D01*
G03X1087264Y-9874I9874J0D01*
G01X1150256D01*
G03X1160130Y0I0J9874D01*
G01Y34843D01*
G02X1166004Y40717I5874J0D01*
G01X1173878D01*
G02X1179752Y34843I0J-5874D01*
G01Y0D01*
G03X1189626Y-9874I9874J0D01*
G01X1252618D01*
G03X1262492Y0I0J9874D01*
G01Y34843D01*
G02X1268366Y40717I5874J0D01*
G01X1276240D01*
G02X1282114Y34843I0J-5874D01*
G01Y0D01*
G03X1291988Y-9874I9874J0D01*
G01X1402618D01*
G03X1412492Y0I0J9874D01*
G01Y34843D01*
G02X1418366Y40717I5874J0D01*
G01X1426240D01*
G02X1432114Y34843I0J-5874D01*
G01Y0D01*
G03X1441988Y-9874I9874J0D01*
G01X1504980D01*
G03X1514854Y0I0J9874D01*
G01Y34843D01*
G02X1520728Y40717I5874J0D01*
G01X1528602D01*
G02X1534476Y34843I0J-5874D01*
G01Y0D01*
G03X1544350Y-9874I9874J0D01*
G01X1607343D01*
G03X1617217Y0I0J9874D01*
G01Y34843D01*
G02X1623091Y40717I5874J0D01*
G01X1630965D01*
G02X1636839Y34843I0J-5874D01*
G01Y0D01*
G03X1646713Y-9874I9874J0D01*
G01X1709705D01*
G03X1719579Y0I0J9874D01*
G01Y34843D01*
G02X1725453Y40717I5874J0D01*
G37*
G36*
G01X1838945Y1528497D02*
Y970427D01*
G02X1838260Y967674I-5874J0D01*
G02X1837222Y966276I-5247J2812D01*
G01X1826874Y955928D01*
G03X1823980Y948943I6985J-6986D01*
G01Y344836D01*
G03X1826874Y337852I9877J1D01*
G01X1837222Y327503D01*
G02X1838941Y323354I-4150J-4150D01*
G01Y7874D01*
G02X1833071Y2004I-5870J0D01*
G01X1756949D01*
G02X1751079Y7874I0J5870D01*
G01Y46654D01*
G03X1745138Y52595I-5941J0D01*
G01X1713642D01*
G03X1707701Y46654I0J-5941D01*
G01Y7874D01*
G02X1701831Y2004I-5870J0D01*
G01X1654587D01*
G02X1648717Y7874I0J5870D01*
G01Y46654D01*
G03X1642776Y52595I-5941J0D01*
G01X1611280D01*
G03X1605339Y46654I0J-5941D01*
G01Y7874D01*
G02X1599469Y2004I-5870J0D01*
G01X1552224D01*
G02X1546354Y7874I0J5870D01*
G01Y46654D01*
G03X1540413Y52595I-5941J0D01*
G01X1508917D01*
G03X1502976Y46654I0J-5941D01*
G01Y7874D01*
G02X1497106Y2004I-5870J0D01*
G01X1449862D01*
G02X1443992Y7874I0J5870D01*
G01Y46654D01*
G03X1438051Y52595I-5941J0D01*
G01X1406555D01*
G03X1400614Y46654I0J-5941D01*
G01Y7874D01*
G02X1394744Y2004I-5870J0D01*
G01X1299862D01*
G02X1293992Y7874I0J5870D01*
G01Y46654D01*
G03X1288051Y52595I-5941J0D01*
G01X1256555D01*
G03X1250614Y46654I0J-5941D01*
G01Y7874D01*
G02X1244744Y2004I-5870J0D01*
G01X1197500D01*
G02X1191630Y7874I0J5870D01*
G01Y46654D01*
G03X1185689Y52595I-5941J0D01*
G01X1154193D01*
G03X1148252Y46654I0J-5941D01*
G01Y7874D01*
G02X1142382Y2004I-5870J0D01*
G01X1095138D01*
G02X1089268Y7874I0J5870D01*
G01Y46654D01*
G03X1083327Y52595I-5941J0D01*
G01X1051831D01*
G03X1045890Y46654I0J-5941D01*
G01Y7874D01*
G02X1040020Y2004I-5870J0D01*
G01X992776D01*
G02X986906Y7874I0J5870D01*
G01Y46654D01*
G03X980965Y52595I-5941J0D01*
G01X949468D01*
G03X943527Y46654I0J-5942D01*
G01Y7874D01*
G02X937657Y2004I-5870J0D01*
G01X842776D01*
G02X836906Y7874I0J5870D01*
G01Y46654D01*
G03X830965Y52595I-5941J0D01*
G01X799468D01*
G03X793527Y46654I0J-5942D01*
G01Y7874D01*
G02X787657Y2004I-5870J0D01*
G01X740413D01*
G02X734543Y7874I0J5870D01*
G01Y46654D01*
G03X728602Y52595I-5941J0D01*
G01X697106D01*
G03X691165Y46654I0J-5941D01*
G01Y7874D01*
G02X685295Y2004I-5870J0D01*
G01X638051D01*
G02X632181Y7874I0J5870D01*
G01Y46654D01*
G03X626240Y52595I-5941J0D01*
G01X594744D01*
G03X588803Y46654I0J-5941D01*
G01Y7874D01*
G02X582933Y2004I-5870J0D01*
G01X535689D01*
G02X529819Y7874I0J5870D01*
G01Y46654D01*
G03X523878Y52595I-5941J0D01*
G01X492382D01*
G03X486441Y46654I0J-5941D01*
G01Y7874D01*
G02X480571Y2004I-5870J0D01*
G01X385689D01*
G02X379819Y7874I0J5870D01*
G01Y46654D01*
G03X373878Y52595I-5941J0D01*
G01X342382D01*
G03X336441Y46654I0J-5941D01*
G01Y7874D01*
G02X330571Y2004I-5870J0D01*
G01X283327D01*
G02X277457Y7874I0J5870D01*
G01Y46654D01*
G03X271516Y52595I-5941J0D01*
G01X240020D01*
G03X234079Y46654I0J-5941D01*
G01Y7874D01*
G02X228209Y2004I-5870J0D01*
G01X180965D01*
G02X175095Y7874I0J5870D01*
G01Y46654D01*
G03X169154Y52595I-5941J0D01*
G01X137657D01*
G03X131716Y46654I0J-5941D01*
G01Y7874D01*
G02X125846Y2004I-5870J0D01*
G01X78602D01*
G02X72732Y7874I0J5870D01*
G01Y46654D01*
G03X66791Y52595I-5941J0D01*
G01X35295D01*
G03X29354Y46654I0J-5941D01*
G01Y7874D01*
G02X23484Y2004I-5870J0D01*
G01X18462D01*
X18458Y2000D01*
X12364D01*
X12360Y2004D01*
X7874D01*
G02X2004Y7874I0J5870D01*
G01Y323354D01*
G02X3723Y327503I5869J-1D01*
G01X14071Y337852D01*
G03X16965Y344836I-6983J6985D01*
G01Y948943D01*
G03X14071Y955928I-9879J-1D01*
G01X3723Y966276D01*
G02X2004Y970426I4151J4151D01*
G01Y1640118D01*
G02X7874Y1645988I5870J0D01*
G01X26771D01*
X26775Y1645992D01*
X31442D01*
X31446Y1645988D01*
X789296D01*
G02X793646Y1644059I0J-5870D01*
G03X800964Y1640815I7319J6634D01*
G01X1070059D01*
G03X1077377Y1644059I-1J9878D01*
G02X1081727Y1645988I4350J-3941D01*
G01X1833071D01*
G02X1838941Y1640118I0J-5870D01*
G01X1838945Y1528497D01*
G37*
G36*
G01X1833071Y1818880D02*
G02X1838945Y1813006I0J-5874D01*
G01Y1663740D01*
G02X1833071Y1657866I-5874J0D01*
G01X1763543D01*
G02X1757669Y1663740I0J5874D01*
G01Y1689331D01*
G03X1747795Y1699205I-9874J0D01*
G01X1461575D01*
G03X1451701Y1689331I0J-9874D01*
G01Y1663740D01*
G02X1445827Y1657866I-5874J0D01*
G01X1417087D01*
G02X1411213Y1663740I0J5874D01*
G01Y1689331D01*
G03X1401339Y1699205I-9874J0D01*
G01X1115118D01*
G03X1105244Y1689331I0J-9874D01*
G01Y1663740D01*
G02X1099370Y1657866I-5874J0D01*
G01X1090079D01*
G02X1084205Y1663740I0J5874D01*
G01Y1695110D01*
G03X1074331Y1704984I-9874J0D01*
G01X796693D01*
G03X786819Y1695110I0J-9874D01*
G01Y1663740D01*
G02X780945Y1657866I-5874J0D01*
G01X741575D01*
G02X735701Y1663740I0J5874D01*
G01Y1689331D01*
G03X725827Y1699205I-9874J0D01*
G01X439607D01*
G03X429733Y1689331I0J-9874D01*
G01Y1663740D01*
G02X423859Y1657866I-5874J0D01*
G01X395118D01*
G02X389244Y1663740I0J5874D01*
G01Y1689331D01*
G03X379370Y1699205I-9874J0D01*
G01X93150D01*
G03X83276Y1689331I0J-9874D01*
G01Y1663740D01*
G02X77402Y1657866I-5874J0D01*
G01X7874D01*
G02X2000Y1663740I0J5874D01*
G01Y1813006D01*
G02X7874Y1818880I5874J0D01*
G01X1833071D01*
G37*
%LPD*%
G75*
G36*
G01X951820Y-29638D02*
Y-33958D01*
G02X951518Y-34260I-302J0D01*
G01X949108D01*
G02X948806Y-33958I0J302D01*
G01Y-29638D01*
G02X949108Y-29336I302J0D01*
G01X951518D01*
G02X951820Y-29638I0J-302D01*
G37*
G36*
G01X976664Y-68818D02*
Y-73138D01*
G02X976362Y-73440I-302J0D01*
G01X973952D01*
G02X973650Y-73138I0J302D01*
G01Y-68818D01*
G02X973952Y-68516I302J0D01*
G01X976362D01*
G02X976664Y-68818I0J-302D01*
G37*
G36*
G01X723128Y-33986D02*
Y-29666D01*
G02X723430Y-29364I302J0D01*
G01X725840D01*
G02X726142Y-29666I0J-302D01*
G01Y-33986D01*
G02X725840Y-34288I-302J0D01*
G01X723430D01*
G02X723128Y-33986I0J302D01*
G37*
G36*
G01X843128Y-73166D02*
Y-68846D01*
G02X843430Y-68544I302J0D01*
G01X845840D01*
G02X846142Y-68846I0J-302D01*
G01Y-73166D01*
G02X845840Y-73468I-302J0D01*
G01X843430D01*
G02X843128Y-73166I0J302D01*
G37*
G36*
G01X1079340Y-78544D02*
G02X1079466Y-78571I1J-302D01*
G01X1079498Y-78586D01*
X1079568Y-78592D01*
X1079883Y-78507D01*
X1079940Y-78467D01*
X1079960Y-78439D01*
G02X1081187Y-77804I1227J-868D01*
G02X1082690Y-79306I1J-1502D01*
G01Y-82706D01*
G02X1081187Y-84208I-1503J1D01*
G02X1079960Y-83573I0J1503D01*
G01X1079940Y-83545D01*
X1079883Y-83505D01*
X1079568Y-83420D01*
X1079498Y-83426D01*
X1079466Y-83441D01*
G02X1079340Y-83468I-125J275D01*
G01X1076930D01*
G02X1076628Y-83166I0J302D01*
G01Y-78846D01*
G02X1076930Y-78544I302J0D01*
G01X1079340D01*
G37*
G36*
G01X1335840D02*
G02X1335966Y-78571I1J-302D01*
G01X1335998Y-78586D01*
X1336068Y-78592D01*
X1336383Y-78507D01*
X1336440Y-78467D01*
X1336460Y-78439D01*
G02X1337687Y-77804I1227J-868D01*
G02X1339190Y-79306I1J-1502D01*
G01Y-82706D01*
G02X1337687Y-84208I-1503J1D01*
G02X1336460Y-83573I0J1503D01*
G01X1336440Y-83545D01*
X1336383Y-83505D01*
X1336068Y-83420D01*
X1335998Y-83426D01*
X1335966Y-83441D01*
G02X1335840Y-83468I-125J275D01*
G01X1333430D01*
G02X1333128Y-83166I0J302D01*
G01Y-78846D01*
G02X1333430Y-78544I302J0D01*
G01X1335840D01*
G37*
G36*
G01X1590340D02*
G02X1590466Y-78571I1J-302D01*
G01X1590498Y-78586D01*
X1590568Y-78592D01*
X1590883Y-78507D01*
X1590940Y-78467D01*
X1590960Y-78439D01*
G02X1592187Y-77804I1227J-868D01*
G02X1593690Y-79306I1J-1502D01*
G01Y-82706D01*
G02X1592187Y-84208I-1503J1D01*
G02X1590960Y-83573I0J1503D01*
G01X1590940Y-83545D01*
X1590883Y-83505D01*
X1590568Y-83420D01*
X1590498Y-83426D01*
X1590466Y-83441D01*
G02X1590340Y-83468I-125J275D01*
G01X1587930D01*
G02X1587628Y-83166I0J302D01*
G01Y-78846D01*
G02X1587930Y-78544I302J0D01*
G01X1590340D01*
G37*
G36*
G01X1223902Y-82678D02*
Y-79278D01*
G02X1225405Y-77776I1503J-1D01*
G02X1226632Y-78411I0J-1503D01*
G01X1226652Y-78439D01*
X1226709Y-78479D01*
X1227024Y-78564D01*
X1227094Y-78558D01*
X1227126Y-78543D01*
G02X1227252Y-78516I125J-275D01*
G01X1229662D01*
G02X1229964Y-78818I0J-302D01*
G01Y-83138D01*
G02X1229662Y-83440I-302J0D01*
G01X1227252D01*
G02X1227126Y-83413I-1J302D01*
G01X1227094Y-83398D01*
X1227024Y-83392D01*
X1226709Y-83477D01*
X1226652Y-83517D01*
X1226632Y-83545D01*
G02X1225405Y-84180I-1227J868D01*
G02X1223902Y-82678I-1J1502D01*
G37*
G36*
G01X1480402D02*
Y-79278D01*
G02X1481905Y-77776I1503J-1D01*
G02X1483132Y-78411I0J-1503D01*
G01X1483152Y-78439D01*
X1483209Y-78479D01*
X1483524Y-78564D01*
X1483594Y-78558D01*
X1483626Y-78543D01*
G02X1483752Y-78516I125J-275D01*
G01X1486162D01*
G02X1486464Y-78818I0J-302D01*
G01Y-83138D01*
G02X1486162Y-83440I-302J0D01*
G01X1483752D01*
G02X1483626Y-83413I-1J302D01*
G01X1483594Y-83398D01*
X1483524Y-83392D01*
X1483209Y-83477D01*
X1483152Y-83517D01*
X1483132Y-83545D01*
G02X1481905Y-84180I-1227J868D01*
G02X1480402Y-82678I-1J1502D01*
G37*
G36*
G01X1734902D02*
Y-79278D01*
G02X1736405Y-77776I1503J-1D01*
G02X1737632Y-78411I0J-1503D01*
G01X1737652Y-78439D01*
X1737709Y-78479D01*
X1738024Y-78564D01*
X1738094Y-78558D01*
X1738126Y-78543D01*
G02X1738252Y-78516I125J-275D01*
G01X1740662D01*
G02X1740964Y-78818I0J-302D01*
G01Y-83138D01*
G02X1740662Y-83440I-302J0D01*
G01X1738252D01*
G02X1738126Y-83413I-1J302D01*
G01X1738094Y-83398D01*
X1738024Y-83392D01*
X1737709Y-83477D01*
X1737652Y-83517D01*
X1737632Y-83545D01*
G02X1736405Y-84180I-1227J868D01*
G02X1734902Y-82678I-1J1502D01*
G37*
G36*
G01X1800258Y-43888D02*
Y-40488D01*
G02X1801761Y-38986I1503J-1D01*
G02X1802988Y-39621I0J-1503D01*
G01X1803008Y-39649D01*
X1803065Y-39689D01*
X1803380Y-39774D01*
X1803450Y-39768D01*
X1803482Y-39753D01*
G02X1803608Y-39726I125J-275D01*
G01X1806018D01*
G02X1806320Y-40028I0J-302D01*
G01Y-44348D01*
G02X1806018Y-44650I-302J0D01*
G01X1803608D01*
G02X1803482Y-44623I-1J302D01*
G01X1803450Y-44608D01*
X1803380Y-44602D01*
X1803065Y-44687D01*
X1803008Y-44727D01*
X1802988Y-44755D01*
G02X1801761Y-45390I-1227J868D01*
G02X1800258Y-43888I-1J1502D01*
G37*
G36*
G01X1580340Y-39624D02*
G02X1580466Y-39651I1J-302D01*
G01X1580498Y-39666D01*
X1580568Y-39672D01*
X1580883Y-39587D01*
X1580940Y-39547D01*
X1580960Y-39519D01*
G02X1582187Y-38884I1227J-868D01*
G02X1583690Y-40386I1J-1502D01*
G01Y-43786D01*
G02X1582187Y-45288I-1503J1D01*
G02X1580960Y-44653I0J1503D01*
G01X1580940Y-44625D01*
X1580883Y-44585D01*
X1580568Y-44500D01*
X1580498Y-44506D01*
X1580466Y-44521D01*
G02X1580340Y-44548I-125J275D01*
G01X1577930D01*
G02X1577628Y-44246I0J302D01*
G01Y-39926D01*
G02X1577930Y-39624I302J0D01*
G01X1580340D01*
G37*
G36*
G01X1515758Y-43758D02*
Y-40358D01*
G02X1517261Y-38856I1503J-1D01*
G02X1518488Y-39491I0J-1503D01*
G01X1518508Y-39519D01*
X1518565Y-39559D01*
X1518880Y-39644D01*
X1518950Y-39638D01*
X1518982Y-39623D01*
G02X1519108Y-39596I125J-275D01*
G01X1521518D01*
G02X1521820Y-39898I0J-302D01*
G01Y-44218D01*
G02X1521518Y-44520I-302J0D01*
G01X1519108D01*
G02X1518982Y-44493I-1J302D01*
G01X1518950Y-44478D01*
X1518880Y-44472D01*
X1518565Y-44557D01*
X1518508Y-44597D01*
X1518488Y-44625D01*
G02X1517261Y-45260I-1227J868D01*
G02X1515758Y-43758I-1J1502D01*
G37*
G36*
G01X1295840Y-39494D02*
G02X1295966Y-39521I1J-302D01*
G01X1295998Y-39536D01*
X1296068Y-39542D01*
X1296383Y-39457D01*
X1296440Y-39417D01*
X1296460Y-39389D01*
G02X1297687Y-38754I1227J-868D01*
G02X1299190Y-40256I1J-1502D01*
G01Y-43656D01*
G02X1297687Y-45158I-1503J1D01*
G02X1296460Y-44523I0J1503D01*
G01X1296440Y-44495D01*
X1296383Y-44455D01*
X1296068Y-44370D01*
X1295998Y-44376D01*
X1295966Y-44391D01*
G02X1295840Y-44418I-125J275D01*
G01X1293430D01*
G02X1293128Y-44116I0J302D01*
G01Y-39796D01*
G02X1293430Y-39494I302J0D01*
G01X1295840D01*
G37*
G36*
G01X1229258Y-43628D02*
Y-40228D01*
G02X1230761Y-38726I1503J-1D01*
G02X1231988Y-39361I0J-1503D01*
G01X1232008Y-39389D01*
X1232065Y-39429D01*
X1232380Y-39514D01*
X1232450Y-39508D01*
X1232482Y-39493D01*
G02X1232608Y-39466I125J-275D01*
G01X1235018D01*
G02X1235320Y-39768I0J-302D01*
G01Y-44088D01*
G02X1235018Y-44390I-302J0D01*
G01X1232608D01*
G02X1232482Y-44363I-1J302D01*
G01X1232450Y-44348D01*
X1232380Y-44342D01*
X1232065Y-44427D01*
X1232008Y-44467D01*
X1231988Y-44495D01*
G02X1230761Y-45130I-1227J868D01*
G02X1229258Y-43628I-1J1502D01*
G37*
G36*
G01X1009340Y-39364D02*
G02X1009466Y-39391I1J-302D01*
G01X1009498Y-39406D01*
X1009568Y-39412D01*
X1009883Y-39327D01*
X1009940Y-39287D01*
X1009960Y-39259D01*
G02X1011187Y-38624I1227J-868D01*
G02X1012690Y-40126I1J-1502D01*
G01Y-43526D01*
G02X1011187Y-45028I-1503J1D01*
G02X1009960Y-44393I0J1503D01*
G01X1009940Y-44365D01*
X1009883Y-44325D01*
X1009568Y-44240D01*
X1009498Y-44246D01*
X1009466Y-44261D01*
G02X1009340Y-44288I-125J275D01*
G01X1006930D01*
G02X1006628Y-43986I0J302D01*
G01Y-39666D01*
G02X1006930Y-39364I302J0D01*
G01X1009340D01*
G37*
G36*
G01X607977Y1552080D02*
X555513D01*
G02X555210Y1552383I0J303D01*
G01Y1643194D01*
G02X555513Y1643498I303J1D01*
G01X608266D01*
G02X608570Y1643194I0J-304D01*
G01Y1552672D01*
X607977Y1552080D01*
G37*
G36*
G01X208954Y1643834D02*
G02X209256Y1644136I302J0D01*
G01X261611D01*
G02X261912Y1643834I-1J-302D01*
G01Y1642872D01*
Y1552470D01*
X261722Y1552280D01*
X208952D01*
Y1642872D01*
X208954D01*
Y1643834D01*
G37*
G36*
G01X1232576D02*
G02X1232878Y1644136I302J0D01*
G01X1285233D01*
G02X1285534Y1643834I-1J-302D01*
G01Y1643226D01*
Y1552461D01*
X1285353Y1552280D01*
X1232574D01*
Y1643226D01*
X1232576D01*
Y1643834D01*
G37*
G36*
G01X1579032D02*
G02X1579335Y1644136I303J-1D01*
G01X1631688D01*
G02X1631990Y1643834I0J-302D01*
G01Y1643174D01*
X1631992D01*
Y1552573D01*
X1631698Y1552280D01*
X1579032D01*
Y1643174D01*
Y1643834D01*
G37*
G36*
G01X177763Y1512216D02*
X180583D01*
G02X180786Y1512014I1J-202D01*
G01Y1511392D01*
G03X180836Y1511260I200J0D01*
G02Y1508348I-1664J-1456D01*
G03X180786Y1508216I150J-132D01*
G01Y1506273D01*
G03X180836Y1506141I200J0D01*
G02Y1503229I-1664J-1456D01*
G03X180786Y1503097I150J-132D01*
G01Y1502476D01*
G02X180583Y1502274I-203J1D01*
G01X177763D01*
G02X177560Y1502476I-1J202D01*
G01Y1503097D01*
G03X177510Y1503229I-200J0D01*
G02Y1506141I1664J1456D01*
G03X177560Y1506273I-150J132D01*
G01Y1508216D01*
G03X177510Y1508348I-200J0D01*
G02Y1511260I1664J1456D01*
G03X177560Y1511392I-150J132D01*
G01Y1512014D01*
G02X177763Y1512216I203J-1D01*
G37*
G36*
G01X350991D02*
X353811D01*
G02X354014Y1512014I1J-202D01*
G01Y1511392D01*
G03X354064Y1511260I200J0D01*
G02Y1508348I-1664J-1456D01*
G03X354014Y1508216I150J-132D01*
G01Y1506273D01*
G03X354064Y1506141I200J0D01*
G02Y1503229I-1664J-1456D01*
G03X354014Y1503097I150J-132D01*
G01Y1502476D01*
G02X353811Y1502274I-203J1D01*
G01X350991D01*
G02X350788Y1502476I-1J202D01*
G01Y1503097D01*
G03X350738Y1503229I-200J0D01*
G02Y1506141I1664J1456D01*
G03X350788Y1506273I-150J132D01*
G01Y1508216D01*
G03X350738Y1508348I-200J0D01*
G02Y1511260I1664J1456D01*
G03X350788Y1511392I-150J132D01*
G01Y1512014D01*
G02X350991Y1512216I203J-1D01*
G37*
G36*
G01X186425Y1516546D02*
X189245D01*
G02X189448Y1516344I1J-202D01*
G01Y1515722D01*
G03X189498Y1515590I200J0D01*
G02Y1512678I-1664J-1456D01*
G03X189448Y1512546I150J-132D01*
G01Y1510604D01*
G03X189498Y1510472I200J0D01*
G02Y1507560I-1664J-1456D01*
G03X189448Y1507428I150J-132D01*
G01Y1506806D01*
G02X189245Y1506604I-203J1D01*
G01X186425D01*
G02X186222Y1506806I-1J202D01*
G01Y1507428D01*
G03X186172Y1507560I-200J0D01*
G02Y1510472I1664J1456D01*
G03X186222Y1510604I-150J132D01*
G01Y1512546D01*
G03X186172Y1512678I-200J0D01*
G02Y1515590I1664J1456D01*
G03X186222Y1515722I-150J132D01*
G01Y1516344D01*
G02X186425Y1516546I203J-1D01*
G37*
G36*
G01X359653D02*
X362473D01*
G02X362676Y1516344I1J-202D01*
G01Y1515722D01*
G03X362726Y1515590I200J0D01*
G02Y1512678I-1664J-1456D01*
G03X362676Y1512546I150J-132D01*
G01Y1510604D01*
G03X362726Y1510472I200J0D01*
G02Y1507560I-1664J-1456D01*
G03X362676Y1507428I150J-132D01*
G01Y1506806D01*
G02X362473Y1506604I-203J1D01*
G01X359653D01*
G02X359450Y1506806I-1J202D01*
G01Y1507428D01*
G03X359400Y1507560I-200J0D01*
G02Y1510472I1664J1456D01*
G03X359450Y1510604I-150J132D01*
G01Y1512546D01*
G03X359400Y1512678I-200J0D01*
G02Y1515590I1664J1456D01*
G03X359450Y1515722I-150J132D01*
G01Y1516344D01*
G02X359653Y1516546I203J-1D01*
G37*
G36*
G01X177763Y1568516D02*
X180583D01*
G02X180786Y1568313I0J-203D01*
G01Y1567691D01*
G03X180836Y1567559I200J0D01*
G02Y1564647I-1664J-1456D01*
G03X180786Y1564515I150J-132D01*
G01Y1562573D01*
G03X180836Y1562441I200J0D01*
G02Y1559529I-1664J-1456D01*
G03X180786Y1559397I150J-132D01*
G01Y1558775D01*
G02X180583Y1558572I-203J0D01*
G01X177763D01*
G02X177560Y1558775I0J203D01*
G01Y1559397D01*
G03X177510Y1559529I-200J0D01*
G02Y1562441I1664J1456D01*
G03X177560Y1562573I-150J132D01*
G01Y1564515D01*
G03X177510Y1564647I-200J0D01*
G02Y1567559I1664J1456D01*
G03X177560Y1567691I-150J132D01*
G01Y1568313D01*
G02X177763Y1568516I203J0D01*
G37*
G36*
G01X350991D02*
X353811D01*
G02X354014Y1568313I0J-203D01*
G01Y1567691D01*
G03X354064Y1567559I200J0D01*
G02Y1564647I-1664J-1456D01*
G03X354014Y1564515I150J-132D01*
G01Y1562573D01*
G03X354064Y1562441I200J0D01*
G02Y1559529I-1664J-1456D01*
G03X354014Y1559397I150J-132D01*
G01Y1558775D01*
G02X353811Y1558572I-203J0D01*
G01X350991D01*
G02X350788Y1558775I0J203D01*
G01Y1559397D01*
G03X350738Y1559529I-200J0D01*
G02Y1562441I1664J1456D01*
G03X350788Y1562573I-150J132D01*
G01Y1564515D01*
G03X350738Y1564647I-200J0D01*
G02Y1567559I1664J1456D01*
G03X350788Y1567691I-150J132D01*
G01Y1568313D01*
G02X350991Y1568516I203J0D01*
G37*
G36*
G01X186425Y1572846D02*
X189245D01*
G02X189448Y1572644I1J-202D01*
G01Y1572022D01*
G03X189498Y1571890I200J0D01*
G02Y1568978I-1664J-1456D01*
G03X189448Y1568846I150J-132D01*
G01Y1566903D01*
G03X189498Y1566771I200J0D01*
G02Y1563859I-1664J-1456D01*
G03X189448Y1563727I150J-132D01*
G01Y1563106D01*
G02X189245Y1562904I-203J1D01*
G01X186425D01*
G02X186222Y1563106I-1J202D01*
G01Y1563727D01*
G03X186172Y1563859I-200J0D01*
G02Y1566771I1664J1456D01*
G03X186222Y1566903I-150J132D01*
G01Y1568846D01*
G03X186172Y1568978I-200J0D01*
G02Y1571890I1664J1456D01*
G03X186222Y1572022I-150J132D01*
G01Y1572644D01*
G02X186425Y1572846I203J-1D01*
G37*
G36*
G01X359653D02*
X362473D01*
G02X362676Y1572644I1J-202D01*
G01Y1572022D01*
G03X362726Y1571890I200J0D01*
G02Y1568978I-1664J-1456D01*
G03X362676Y1568846I150J-132D01*
G01Y1566903D01*
G03X362726Y1566771I200J0D01*
G02Y1563859I-1664J-1456D01*
G03X362676Y1563727I150J-132D01*
G01Y1563106D01*
G02X362473Y1562904I-203J1D01*
G01X359653D01*
G02X359450Y1563106I-1J202D01*
G01Y1563727D01*
G03X359400Y1563859I-200J0D01*
G02Y1566771I1664J1456D01*
G03X359450Y1566903I-150J132D01*
G01Y1568846D01*
G03X359400Y1568978I-200J0D01*
G02Y1571890I1664J1456D01*
G03X359450Y1572022I-150J132D01*
G01Y1572644D01*
G02X359653Y1572846I203J-1D01*
G37*
G36*
G01X177763Y1583870D02*
X180583D01*
G02X180786Y1583667I0J-203D01*
G01Y1583045D01*
G03X180836Y1582913I200J0D01*
G02Y1580001I-1664J-1456D01*
G03X180786Y1579869I150J-132D01*
G01Y1577927D01*
G03X180836Y1577795I200J0D01*
G02Y1574883I-1664J-1456D01*
G03X180786Y1574751I150J-132D01*
G01Y1574129D01*
G02X180583Y1573926I-203J0D01*
G01X177763D01*
G02X177560Y1574129I0J203D01*
G01Y1574751D01*
G03X177510Y1574883I-200J0D01*
G02Y1577795I1664J1456D01*
G03X177560Y1577927I-150J132D01*
G01Y1579869D01*
G03X177510Y1580001I-200J0D01*
G02Y1582913I1664J1456D01*
G03X177560Y1583045I-150J132D01*
G01Y1583667D01*
G02X177763Y1583870I203J0D01*
G37*
G36*
G01X956709Y1489429D02*
X1046333D01*
G02X1047217Y1489063I0J-1251D01*
G01X1048852Y1487428D01*
G02X1049218Y1486544I-885J-884D01*
G01Y1451702D01*
G02X1048852Y1450818I-1251J0D01*
G01X1046676Y1448642D01*
G02X1045792Y1448276I-884J885D01*
G01X929991D01*
G02X929107Y1448642I0J1251D01*
G01X927428Y1450321D01*
G02X927062Y1451205I885J884D01*
G01Y1481492D01*
G02X927428Y1482376I1251J0D01*
G01X929075Y1484023D01*
G02X929959Y1484389I884J-885D01*
G01X952618D01*
G03X952760Y1484448I0J200D01*
G01X953133Y1484821D01*
G03X953192Y1484963I-141J142D01*
G01Y1485912D01*
G02X953558Y1486796I1251J0D01*
G01X955825Y1489063D01*
G02X956709Y1489429I884J-885D01*
G37*
G36*
G01X404759Y1350874D02*
X408159D01*
G02Y1347270I0J-1802D01*
G01X404759D01*
G02Y1350874I0J1802D01*
G37*
G36*
G01X402489Y1419078D02*
X405889D01*
G02Y1415472I0J-1803D01*
G01X402489D01*
G02Y1419078I0J1803D01*
G37*
G36*
G01X1443660Y1308896D02*
X1440260D01*
G02Y1312500I0J1802D01*
G01X1443660D01*
G02Y1308896I0J-1802D01*
G37*
G36*
G01X970197Y665850D02*
X966797D01*
G02Y669456I0J1803D01*
G01X970197D01*
G02Y665850I0J-1803D01*
G37*
G36*
G01X501495Y772260D02*
X504895D01*
G02Y768654I0J-1803D01*
G01X501495D01*
G02Y772260I0J1803D01*
G37*
G36*
G01X909508Y623418D02*
X912908D01*
G02Y619814I0J-1802D01*
G01X909508D01*
G02Y623418I0J1802D01*
G37*
G36*
G01X900676Y623338D02*
X904076D01*
G02Y619734I0J-1802D01*
G01X900676D01*
G02Y623338I0J1802D01*
G37*
G36*
G01X526264Y665858D02*
X529664D01*
G02Y662254I0J-1802D01*
G01X526264D01*
G02Y665858I0J1802D01*
G37*
G36*
G01X534264Y663358D02*
X537664D01*
G02Y659754I0J-1802D01*
G01X534264D01*
G02Y663358I0J1802D01*
G37*
G36*
G01X538985Y734790D02*
X535585D01*
G02Y738396I0J1803D01*
G01X538985D01*
G02Y734790I0J-1803D01*
G37*
G36*
G01X530985Y739790D02*
X527585D01*
G02Y743396I0J1803D01*
G01X530985D01*
G02Y739790I0J-1803D01*
G37*
G36*
G01X517731Y742874D02*
X521131D01*
G02Y739268I0J-1803D01*
G01X517731D01*
G02Y742874I0J1803D01*
G37*
G36*
G01X511724Y739232D02*
X508324D01*
G02Y742838I0J1803D01*
G01X511724D01*
G02Y739232I0J-1803D01*
G37*
G36*
G01X415777Y306272D02*
X419177D01*
G02Y302668I0J-1802D01*
G01X415777D01*
G02Y306272I0J1802D01*
G37*
G36*
G01X423651Y309272D02*
X427051D01*
G02Y305668I0J-1802D01*
G01X423651D01*
G02Y309272I0J1802D01*
G37*
G36*
G01X431525Y306272D02*
X434925D01*
G02Y302668I0J-1802D01*
G01X431525D01*
G02Y306272I0J1802D01*
G37*
G36*
G01X434924Y368506D02*
X431524D01*
G02Y372112I0J1803D01*
G01X434924D01*
G02Y368506I0J-1803D01*
G37*
G36*
G01X26772Y1559218D02*
X20472D01*
G02Y1575428I0J8105D01*
G01X26772D01*
G02Y1559218I0J-8105D01*
G37*
G36*
G01X216125Y1441832D02*
X219525D01*
G02Y1438226I0J-1803D01*
G01X216125D01*
G02Y1441832I0J1803D01*
G37*
G36*
G01X413753Y1518690D02*
X417153D01*
G02Y1515084I0J-1803D01*
G01X413753D01*
G02Y1518690I0J1803D01*
G37*
G36*
G01X417334Y1475298D02*
X413934D01*
G02Y1478902I0J1802D01*
G01X417334D01*
G02Y1475298I0J-1802D01*
G37*
G36*
G01X919628Y334530D02*
X916228D01*
G02Y338136I0J1803D01*
G01X919628D01*
G02Y334530I0J-1803D01*
G37*
G36*
G01X905899Y304150D02*
X909299D01*
G02Y300544I0J-1803D01*
G01X905899D01*
G02Y304150I0J1803D01*
G37*
G36*
G01X1033891Y298096D02*
X1037291D01*
G02Y294490I0J-1803D01*
G01X1033891D01*
G02Y298096I0J1803D01*
G37*
G36*
G01X1318363Y312364D02*
X1321763D01*
G02Y308760I0J-1802D01*
G01X1318363D01*
G02Y312364I0J1802D01*
G37*
G36*
G01X1337508Y371598D02*
X1334108D01*
G02Y375204I0J1803D01*
G01X1337508D01*
G02Y371598I0J-1803D01*
G37*
G36*
G01X1326237Y309364D02*
X1329637D01*
G02Y305760I0J-1802D01*
G01X1326237D01*
G02Y309364I0J1802D01*
G37*
G36*
G01X1334111Y312364D02*
X1337511D01*
G02Y308760I0J-1802D01*
G01X1334111D01*
G02Y312364I0J1802D01*
G37*
G36*
G01X1518207Y1176748D02*
X1514467D01*
G02Y1179354I0J1303D01*
G01X1518207D01*
G02Y1176748I0J-1303D01*
G37*
G36*
G01Y1169268D02*
X1514467D01*
G02Y1171872I0J1302D01*
G01X1518207D01*
G02Y1169268I0J-1302D01*
G37*
G36*
G01X1513926Y907148D02*
X1510526D01*
G02Y910754I0J1803D01*
G01X1513926D01*
G02Y907148I0J-1803D01*
G37*
G36*
G01X1531299Y1174878D02*
X1527559D01*
G02Y1177482I0J1302D01*
G01X1531299D01*
G02Y1174878I0J-1302D01*
G37*
G36*
G01X146947Y1176748D02*
X143207D01*
G02Y1179354I0J1303D01*
G01X146947D01*
G02Y1176748I0J-1303D01*
G37*
G36*
G01Y1169268D02*
X143207D01*
G02Y1171872I0J1302D01*
G01X146947D01*
G02Y1169268I0J-1302D01*
G37*
G36*
G01X160039Y1174878D02*
X156299D01*
G02Y1177482I0J1302D01*
G01X160039D01*
G02Y1174878I0J-1302D01*
G37*
G36*
G01X604034Y1176748D02*
X600294D01*
G02Y1179354I0J1303D01*
G01X604034D01*
G02Y1176748I0J-1303D01*
G37*
G36*
G01Y1169268D02*
X600294D01*
G02Y1171872I0J1302D01*
G01X604034D01*
G02Y1169268I0J-1302D01*
G37*
G36*
G01X605733Y942940D02*
X609133D01*
G02Y939336I0J-1802D01*
G01X605733D01*
G02Y942940I0J1802D01*
G37*
G36*
G01X615256Y1176748D02*
X611516D01*
G02Y1179354I0J1303D01*
G01X615256D01*
G02Y1176748I0J-1303D01*
G37*
G36*
G01X1061120D02*
X1057380D01*
G02Y1179354I0J1303D01*
G01X1061120D01*
G02Y1176748I0J-1303D01*
G37*
G36*
G01Y1169268D02*
X1057380D01*
G02Y1171872I0J1302D01*
G01X1061120D01*
G02Y1169268I0J-1302D01*
G37*
G36*
G01X1769063Y921922D02*
X1765663D01*
G02Y925526I0J1802D01*
G01X1769063D01*
G02Y921922I0J-1802D01*
G37*
G36*
G01X1072342Y1176748D02*
X1068602D01*
G02Y1179354I0J1303D01*
G01X1072342D01*
G02Y1176748I0J-1303D01*
G37*
G36*
G01X647411Y379065D02*
X647412D01*
G02Y370659I0J-4203D01*
G01X647411D01*
G02Y379065I0J4203D01*
G37*
G36*
G01X815062Y1622338D02*
X821185Y1628461D01*
G02X822069Y1628827I884J-885D01*
G01X928166D01*
G02X929050Y1628461I0J-1251D01*
G01X934307Y1623204D01*
G02X934673Y1622320I-885J-884D01*
G01Y1586606D01*
G03X934732Y1586464I200J0D01*
G01X941369Y1579827D01*
G03X941511Y1579768I142J141D01*
G01X956943D01*
G02X957827Y1579402I0J-1251D01*
G01X962023Y1575206D01*
G02X962389Y1574322I-885J-884D01*
G01Y1544281D01*
G03X962448Y1544139I200J0D01*
G01X965638Y1540949D01*
G03X965780Y1540890I142J141D01*
G01X1020507D01*
G02X1021391Y1540524I0J-1251D01*
G01X1033708Y1528207D01*
G02X1034074Y1527323I-885J-884D01*
G01Y1492303D01*
G02X1033708Y1491419I-1251J0D01*
G01X1032711Y1490422D01*
G02X1031827Y1490056I-884J885D01*
G01X946582D01*
G02X945698Y1490422I0J1251D01*
G01X943533Y1492587D01*
G03X943391Y1492646I-142J-141D01*
G01X934180D01*
G03X934038Y1492587I0J-200D01*
G01X919334Y1477883D01*
G03X919275Y1477741I141J-142D01*
G01Y1464419D01*
G02X918909Y1463535I-1251J0D01*
G01X916381Y1461007D01*
G03X916322Y1460865I141J-142D01*
G01Y1460327D01*
G02X915956Y1459443I-1251J0D01*
G01X915720Y1459207D01*
G03X915661Y1459065I141J-142D01*
G01Y1445847D01*
G02X915295Y1444963I-1251J0D01*
G01X914298Y1443966D01*
G02X913414Y1443600I-884J885D01*
G01X899958D01*
G02X899074Y1443966I0J1251D01*
G01X898077Y1444963D01*
G02X897711Y1445847I885J884D01*
G01Y1459039D01*
G03X897652Y1459181I-200J0D01*
G01X897339Y1459494D01*
G02X896973Y1460378I885J884D01*
G01Y1461423D01*
G03X896914Y1461565I-200J0D01*
G01X892210Y1466269D01*
G02X891844Y1467153I885J884D01*
G01Y1472495D01*
G03X891785Y1472637I-200J0D01*
G01X887610Y1476812D01*
G03X887468Y1476871I-142J-141D01*
G01X881105D01*
G03X880963Y1476812I0J-200D01*
G01X874458Y1470307D01*
G03X874399Y1470165I141J-142D01*
G01Y1460390D01*
G02X874033Y1459506I-1251J0D01*
G01X873695Y1459168D01*
G03X873636Y1459026I141J-142D01*
G01Y1445822D01*
G02X873270Y1444938I-1251J0D01*
G01X872311Y1443979D01*
G02X871427Y1443613I-884J885D01*
G01X858101D01*
G02X857217Y1443979I0J1251D01*
G01X855946Y1445250D01*
G02X855580Y1446134I885J884D01*
G01Y1458923D01*
G03X855521Y1459065I-200J0D01*
G01X852317Y1462269D01*
G03X852175Y1462328I-142J-141D01*
G01X829373D01*
G03X829173Y1462128I0J-200D01*
G01Y1461246D01*
G02X828807Y1460362I-1251J0D01*
G01X827914Y1459469D01*
G02X827030Y1459103I-884J885D01*
G01X825637D01*
G03X825495Y1459044I0J-200D01*
G01X822876Y1456425D01*
G02X821992Y1456059I-884J885D01*
G01X821694D01*
G03X821494Y1455859I0J-200D01*
G01Y1445861D01*
G02X821128Y1444977I-1251J0D01*
G01X820169Y1444018D01*
G02X819285Y1443652I-884J885D01*
G01X805792D01*
G02X804908Y1444018I0J1251D01*
G01X803870Y1445056D01*
G02X803504Y1445940I885J884D01*
G01Y1460429D01*
G02X803870Y1461313I1251J0D01*
G01X804002Y1461445D01*
G03X804061Y1461587I-141J142D01*
G01Y1474910D01*
G02X804396Y1475762I1251J0D01*
G03X804450Y1475898I-146J137D01*
G01Y1487743D01*
X804385Y1487842D01*
X804329Y1487866D01*
G02Y1490628I590J1381D01*
G01X804385Y1490652D01*
X804450Y1490751D01*
Y1524316D01*
G02X804816Y1525200I1251J0D01*
G01X814637Y1535021D01*
G03X814696Y1535163I-141J142D01*
G01Y1621454D01*
G02X815062Y1622338I1251J0D01*
G37*
G36*
G01X111494Y1456412D02*
G02X111292Y1456210I-202J0D01*
G01X108472D01*
G02X108270Y1456413I1J203D01*
G01Y1457032D01*
G03X108220Y1457164I-200J0D01*
G02Y1460080I1661J1458D01*
G03X108270Y1460212I-150J132D01*
G01Y1462151D01*
G03X108220Y1462283I-200J0D01*
G02Y1465199I1661J1458D01*
G03X108270Y1465331I-150J132D01*
G01Y1465952D01*
G02X108472Y1466154I202J0D01*
G01X111292D01*
G02X111494Y1465951I-1J-203D01*
G01Y1465331D01*
G03X111544Y1465199I200J0D01*
G02Y1462283I-1661J-1458D01*
G03X111494Y1462151I150J-132D01*
G01Y1460212D01*
G03X111544Y1460080I200J0D01*
G02Y1457164I-1661J-1458D01*
G03X111494Y1457032I150J-132D01*
G01Y1456412D01*
G37*
G36*
G01X319368D02*
G02X319166Y1456210I-202J0D01*
G01X316346D01*
G02X316144Y1456413I1J203D01*
G01Y1457032D01*
G03X316094Y1457164I-200J0D01*
G02Y1460080I1661J1458D01*
G03X316144Y1460212I-150J132D01*
G01Y1462151D01*
G03X316094Y1462283I-200J0D01*
G02Y1465199I1661J1458D01*
G03X316144Y1465331I-150J132D01*
G01Y1465952D01*
G02X316346Y1466154I202J0D01*
G01X319166D01*
G02X319368Y1465951I-1J-203D01*
G01Y1465331D01*
G03X319418Y1465199I200J0D01*
G02Y1462283I-1661J-1458D01*
G03X319368Y1462151I150J-132D01*
G01Y1460212D01*
G03X319418Y1460080I200J0D01*
G02Y1457164I-1661J-1458D01*
G03X319368Y1457032I150J-132D01*
G01Y1456412D01*
G37*
G36*
G01X336690D02*
G02X336488Y1456210I-202J0D01*
G01X333668D01*
G02X333466Y1456413I1J203D01*
G01Y1457032D01*
G03X333416Y1457164I-200J0D01*
G02Y1460080I1661J1458D01*
G03X333466Y1460212I-150J132D01*
G01Y1462151D01*
G03X333416Y1462283I-200J0D01*
G02Y1465199I1661J1458D01*
G03X333466Y1465331I-150J132D01*
G01Y1465952D01*
G02X333668Y1466154I202J0D01*
G01X336488D01*
G02X336690Y1465951I-1J-203D01*
G01Y1465331D01*
G03X336740Y1465199I200J0D01*
G02Y1462283I-1661J-1458D01*
G03X336690Y1462151I150J-132D01*
G01Y1460212D01*
G03X336740Y1460080I200J0D01*
G02Y1457164I-1661J-1458D01*
G03X336690Y1457032I150J-132D01*
G01Y1456412D01*
G37*
G36*
G01X628157Y1466154D02*
X630977D01*
G02X631180Y1465951I0J-203D01*
G01Y1465329D01*
G03X631230Y1465197I200J0D01*
G02Y1462285I-1664J-1456D01*
G03X631180Y1462153I150J-132D01*
G01Y1460210D01*
G03X631230Y1460078I200J0D01*
G02Y1457166I-1664J-1456D01*
G03X631180Y1457034I150J-132D01*
G01Y1456413D01*
G02X630977Y1456210I-203J0D01*
G01X628157D01*
G02X627954Y1456413I0J203D01*
G01Y1457034D01*
G03X627904Y1457166I-200J0D01*
G02Y1460078I1664J1456D01*
G03X627954Y1460210I-150J132D01*
G01Y1462153D01*
G03X627904Y1462285I-200J0D01*
G02Y1465197I1664J1456D01*
G03X627954Y1465329I-150J132D01*
G01Y1465951D01*
G02X628157Y1466154I203J0D01*
G37*
G36*
G01X1133462Y1456412D02*
G02X1133260Y1456210I-202J0D01*
G01X1130440D01*
G02X1130238Y1456413I1J203D01*
G01Y1457032D01*
G03X1130188Y1457164I-200J0D01*
G02Y1460080I1661J1458D01*
G03X1130238Y1460212I-150J132D01*
G01Y1462151D01*
G03X1130188Y1462283I-200J0D01*
G02Y1465199I1661J1458D01*
G03X1130238Y1465331I-150J132D01*
G01Y1465952D01*
G02X1130440Y1466154I202J0D01*
G01X1133260D01*
G02X1133462Y1465951I-1J-203D01*
G01Y1465331D01*
G03X1133512Y1465199I200J0D01*
G02Y1462283I-1661J-1458D01*
G03X1133462Y1462151I150J-132D01*
G01Y1460212D01*
G03X1133512Y1460080I200J0D01*
G02Y1457164I-1661J-1458D01*
G03X1133462Y1457032I150J-132D01*
G01Y1456412D01*
G37*
G36*
G01X1147763Y1466154D02*
X1150583D01*
G02X1150786Y1465951I0J-203D01*
G01Y1465329D01*
G03X1150836Y1465197I200J0D01*
G02Y1462285I-1664J-1456D01*
G03X1150786Y1462153I150J-132D01*
G01Y1460210D01*
G03X1150836Y1460078I200J0D01*
G02Y1457166I-1664J-1456D01*
G03X1150786Y1457034I150J-132D01*
G01Y1456413D01*
G02X1150583Y1456210I-203J0D01*
G01X1147763D01*
G02X1147560Y1456413I0J203D01*
G01Y1457034D01*
G03X1147510Y1457166I-200J0D01*
G02Y1460078I1664J1456D01*
G03X1147560Y1460210I-150J132D01*
G01Y1462153D01*
G03X1147510Y1462285I-200J0D01*
G02Y1465197I1664J1456D01*
G03X1147560Y1465329I-150J132D01*
G01Y1465951D01*
G02X1147763Y1466154I203J0D01*
G37*
G36*
G01X1650125D02*
X1652945D01*
G02X1653148Y1465951I0J-203D01*
G01Y1465329D01*
G03X1653198Y1465197I200J0D01*
G02Y1462285I-1664J-1456D01*
G03X1653148Y1462153I150J-132D01*
G01Y1460210D01*
G03X1653198Y1460078I200J0D01*
G02Y1457166I-1664J-1456D01*
G03X1653148Y1457034I150J-132D01*
G01Y1456413D01*
G02X1652945Y1456210I-203J0D01*
G01X1650125D01*
G02X1649922Y1456413I0J203D01*
G01Y1457034D01*
G03X1649872Y1457166I-200J0D01*
G02Y1460078I1664J1456D01*
G03X1649922Y1460210I-150J132D01*
G01Y1462153D01*
G03X1649872Y1462285I-200J0D01*
G02Y1465197I1664J1456D01*
G03X1649922Y1465329I-150J132D01*
G01Y1465951D01*
G02X1650125Y1466154I203J0D01*
G37*
G36*
G01X1670470Y1456412D02*
G02X1670268Y1456210I-202J0D01*
G01X1667448D01*
G02X1667246Y1456413I1J203D01*
G01Y1457032D01*
G03X1667196Y1457164I-200J0D01*
G02Y1460080I1661J1458D01*
G03X1667246Y1460212I-150J132D01*
G01Y1462151D01*
G03X1667196Y1462283I-200J0D01*
G02Y1465199I1661J1458D01*
G03X1667246Y1465331I-150J132D01*
G01Y1465952D01*
G02X1667448Y1466154I202J0D01*
G01X1670268D01*
G02X1670470Y1465951I-1J-203D01*
G01Y1465331D01*
G03X1670520Y1465199I200J0D01*
G02Y1462283I-1661J-1458D01*
G03X1670470Y1462151I150J-132D01*
G01Y1460212D01*
G03X1670520Y1460080I200J0D01*
G02Y1457164I-1661J-1458D01*
G03X1670470Y1457032I150J-132D01*
G01Y1456412D01*
G37*
G36*
G01X117133Y1470484D02*
X119953D01*
G02X120156Y1470281I0J-203D01*
G01Y1469659D01*
G03X120206Y1469527I200J0D01*
G02Y1466615I-1664J-1456D01*
G03X120156Y1466483I150J-132D01*
G01Y1464541D01*
G03X120206Y1464409I200J0D01*
G02Y1461497I-1664J-1456D01*
G03X120156Y1461365I150J-132D01*
G01Y1460743D01*
G02X119953Y1460540I-203J0D01*
G01X117133D01*
G02X116930Y1460743I0J203D01*
G01Y1461365D01*
G03X116880Y1461497I-200J0D01*
G02Y1464409I1664J1456D01*
G03X116930Y1464541I-150J132D01*
G01Y1466483D01*
G03X116880Y1466615I-200J0D01*
G02Y1469527I1664J1456D01*
G03X116930Y1469659I-150J132D01*
G01Y1470281D01*
G02X117133Y1470484I203J0D01*
G37*
G36*
G01X310706Y1460742D02*
G02X310504Y1460540I-202J0D01*
G01X307684D01*
G02X307482Y1460743I1J203D01*
G01Y1461363D01*
G03X307432Y1461495I-200J0D01*
G02Y1464411I1661J1458D01*
G03X307482Y1464543I-150J132D01*
G01Y1466481D01*
G03X307432Y1466613I-200J0D01*
G02Y1469529I1661J1458D01*
G03X307482Y1469661I-150J132D01*
G01Y1470282D01*
G02X307684Y1470484I202J0D01*
G01X310504D01*
G02X310706Y1470281I-1J-203D01*
G01Y1469661D01*
G03X310756Y1469529I200J0D01*
G02Y1466613I-1661J-1458D01*
G03X310706Y1466481I150J-132D01*
G01Y1464543D01*
G03X310756Y1464411I200J0D01*
G02Y1461495I-1661J-1458D01*
G03X310706Y1461363I150J-132D01*
G01Y1460742D01*
G37*
G36*
G01X325007Y1470484D02*
X327827D01*
G02X328030Y1470281I0J-203D01*
G01Y1469659D01*
G03X328080Y1469527I200J0D01*
G02Y1466615I-1664J-1456D01*
G03X328030Y1466483I150J-132D01*
G01Y1464541D01*
G03X328080Y1464409I200J0D01*
G02Y1461497I-1664J-1456D01*
G03X328030Y1461365I150J-132D01*
G01Y1460743D01*
G02X327827Y1460540I-203J0D01*
G01X325007D01*
G02X324804Y1460743I0J203D01*
G01Y1461365D01*
G03X324754Y1461497I-200J0D01*
G02Y1464409I1664J1456D01*
G03X324804Y1464541I-150J132D01*
G01Y1466483D01*
G03X324754Y1466615I-200J0D01*
G02Y1469527I1664J1456D01*
G03X324804Y1469659I-150J132D01*
G01Y1470281D01*
G02X325007Y1470484I203J0D01*
G37*
G36*
G01X345352Y1460742D02*
G02X345150Y1460540I-202J0D01*
G01X342330D01*
G02X342128Y1460743I1J203D01*
G01Y1461363D01*
G03X342078Y1461495I-200J0D01*
G02Y1464411I1661J1458D01*
G03X342128Y1464543I-150J132D01*
G01Y1466481D01*
G03X342078Y1466613I-200J0D01*
G02Y1469529I1661J1458D01*
G03X342128Y1469661I-150J132D01*
G01Y1470282D01*
G02X342330Y1470484I202J0D01*
G01X345150D01*
G02X345352Y1470281I-1J-203D01*
G01Y1469661D01*
G03X345402Y1469529I200J0D01*
G02Y1466613I-1661J-1458D01*
G03X345352Y1466481I150J-132D01*
G01Y1464543D01*
G03X345402Y1464411I200J0D01*
G02Y1461495I-1661J-1458D01*
G03X345352Y1461363I150J-132D01*
G01Y1460742D01*
G37*
G36*
G01X639840D02*
G02X639638Y1460540I-202J0D01*
G01X636818D01*
G02X636616Y1460743I1J203D01*
G01Y1461363D01*
G03X636566Y1461495I-200J0D01*
G02Y1464411I1661J1458D01*
G03X636616Y1464543I-150J132D01*
G01Y1466481D01*
G03X636566Y1466613I-200J0D01*
G02Y1469529I1661J1458D01*
G03X636616Y1469661I-150J132D01*
G01Y1470282D01*
G02X636818Y1470484I202J0D01*
G01X639638D01*
G02X639840Y1470281I-1J-203D01*
G01Y1469661D01*
G03X639890Y1469529I200J0D01*
G02Y1466613I-1661J-1458D01*
G03X639840Y1466481I150J-132D01*
G01Y1464543D01*
G03X639890Y1464411I200J0D01*
G02Y1461495I-1661J-1458D01*
G03X639840Y1461363I150J-132D01*
G01Y1460742D01*
G37*
G36*
G01X1139101Y1470484D02*
X1141921D01*
G02X1142124Y1470281I0J-203D01*
G01Y1469659D01*
G03X1142174Y1469527I200J0D01*
G02Y1466615I-1664J-1456D01*
G03X1142124Y1466483I150J-132D01*
G01Y1464541D01*
G03X1142174Y1464409I200J0D01*
G02Y1461497I-1664J-1456D01*
G03X1142124Y1461365I150J-132D01*
G01Y1460743D01*
G02X1141921Y1460540I-203J0D01*
G01X1139101D01*
G02X1138898Y1460743I0J203D01*
G01Y1461365D01*
G03X1138848Y1461497I-200J0D01*
G02Y1464409I1664J1456D01*
G03X1138898Y1464541I-150J132D01*
G01Y1466483D01*
G03X1138848Y1466615I-200J0D01*
G02Y1469527I1664J1456D01*
G03X1138898Y1469659I-150J132D01*
G01Y1470281D01*
G02X1139101Y1470484I203J0D01*
G37*
G36*
G01X1159446Y1460742D02*
G02X1159244Y1460540I-202J0D01*
G01X1156424D01*
G02X1156222Y1460743I1J203D01*
G01Y1461363D01*
G03X1156172Y1461495I-200J0D01*
G02Y1464411I1661J1458D01*
G03X1156222Y1464543I-150J132D01*
G01Y1466481D01*
G03X1156172Y1466613I-200J0D01*
G02Y1469529I1661J1458D01*
G03X1156222Y1469661I-150J132D01*
G01Y1470282D01*
G02X1156424Y1470484I202J0D01*
G01X1159244D01*
G02X1159446Y1470281I-1J-203D01*
G01Y1469661D01*
G03X1159496Y1469529I200J0D01*
G02Y1466613I-1661J-1458D01*
G03X1159446Y1466481I150J-132D01*
G01Y1464543D01*
G03X1159496Y1464411I200J0D01*
G02Y1461495I-1661J-1458D01*
G03X1159446Y1461363I150J-132D01*
G01Y1460742D01*
G37*
G36*
G01X1661808D02*
G02X1661606Y1460540I-202J0D01*
G01X1658786D01*
G02X1658584Y1460743I1J203D01*
G01Y1461363D01*
G03X1658534Y1461495I-200J0D01*
G02Y1464411I1661J1458D01*
G03X1658584Y1464543I-150J132D01*
G01Y1466481D01*
G03X1658534Y1466613I-200J0D01*
G02Y1469529I1661J1458D01*
G03X1658584Y1469661I-150J132D01*
G01Y1470282D01*
G02X1658786Y1470484I202J0D01*
G01X1661606D01*
G02X1661808Y1470281I-1J-203D01*
G01Y1469661D01*
G03X1661858Y1469529I200J0D01*
G02Y1466613I-1661J-1458D01*
G03X1661808Y1466481I150J-132D01*
G01Y1464543D01*
G03X1661858Y1464411I200J0D01*
G02Y1461495I-1661J-1458D01*
G03X1661808Y1461363I150J-132D01*
G01Y1460742D01*
G37*
G36*
G01X1676109Y1470484D02*
X1678929D01*
G02X1679132Y1470281I0J-203D01*
G01Y1469659D01*
G03X1679182Y1469527I200J0D01*
G02Y1466615I-1664J-1456D01*
G03X1679132Y1466483I150J-132D01*
G01Y1464541D01*
G03X1679182Y1464409I200J0D01*
G02Y1461497I-1664J-1456D01*
G03X1679132Y1461365I150J-132D01*
G01Y1460743D01*
G02X1678929Y1460540I-203J0D01*
G01X1676109D01*
G02X1675906Y1460743I0J203D01*
G01Y1461365D01*
G03X1675856Y1461497I-200J0D01*
G02Y1464409I1664J1456D01*
G03X1675906Y1464541I-150J132D01*
G01Y1466483D01*
G03X1675856Y1466615I-200J0D01*
G02Y1469527I1664J1456D01*
G03X1675906Y1469659I-150J132D01*
G01Y1470281D01*
G02X1676109Y1470484I203J0D01*
G37*
G36*
G01X111494Y1471766D02*
G02X111292Y1471564I-202J0D01*
G01X108472D01*
G02X108270Y1471767I1J203D01*
G01Y1472387D01*
G03X108220Y1472519I-200J0D01*
G02Y1475435I1661J1458D01*
G03X108270Y1475567I-150J132D01*
G01Y1477505D01*
G03X108220Y1477637I-200J0D01*
G02Y1480553I1661J1458D01*
G03X108270Y1480685I-150J132D01*
G01Y1481306D01*
G02X108472Y1481508I202J0D01*
G01X111292D01*
G02X111494Y1481305I-1J-203D01*
G01Y1480685D01*
G03X111544Y1480553I200J0D01*
G02Y1477637I-1661J-1458D01*
G03X111494Y1477505I150J-132D01*
G01Y1475567D01*
G03X111544Y1475435I200J0D01*
G02Y1472519I-1661J-1458D01*
G03X111494Y1472387I150J-132D01*
G01Y1471766D01*
G37*
G36*
G01X319368D02*
G02X319166Y1471564I-202J0D01*
G01X316346D01*
G02X316144Y1471767I1J203D01*
G01Y1472387D01*
G03X316094Y1472519I-200J0D01*
G02Y1475435I1661J1458D01*
G03X316144Y1475567I-150J132D01*
G01Y1477505D01*
G03X316094Y1477637I-200J0D01*
G02Y1480553I1661J1458D01*
G03X316144Y1480685I-150J132D01*
G01Y1481306D01*
G02X316346Y1481508I202J0D01*
G01X319166D01*
G02X319368Y1481305I-1J-203D01*
G01Y1480685D01*
G03X319418Y1480553I200J0D01*
G02Y1477637I-1661J-1458D01*
G03X319368Y1477505I150J-132D01*
G01Y1475567D01*
G03X319418Y1475435I200J0D01*
G02Y1472519I-1661J-1458D01*
G03X319368Y1472387I150J-132D01*
G01Y1471766D01*
G37*
G36*
G01X336690D02*
G02X336488Y1471564I-202J0D01*
G01X333668D01*
G02X333466Y1471767I1J203D01*
G01Y1472387D01*
G03X333416Y1472519I-200J0D01*
G02Y1475435I1661J1458D01*
G03X333466Y1475567I-150J132D01*
G01Y1477505D01*
G03X333416Y1477637I-200J0D01*
G02Y1480553I1661J1458D01*
G03X333466Y1480685I-150J132D01*
G01Y1481306D01*
G02X333668Y1481508I202J0D01*
G01X336488D01*
G02X336690Y1481305I-1J-203D01*
G01Y1480685D01*
G03X336740Y1480553I200J0D01*
G02Y1477637I-1661J-1458D01*
G03X336690Y1477505I150J-132D01*
G01Y1475567D01*
G03X336740Y1475435I200J0D01*
G02Y1472519I-1661J-1458D01*
G03X336690Y1472387I150J-132D01*
G01Y1471766D01*
G37*
G36*
G01X628157Y1481508D02*
X630977D01*
G02X631180Y1481305I0J-203D01*
G01Y1480683D01*
G03X631230Y1480551I200J0D01*
G02Y1477639I-1664J-1456D01*
G03X631180Y1477507I150J-132D01*
G01Y1475565D01*
G03X631230Y1475433I200J0D01*
G02Y1472521I-1664J-1456D01*
G03X631180Y1472389I150J-132D01*
G01Y1471767D01*
G02X630977Y1471564I-203J0D01*
G01X628157D01*
G02X627954Y1471767I0J203D01*
G01Y1472389D01*
G03X627904Y1472521I-200J0D01*
G02Y1475433I1664J1456D01*
G03X627954Y1475565I-150J132D01*
G01Y1477507D01*
G03X627904Y1477639I-200J0D01*
G02Y1480551I1664J1456D01*
G03X627954Y1480683I-150J132D01*
G01Y1481305D01*
G02X628157Y1481508I203J0D01*
G37*
G36*
G01X1133462Y1471766D02*
G02X1133260Y1471564I-202J0D01*
G01X1130440D01*
G02X1130238Y1471767I1J203D01*
G01Y1472387D01*
G03X1130188Y1472519I-200J0D01*
G02Y1475435I1661J1458D01*
G03X1130238Y1475567I-150J132D01*
G01Y1477505D01*
G03X1130188Y1477637I-200J0D01*
G02Y1480553I1661J1458D01*
G03X1130238Y1480685I-150J132D01*
G01Y1481306D01*
G02X1130440Y1481508I202J0D01*
G01X1133260D01*
G02X1133462Y1481305I-1J-203D01*
G01Y1480685D01*
G03X1133512Y1480553I200J0D01*
G02Y1477637I-1661J-1458D01*
G03X1133462Y1477505I150J-132D01*
G01Y1475567D01*
G03X1133512Y1475435I200J0D01*
G02Y1472519I-1661J-1458D01*
G03X1133462Y1472387I150J-132D01*
G01Y1471766D01*
G37*
G36*
G01X1147763Y1481508D02*
X1150583D01*
G02X1150786Y1481305I0J-203D01*
G01Y1480683D01*
G03X1150836Y1480551I200J0D01*
G02Y1477639I-1664J-1456D01*
G03X1150786Y1477507I150J-132D01*
G01Y1475565D01*
G03X1150836Y1475433I200J0D01*
G02Y1472521I-1664J-1456D01*
G03X1150786Y1472389I150J-132D01*
G01Y1471767D01*
G02X1150583Y1471564I-203J0D01*
G01X1147763D01*
G02X1147560Y1471767I0J203D01*
G01Y1472389D01*
G03X1147510Y1472521I-200J0D01*
G02Y1475433I1664J1456D01*
G03X1147560Y1475565I-150J132D01*
G01Y1477507D01*
G03X1147510Y1477639I-200J0D01*
G02Y1480551I1664J1456D01*
G03X1147560Y1480683I-150J132D01*
G01Y1481305D01*
G02X1147763Y1481508I203J0D01*
G37*
G36*
G01X1650125D02*
X1652945D01*
G02X1653148Y1481305I0J-203D01*
G01Y1480683D01*
G03X1653198Y1480551I200J0D01*
G02Y1477639I-1664J-1456D01*
G03X1653148Y1477507I150J-132D01*
G01Y1475565D01*
G03X1653198Y1475433I200J0D01*
G02Y1472521I-1664J-1456D01*
G03X1653148Y1472389I150J-132D01*
G01Y1471767D01*
G02X1652945Y1471564I-203J0D01*
G01X1650125D01*
G02X1649922Y1471767I0J203D01*
G01Y1472389D01*
G03X1649872Y1472521I-200J0D01*
G02Y1475433I1664J1456D01*
G03X1649922Y1475565I-150J132D01*
G01Y1477507D01*
G03X1649872Y1477639I-200J0D01*
G02Y1480551I1664J1456D01*
G03X1649922Y1480683I-150J132D01*
G01Y1481305D01*
G02X1650125Y1481508I203J0D01*
G37*
G36*
G01X1670470Y1471766D02*
G02X1670268Y1471564I-202J0D01*
G01X1667448D01*
G02X1667246Y1471767I1J203D01*
G01Y1472387D01*
G03X1667196Y1472519I-200J0D01*
G02Y1475435I1661J1458D01*
G03X1667246Y1475567I-150J132D01*
G01Y1477505D01*
G03X1667196Y1477637I-200J0D01*
G02Y1480553I1661J1458D01*
G03X1667246Y1480685I-150J132D01*
G01Y1481306D01*
G02X1667448Y1481508I202J0D01*
G01X1670268D01*
G02X1670470Y1481305I-1J-203D01*
G01Y1480685D01*
G03X1670520Y1480553I200J0D01*
G02Y1477637I-1661J-1458D01*
G03X1670470Y1477505I150J-132D01*
G01Y1475567D01*
G03X1670520Y1475435I200J0D01*
G02Y1472519I-1661J-1458D01*
G03X1670470Y1472387I150J-132D01*
G01Y1471766D01*
G37*
G36*
G01X117133Y1485838D02*
X119953D01*
G02X120156Y1485635I0J-203D01*
G01Y1485014D01*
G03X120206Y1484882I200J0D01*
G02Y1481970I-1664J-1456D01*
G03X120156Y1481838I150J-132D01*
G01Y1479896D01*
G03X120206Y1479764I200J0D01*
G02Y1476852I-1664J-1456D01*
G03X120156Y1476720I150J-132D01*
G01Y1476097D01*
G02X119953Y1475894I-203J0D01*
G01X117133D01*
G02X116930Y1476097I0J203D01*
G01Y1476720D01*
G03X116880Y1476852I-200J0D01*
G02Y1479764I1664J1456D01*
G03X116930Y1479896I-150J132D01*
G01Y1481838D01*
G03X116880Y1481970I-200J0D01*
G02Y1484882I1664J1456D01*
G03X116930Y1485014I-150J132D01*
G01Y1485635D01*
G02X117133Y1485838I203J0D01*
G37*
G36*
G01X310706Y1476096D02*
G02X310504Y1475894I-202J0D01*
G01X307684D01*
G02X307482Y1476097I1J203D01*
G01Y1476718D01*
G03X307432Y1476850I-200J0D01*
G02Y1479766I1661J1458D01*
G03X307482Y1479898I-150J132D01*
G01Y1481836D01*
G03X307432Y1481968I-200J0D01*
G02Y1484884I1661J1458D01*
G03X307482Y1485016I-150J132D01*
G01Y1485636D01*
G02X307684Y1485838I202J0D01*
G01X310504D01*
G02X310706Y1485635I-1J-203D01*
G01Y1485016D01*
G03X310756Y1484884I200J0D01*
G02Y1481968I-1661J-1458D01*
G03X310706Y1481836I150J-132D01*
G01Y1479898D01*
G03X310756Y1479766I200J0D01*
G02Y1476850I-1661J-1458D01*
G03X310706Y1476718I150J-132D01*
G01Y1476096D01*
G37*
G36*
G01X325007Y1485838D02*
X327827D01*
G02X328030Y1485635I0J-203D01*
G01Y1485014D01*
G03X328080Y1484882I200J0D01*
G02Y1481970I-1664J-1456D01*
G03X328030Y1481838I150J-132D01*
G01Y1479896D01*
G03X328080Y1479764I200J0D01*
G02Y1476852I-1664J-1456D01*
G03X328030Y1476720I150J-132D01*
G01Y1476097D01*
G02X327827Y1475894I-203J0D01*
G01X325007D01*
G02X324804Y1476097I0J203D01*
G01Y1476720D01*
G03X324754Y1476852I-200J0D01*
G02Y1479764I1664J1456D01*
G03X324804Y1479896I-150J132D01*
G01Y1481838D01*
G03X324754Y1481970I-200J0D01*
G02Y1484882I1664J1456D01*
G03X324804Y1485014I-150J132D01*
G01Y1485635D01*
G02X325007Y1485838I203J0D01*
G37*
G36*
G01X345352Y1476096D02*
G02X345150Y1475894I-202J0D01*
G01X342330D01*
G02X342128Y1476097I1J203D01*
G01Y1476718D01*
G03X342078Y1476850I-200J0D01*
G02Y1479766I1661J1458D01*
G03X342128Y1479898I-150J132D01*
G01Y1481836D01*
G03X342078Y1481968I-200J0D01*
G02Y1484884I1661J1458D01*
G03X342128Y1485016I-150J132D01*
G01Y1485636D01*
G02X342330Y1485838I202J0D01*
G01X345150D01*
G02X345352Y1485635I-1J-203D01*
G01Y1485016D01*
G03X345402Y1484884I200J0D01*
G02Y1481968I-1661J-1458D01*
G03X345352Y1481836I150J-132D01*
G01Y1479898D01*
G03X345402Y1479766I200J0D01*
G02Y1476850I-1661J-1458D01*
G03X345352Y1476718I150J-132D01*
G01Y1476096D01*
G37*
G36*
G01X639840D02*
G02X639638Y1475894I-202J0D01*
G01X636818D01*
G02X636616Y1476097I1J203D01*
G01Y1476718D01*
G03X636566Y1476850I-200J0D01*
G02Y1479766I1661J1458D01*
G03X636616Y1479898I-150J132D01*
G01Y1481836D01*
G03X636566Y1481968I-200J0D01*
G02Y1484884I1661J1458D01*
G03X636616Y1485016I-150J132D01*
G01Y1485636D01*
G02X636818Y1485838I202J0D01*
G01X639638D01*
G02X639840Y1485635I-1J-203D01*
G01Y1485016D01*
G03X639890Y1484884I200J0D01*
G02Y1481968I-1661J-1458D01*
G03X639840Y1481836I150J-132D01*
G01Y1479898D01*
G03X639890Y1479766I200J0D01*
G02Y1476850I-1661J-1458D01*
G03X639840Y1476718I150J-132D01*
G01Y1476096D01*
G37*
G36*
G01X1139101Y1485838D02*
X1141921D01*
G02X1142124Y1485635I0J-203D01*
G01Y1485014D01*
G03X1142174Y1484882I200J0D01*
G02Y1481970I-1664J-1456D01*
G03X1142124Y1481838I150J-132D01*
G01Y1479896D01*
G03X1142174Y1479764I200J0D01*
G02Y1476852I-1664J-1456D01*
G03X1142124Y1476720I150J-132D01*
G01Y1476097D01*
G02X1141921Y1475894I-203J0D01*
G01X1139101D01*
G02X1138898Y1476097I0J203D01*
G01Y1476720D01*
G03X1138848Y1476852I-200J0D01*
G02Y1479764I1664J1456D01*
G03X1138898Y1479896I-150J132D01*
G01Y1481838D01*
G03X1138848Y1481970I-200J0D01*
G02Y1484882I1664J1456D01*
G03X1138898Y1485014I-150J132D01*
G01Y1485635D01*
G02X1139101Y1485838I203J0D01*
G37*
G36*
G01X1159446Y1476096D02*
G02X1159244Y1475894I-202J0D01*
G01X1156424D01*
G02X1156222Y1476097I1J203D01*
G01Y1476718D01*
G03X1156172Y1476850I-200J0D01*
G02Y1479766I1661J1458D01*
G03X1156222Y1479898I-150J132D01*
G01Y1481836D01*
G03X1156172Y1481968I-200J0D01*
G02Y1484884I1661J1458D01*
G03X1156222Y1485016I-150J132D01*
G01Y1485636D01*
G02X1156424Y1485838I202J0D01*
G01X1159244D01*
G02X1159446Y1485635I-1J-203D01*
G01Y1485016D01*
G03X1159496Y1484884I200J0D01*
G02Y1481968I-1661J-1458D01*
G03X1159446Y1481836I150J-132D01*
G01Y1479898D01*
G03X1159496Y1479766I200J0D01*
G02Y1476850I-1661J-1458D01*
G03X1159446Y1476718I150J-132D01*
G01Y1476096D01*
G37*
G36*
G01X1661808D02*
G02X1661606Y1475894I-202J0D01*
G01X1658786D01*
G02X1658584Y1476097I1J203D01*
G01Y1476718D01*
G03X1658534Y1476850I-200J0D01*
G02Y1479766I1661J1458D01*
G03X1658584Y1479898I-150J132D01*
G01Y1481836D01*
G03X1658534Y1481968I-200J0D01*
G02Y1484884I1661J1458D01*
G03X1658584Y1485016I-150J132D01*
G01Y1485636D01*
G02X1658786Y1485838I202J0D01*
G01X1661606D01*
G02X1661808Y1485635I-1J-203D01*
G01Y1485016D01*
G03X1661858Y1484884I200J0D01*
G02Y1481968I-1661J-1458D01*
G03X1661808Y1481836I150J-132D01*
G01Y1479898D01*
G03X1661858Y1479766I200J0D01*
G02Y1476850I-1661J-1458D01*
G03X1661808Y1476718I150J-132D01*
G01Y1476096D01*
G37*
G36*
G01X1676109Y1485838D02*
X1678929D01*
G02X1679132Y1485635I0J-203D01*
G01Y1485014D01*
G03X1679182Y1484882I200J0D01*
G02Y1481970I-1664J-1456D01*
G03X1679132Y1481838I150J-132D01*
G01Y1479896D01*
G03X1679182Y1479764I200J0D01*
G02Y1476852I-1664J-1456D01*
G03X1679132Y1476720I150J-132D01*
G01Y1476097D01*
G02X1678929Y1475894I-203J0D01*
G01X1676109D01*
G02X1675906Y1476097I0J203D01*
G01Y1476720D01*
G03X1675856Y1476852I-200J0D01*
G02Y1479764I1664J1456D01*
G03X1675906Y1479896I-150J132D01*
G01Y1481838D01*
G03X1675856Y1481970I-200J0D01*
G02Y1484882I1664J1456D01*
G03X1675906Y1485014I-150J132D01*
G01Y1485635D01*
G02X1676109Y1485838I203J0D01*
G37*
G36*
G01X111494Y1487120D02*
G02X111292Y1486918I-202J0D01*
G01X108472D01*
G02X108270Y1487121I1J203D01*
G01Y1487741D01*
G03X108220Y1487873I-200J0D01*
G02Y1490789I1661J1458D01*
G03X108270Y1490921I-150J132D01*
G01Y1492859D01*
G03X108220Y1492991I-200J0D01*
G02Y1495907I1661J1458D01*
G03X108270Y1496039I-150J132D01*
G01Y1496660D01*
G02X108472Y1496862I202J0D01*
G01X111292D01*
G02X111494Y1496659I-1J-203D01*
G01Y1496039D01*
G03X111544Y1495907I200J0D01*
G02Y1492991I-1661J-1458D01*
G03X111494Y1492859I150J-132D01*
G01Y1490921D01*
G03X111544Y1490789I200J0D01*
G02Y1487873I-1661J-1458D01*
G03X111494Y1487741I150J-132D01*
G01Y1487120D01*
G37*
G36*
G01X319368D02*
G02X319166Y1486918I-202J0D01*
G01X316346D01*
G02X316144Y1487121I1J203D01*
G01Y1487741D01*
G03X316094Y1487873I-200J0D01*
G02Y1490789I1661J1458D01*
G03X316144Y1490921I-150J132D01*
G01Y1492859D01*
G03X316094Y1492991I-200J0D01*
G02Y1495907I1661J1458D01*
G03X316144Y1496039I-150J132D01*
G01Y1496660D01*
G02X316346Y1496862I202J0D01*
G01X319166D01*
G02X319368Y1496659I-1J-203D01*
G01Y1496039D01*
G03X319418Y1495907I200J0D01*
G02Y1492991I-1661J-1458D01*
G03X319368Y1492859I150J-132D01*
G01Y1490921D01*
G03X319418Y1490789I200J0D01*
G02Y1487873I-1661J-1458D01*
G03X319368Y1487741I150J-132D01*
G01Y1487120D01*
G37*
G36*
G01X336690D02*
G02X336488Y1486918I-202J0D01*
G01X333668D01*
G02X333466Y1487121I1J203D01*
G01Y1487741D01*
G03X333416Y1487873I-200J0D01*
G02Y1490789I1661J1458D01*
G03X333466Y1490921I-150J132D01*
G01Y1492859D01*
G03X333416Y1492991I-200J0D01*
G02Y1495907I1661J1458D01*
G03X333466Y1496039I-150J132D01*
G01Y1496660D01*
G02X333668Y1496862I202J0D01*
G01X336488D01*
G02X336690Y1496659I-1J-203D01*
G01Y1496039D01*
G03X336740Y1495907I200J0D01*
G02Y1492991I-1661J-1458D01*
G03X336690Y1492859I150J-132D01*
G01Y1490921D01*
G03X336740Y1490789I200J0D01*
G02Y1487873I-1661J-1458D01*
G03X336690Y1487741I150J-132D01*
G01Y1487120D01*
G37*
G36*
G01X628157Y1496862D02*
X630977D01*
G02X631180Y1496659I0J-203D01*
G01Y1496037D01*
G03X631230Y1495905I200J0D01*
G02Y1492993I-1664J-1456D01*
G03X631180Y1492861I150J-132D01*
G01Y1490919D01*
G03X631230Y1490787I200J0D01*
G02Y1487875I-1664J-1456D01*
G03X631180Y1487743I150J-132D01*
G01Y1487121D01*
G02X630977Y1486918I-203J0D01*
G01X628157D01*
G02X627954Y1487121I0J203D01*
G01Y1487743D01*
G03X627904Y1487875I-200J0D01*
G02Y1490787I1664J1456D01*
G03X627954Y1490919I-150J132D01*
G01Y1492861D01*
G03X627904Y1492993I-200J0D01*
G02Y1495905I1664J1456D01*
G03X627954Y1496037I-150J132D01*
G01Y1496659D01*
G02X628157Y1496862I203J0D01*
G37*
G36*
G01X1133462Y1487120D02*
G02X1133260Y1486918I-202J0D01*
G01X1130440D01*
G02X1130238Y1487121I1J203D01*
G01Y1487741D01*
G03X1130188Y1487873I-200J0D01*
G02Y1490789I1661J1458D01*
G03X1130238Y1490921I-150J132D01*
G01Y1492859D01*
G03X1130188Y1492991I-200J0D01*
G02Y1495907I1661J1458D01*
G03X1130238Y1496039I-150J132D01*
G01Y1496660D01*
G02X1130440Y1496862I202J0D01*
G01X1133260D01*
G02X1133462Y1496659I-1J-203D01*
G01Y1496039D01*
G03X1133512Y1495907I200J0D01*
G02Y1492991I-1661J-1458D01*
G03X1133462Y1492859I150J-132D01*
G01Y1490921D01*
G03X1133512Y1490789I200J0D01*
G02Y1487873I-1661J-1458D01*
G03X1133462Y1487741I150J-132D01*
G01Y1487120D01*
G37*
G36*
G01X1147763Y1496862D02*
X1150583D01*
G02X1150786Y1496659I0J-203D01*
G01Y1496037D01*
G03X1150836Y1495905I200J0D01*
G02Y1492993I-1664J-1456D01*
G03X1150786Y1492861I150J-132D01*
G01Y1490919D01*
G03X1150836Y1490787I200J0D01*
G02Y1487875I-1664J-1456D01*
G03X1150786Y1487743I150J-132D01*
G01Y1487121D01*
G02X1150583Y1486918I-203J0D01*
G01X1147763D01*
G02X1147560Y1487121I0J203D01*
G01Y1487743D01*
G03X1147510Y1487875I-200J0D01*
G02Y1490787I1664J1456D01*
G03X1147560Y1490919I-150J132D01*
G01Y1492861D01*
G03X1147510Y1492993I-200J0D01*
G02Y1495905I1664J1456D01*
G03X1147560Y1496037I-150J132D01*
G01Y1496659D01*
G02X1147763Y1496862I203J0D01*
G37*
G36*
G01X1650125D02*
X1652945D01*
G02X1653148Y1496659I0J-203D01*
G01Y1496037D01*
G03X1653198Y1495905I200J0D01*
G02Y1492993I-1664J-1456D01*
G03X1653148Y1492861I150J-132D01*
G01Y1490919D01*
G03X1653198Y1490787I200J0D01*
G02Y1487875I-1664J-1456D01*
G03X1653148Y1487743I150J-132D01*
G01Y1487121D01*
G02X1652945Y1486918I-203J0D01*
G01X1650125D01*
G02X1649922Y1487121I0J203D01*
G01Y1487743D01*
G03X1649872Y1487875I-200J0D01*
G02Y1490787I1664J1456D01*
G03X1649922Y1490919I-150J132D01*
G01Y1492861D01*
G03X1649872Y1492993I-200J0D01*
G02Y1495905I1664J1456D01*
G03X1649922Y1496037I-150J132D01*
G01Y1496659D01*
G02X1650125Y1496862I203J0D01*
G37*
G36*
G01X1670470Y1487120D02*
G02X1670268Y1486918I-202J0D01*
G01X1667448D01*
G02X1667246Y1487121I1J203D01*
G01Y1487741D01*
G03X1667196Y1487873I-200J0D01*
G02Y1490789I1661J1458D01*
G03X1667246Y1490921I-150J132D01*
G01Y1492859D01*
G03X1667196Y1492991I-200J0D01*
G02Y1495907I1661J1458D01*
G03X1667246Y1496039I-150J132D01*
G01Y1496660D01*
G02X1667448Y1496862I202J0D01*
G01X1670268D01*
G02X1670470Y1496659I-1J-203D01*
G01Y1496039D01*
G03X1670520Y1495907I200J0D01*
G02Y1492991I-1661J-1458D01*
G03X1670470Y1492859I150J-132D01*
G01Y1490921D01*
G03X1670520Y1490789I200J0D01*
G02Y1487873I-1661J-1458D01*
G03X1670470Y1487741I150J-132D01*
G01Y1487120D01*
G37*
G36*
G01X117133Y1501192D02*
X119953D01*
G02X120156Y1500989I0J-203D01*
G01Y1500368D01*
G03X120206Y1500236I200J0D01*
G02Y1497324I-1664J-1456D01*
G03X120156Y1497192I150J-132D01*
G01Y1495250D01*
G03X120206Y1495118I200J0D01*
G02Y1492206I-1664J-1456D01*
G03X120156Y1492074I150J-132D01*
G01Y1491451D01*
G02X119953Y1491248I-203J0D01*
G01X117133D01*
G02X116930Y1491451I0J203D01*
G01Y1492074D01*
G03X116880Y1492206I-200J0D01*
G02Y1495118I1664J1456D01*
G03X116930Y1495250I-150J132D01*
G01Y1497192D01*
G03X116880Y1497324I-200J0D01*
G02Y1500236I1664J1456D01*
G03X116930Y1500368I-150J132D01*
G01Y1500989D01*
G02X117133Y1501192I203J0D01*
G37*
G36*
G01X310706Y1491450D02*
G02X310504Y1491248I-202J0D01*
G01X307684D01*
G02X307482Y1491451I1J203D01*
G01Y1492072D01*
G03X307432Y1492204I-200J0D01*
G02Y1495120I1661J1458D01*
G03X307482Y1495252I-150J132D01*
G01Y1497190D01*
G03X307432Y1497322I-200J0D01*
G02Y1500238I1661J1458D01*
G03X307482Y1500370I-150J132D01*
G01Y1500990D01*
G02X307684Y1501192I202J0D01*
G01X310504D01*
G02X310706Y1500989I-1J-203D01*
G01Y1500370D01*
G03X310756Y1500238I200J0D01*
G02Y1497322I-1661J-1458D01*
G03X310706Y1497190I150J-132D01*
G01Y1495252D01*
G03X310756Y1495120I200J0D01*
G02Y1492204I-1661J-1458D01*
G03X310706Y1492072I150J-132D01*
G01Y1491450D01*
G37*
G36*
G01X325007Y1501192D02*
X327827D01*
G02X328030Y1500989I0J-203D01*
G01Y1500368D01*
G03X328080Y1500236I200J0D01*
G02Y1497324I-1664J-1456D01*
G03X328030Y1497192I150J-132D01*
G01Y1495250D01*
G03X328080Y1495118I200J0D01*
G02Y1492206I-1664J-1456D01*
G03X328030Y1492074I150J-132D01*
G01Y1491451D01*
G02X327827Y1491248I-203J0D01*
G01X325007D01*
G02X324804Y1491451I0J203D01*
G01Y1492074D01*
G03X324754Y1492206I-200J0D01*
G02Y1495118I1664J1456D01*
G03X324804Y1495250I-150J132D01*
G01Y1497192D01*
G03X324754Y1497324I-200J0D01*
G02Y1500236I1664J1456D01*
G03X324804Y1500368I-150J132D01*
G01Y1500989D01*
G02X325007Y1501192I203J0D01*
G37*
G36*
G01X345352Y1491450D02*
G02X345150Y1491248I-202J0D01*
G01X342330D01*
G02X342128Y1491451I1J203D01*
G01Y1492072D01*
G03X342078Y1492204I-200J0D01*
G02Y1495120I1661J1458D01*
G03X342128Y1495252I-150J132D01*
G01Y1497190D01*
G03X342078Y1497322I-200J0D01*
G02Y1500238I1661J1458D01*
G03X342128Y1500370I-150J132D01*
G01Y1500990D01*
G02X342330Y1501192I202J0D01*
G01X345150D01*
G02X345352Y1500989I-1J-203D01*
G01Y1500370D01*
G03X345402Y1500238I200J0D01*
G02Y1497322I-1661J-1458D01*
G03X345352Y1497190I150J-132D01*
G01Y1495252D01*
G03X345402Y1495120I200J0D01*
G02Y1492204I-1661J-1458D01*
G03X345352Y1492072I150J-132D01*
G01Y1491450D01*
G37*
G36*
G01X639840D02*
G02X639638Y1491248I-202J0D01*
G01X636818D01*
G02X636616Y1491451I1J203D01*
G01Y1492072D01*
G03X636566Y1492204I-200J0D01*
G02Y1495120I1661J1458D01*
G03X636616Y1495252I-150J132D01*
G01Y1497190D01*
G03X636566Y1497322I-200J0D01*
G02Y1500238I1661J1458D01*
G03X636616Y1500370I-150J132D01*
G01Y1500990D01*
G02X636818Y1501192I202J0D01*
G01X639638D01*
G02X639840Y1500989I-1J-203D01*
G01Y1500370D01*
G03X639890Y1500238I200J0D01*
G02Y1497322I-1661J-1458D01*
G03X639840Y1497190I150J-132D01*
G01Y1495252D01*
G03X639890Y1495120I200J0D01*
G02Y1492204I-1661J-1458D01*
G03X639840Y1492072I150J-132D01*
G01Y1491450D01*
G37*
G36*
G01X1139101Y1501192D02*
X1141921D01*
G02X1142124Y1500989I0J-203D01*
G01Y1500368D01*
G03X1142174Y1500236I200J0D01*
G02Y1497324I-1664J-1456D01*
G03X1142124Y1497192I150J-132D01*
G01Y1495250D01*
G03X1142174Y1495118I200J0D01*
G02Y1492206I-1664J-1456D01*
G03X1142124Y1492074I150J-132D01*
G01Y1491451D01*
G02X1141921Y1491248I-203J0D01*
G01X1139101D01*
G02X1138898Y1491451I0J203D01*
G01Y1492074D01*
G03X1138848Y1492206I-200J0D01*
G02Y1495118I1664J1456D01*
G03X1138898Y1495250I-150J132D01*
G01Y1497192D01*
G03X1138848Y1497324I-200J0D01*
G02Y1500236I1664J1456D01*
G03X1138898Y1500368I-150J132D01*
G01Y1500989D01*
G02X1139101Y1501192I203J0D01*
G37*
G36*
G01X1159446Y1491450D02*
G02X1159244Y1491248I-202J0D01*
G01X1156424D01*
G02X1156222Y1491451I1J203D01*
G01Y1492072D01*
G03X1156172Y1492204I-200J0D01*
G02Y1495120I1661J1458D01*
G03X1156222Y1495252I-150J132D01*
G01Y1497190D01*
G03X1156172Y1497322I-200J0D01*
G02Y1500238I1661J1458D01*
G03X1156222Y1500370I-150J132D01*
G01Y1500990D01*
G02X1156424Y1501192I202J0D01*
G01X1159244D01*
G02X1159446Y1500989I-1J-203D01*
G01Y1500370D01*
G03X1159496Y1500238I200J0D01*
G02Y1497322I-1661J-1458D01*
G03X1159446Y1497190I150J-132D01*
G01Y1495252D01*
G03X1159496Y1495120I200J0D01*
G02Y1492204I-1661J-1458D01*
G03X1159446Y1492072I150J-132D01*
G01Y1491450D01*
G37*
G36*
G01X1661808D02*
G02X1661606Y1491248I-202J0D01*
G01X1658786D01*
G02X1658584Y1491451I1J203D01*
G01Y1492072D01*
G03X1658534Y1492204I-200J0D01*
G02Y1495120I1661J1458D01*
G03X1658584Y1495252I-150J132D01*
G01Y1497190D01*
G03X1658534Y1497322I-200J0D01*
G02Y1500238I1661J1458D01*
G03X1658584Y1500370I-150J132D01*
G01Y1500990D01*
G02X1658786Y1501192I202J0D01*
G01X1661606D01*
G02X1661808Y1500989I-1J-203D01*
G01Y1500370D01*
G03X1661858Y1500238I200J0D01*
G02Y1497322I-1661J-1458D01*
G03X1661808Y1497190I150J-132D01*
G01Y1495252D01*
G03X1661858Y1495120I200J0D01*
G02Y1492204I-1661J-1458D01*
G03X1661808Y1492072I150J-132D01*
G01Y1491450D01*
G37*
G36*
G01X1676109Y1501192D02*
X1678929D01*
G02X1679132Y1500989I0J-203D01*
G01Y1500368D01*
G03X1679182Y1500236I200J0D01*
G02Y1497324I-1664J-1456D01*
G03X1679132Y1497192I150J-132D01*
G01Y1495250D01*
G03X1679182Y1495118I200J0D01*
G02Y1492206I-1664J-1456D01*
G03X1679132Y1492074I150J-132D01*
G01Y1491451D01*
G02X1678929Y1491248I-203J0D01*
G01X1676109D01*
G02X1675906Y1491451I0J203D01*
G01Y1492074D01*
G03X1675856Y1492206I-200J0D01*
G02Y1495118I1664J1456D01*
G03X1675906Y1495250I-150J132D01*
G01Y1497192D01*
G03X1675856Y1497324I-200J0D01*
G02Y1500236I1664J1456D01*
G03X1675906Y1500368I-150J132D01*
G01Y1500989D01*
G02X1676109Y1501192I203J0D01*
G37*
G36*
G01X108472Y1512216D02*
X111292D01*
G02X111494Y1512014I0J-202D01*
G01Y1511394D01*
G03X111544Y1511262I200J0D01*
G02Y1508346I-1661J-1458D01*
G03X111494Y1508214I150J-132D01*
G01Y1506275D01*
G03X111544Y1506143I200J0D01*
G02Y1503227I-1661J-1458D01*
G03X111494Y1503095I150J-132D01*
G01Y1502476D01*
G02X111292Y1502274I-202J0D01*
G01X108472D01*
G02X108270Y1502476I0J202D01*
G01Y1503095D01*
G03X108220Y1503227I-200J0D01*
G02Y1506143I1661J1458D01*
G03X108270Y1506275I-150J132D01*
G01Y1508214D01*
G03X108220Y1508346I-200J0D01*
G02Y1511262I1661J1458D01*
G03X108270Y1511394I-150J132D01*
G01Y1512014D01*
G02X108472Y1512216I202J0D01*
G37*
G36*
G01X316346D02*
X319166D01*
G02X319368Y1512014I0J-202D01*
G01Y1511394D01*
G03X319418Y1511262I200J0D01*
G02Y1508346I-1661J-1458D01*
G03X319368Y1508214I150J-132D01*
G01Y1506275D01*
G03X319418Y1506143I200J0D01*
G02Y1503227I-1661J-1458D01*
G03X319368Y1503095I150J-132D01*
G01Y1502476D01*
G02X319166Y1502274I-202J0D01*
G01X316346D01*
G02X316144Y1502476I0J202D01*
G01Y1503095D01*
G03X316094Y1503227I-200J0D01*
G02Y1506143I1661J1458D01*
G03X316144Y1506275I-150J132D01*
G01Y1508214D01*
G03X316094Y1508346I-200J0D01*
G02Y1511262I1661J1458D01*
G03X316144Y1511394I-150J132D01*
G01Y1512014D01*
G02X316346Y1512216I202J0D01*
G37*
G36*
G01X333668D02*
X336488D01*
G02X336690Y1512014I0J-202D01*
G01Y1511394D01*
G03X336740Y1511262I200J0D01*
G02Y1508346I-1661J-1458D01*
G03X336690Y1508214I150J-132D01*
G01Y1506275D01*
G03X336740Y1506143I200J0D01*
G02Y1503227I-1661J-1458D01*
G03X336690Y1503095I150J-132D01*
G01Y1502476D01*
G02X336488Y1502274I-202J0D01*
G01X333668D01*
G02X333466Y1502476I0J202D01*
G01Y1503095D01*
G03X333416Y1503227I-200J0D01*
G02Y1506143I1661J1458D01*
G03X333466Y1506275I-150J132D01*
G01Y1508214D01*
G03X333416Y1508346I-200J0D01*
G02Y1511262I1661J1458D01*
G03X333466Y1511394I-150J132D01*
G01Y1512014D01*
G02X333668Y1512216I202J0D01*
G37*
G36*
G01X1130440D02*
X1133260D01*
G02X1133462Y1512014I0J-202D01*
G01Y1511394D01*
G03X1133512Y1511262I200J0D01*
G02Y1508346I-1661J-1458D01*
G03X1133462Y1508214I150J-132D01*
G01Y1506275D01*
G03X1133512Y1506143I200J0D01*
G02Y1503227I-1661J-1458D01*
G03X1133462Y1503095I150J-132D01*
G01Y1502476D01*
G02X1133260Y1502274I-202J0D01*
G01X1130440D01*
G02X1130238Y1502476I0J202D01*
G01Y1503095D01*
G03X1130188Y1503227I-200J0D01*
G02Y1506143I1661J1458D01*
G03X1130238Y1506275I-150J132D01*
G01Y1508214D01*
G03X1130188Y1508346I-200J0D01*
G02Y1511262I1661J1458D01*
G03X1130238Y1511394I-150J132D01*
G01Y1512014D01*
G02X1130440Y1512216I202J0D01*
G37*
G36*
G01X1667448D02*
X1670268D01*
G02X1670470Y1512014I0J-202D01*
G01Y1511394D01*
G03X1670520Y1511262I200J0D01*
G02Y1508346I-1661J-1458D01*
G03X1670470Y1508214I150J-132D01*
G01Y1506275D01*
G03X1670520Y1506143I200J0D01*
G02Y1503227I-1661J-1458D01*
G03X1670470Y1503095I150J-132D01*
G01Y1502476D01*
G02X1670268Y1502274I-202J0D01*
G01X1667448D01*
G02X1667246Y1502476I0J202D01*
G01Y1503095D01*
G03X1667196Y1503227I-200J0D01*
G02Y1506143I1661J1458D01*
G03X1667246Y1506275I-150J132D01*
G01Y1508214D01*
G03X1667196Y1508346I-200J0D01*
G02Y1511262I1661J1458D01*
G03X1667246Y1511394I-150J132D01*
G01Y1512014D01*
G02X1667448Y1512216I202J0D01*
G37*
G36*
G01X628156Y1502274D02*
G02X627954Y1502476I0J202D01*
G01Y1503097D01*
G03X627904Y1503229I-200J0D01*
G02Y1506141I1664J1456D01*
G03X627954Y1506273I-150J132D01*
G01Y1508216D01*
G03X627904Y1508348I-200J0D01*
G02Y1511260I1664J1456D01*
G03X627954Y1511392I-150J132D01*
G01Y1512014D01*
G02X628157Y1512216I203J-1D01*
G01X630978D01*
G02X631180Y1512014I0J-202D01*
G01Y1511392D01*
G03X631230Y1511260I200J0D01*
G02Y1508348I-1664J-1456D01*
G03X631180Y1508216I150J-132D01*
G01Y1506273D01*
G03X631230Y1506141I200J0D01*
G02Y1503229I-1664J-1456D01*
G03X631180Y1503097I150J-132D01*
G01Y1502476D01*
G02X630977Y1502274I-203J1D01*
G01X628156D01*
G37*
G36*
G01X1147762D02*
G02X1147560Y1502476I0J202D01*
G01Y1503097D01*
G03X1147510Y1503229I-200J0D01*
G02Y1506141I1664J1456D01*
G03X1147560Y1506273I-150J132D01*
G01Y1508216D01*
G03X1147510Y1508348I-200J0D01*
G02Y1511260I1664J1456D01*
G03X1147560Y1511392I-150J132D01*
G01Y1512014D01*
G02X1147763Y1512216I203J-1D01*
G01X1150584D01*
G02X1150786Y1512014I0J-202D01*
G01Y1511392D01*
G03X1150836Y1511260I200J0D01*
G02Y1508348I-1664J-1456D01*
G03X1150786Y1508216I150J-132D01*
G01Y1506273D01*
G03X1150836Y1506141I200J0D01*
G02Y1503229I-1664J-1456D01*
G03X1150786Y1503097I150J-132D01*
G01Y1502476D01*
G02X1150583Y1502274I-203J1D01*
G01X1147762D01*
G37*
G36*
G01X1650124D02*
G02X1649922Y1502476I0J202D01*
G01Y1503097D01*
G03X1649872Y1503229I-200J0D01*
G02Y1506141I1664J1456D01*
G03X1649922Y1506273I-150J132D01*
G01Y1508216D01*
G03X1649872Y1508348I-200J0D01*
G02Y1511260I1664J1456D01*
G03X1649922Y1511392I-150J132D01*
G01Y1512014D01*
G02X1650125Y1512216I203J-1D01*
G01X1652946D01*
G02X1653148Y1512014I0J-202D01*
G01Y1511392D01*
G03X1653198Y1511260I200J0D01*
G02Y1508348I-1664J-1456D01*
G03X1653148Y1508216I150J-132D01*
G01Y1506273D01*
G03X1653198Y1506141I200J0D01*
G02Y1503229I-1664J-1456D01*
G03X1653148Y1503097I150J-132D01*
G01Y1502476D01*
G02X1652945Y1502274I-203J1D01*
G01X1650124D01*
G37*
G36*
G01X307684Y1516546D02*
X310504D01*
G02X310706Y1516344I0J-202D01*
G01Y1515724D01*
G03X310756Y1515592I200J0D01*
G02Y1512676I-1661J-1458D01*
G03X310706Y1512544I150J-132D01*
G01Y1510606D01*
G03X310756Y1510474I200J0D01*
G02Y1507558I-1661J-1458D01*
G03X310706Y1507426I150J-132D01*
G01Y1506806D01*
G02X310504Y1506604I-202J0D01*
G01X307684D01*
G02X307482Y1506806I0J202D01*
G01Y1507426D01*
G03X307432Y1507558I-200J0D01*
G02Y1510474I1661J1458D01*
G03X307482Y1510606I-150J132D01*
G01Y1512544D01*
G03X307432Y1512676I-200J0D01*
G02Y1515592I1661J1458D01*
G03X307482Y1515724I-150J132D01*
G01Y1516344D01*
G02X307684Y1516546I202J0D01*
G37*
G36*
G01X342330D02*
X345150D01*
G02X345352Y1516344I0J-202D01*
G01Y1515724D01*
G03X345402Y1515592I200J0D01*
G02Y1512676I-1661J-1458D01*
G03X345352Y1512544I150J-132D01*
G01Y1510606D01*
G03X345402Y1510474I200J0D01*
G02Y1507558I-1661J-1458D01*
G03X345352Y1507426I150J-132D01*
G01Y1506806D01*
G02X345150Y1506604I-202J0D01*
G01X342330D01*
G02X342128Y1506806I0J202D01*
G01Y1507426D01*
G03X342078Y1507558I-200J0D01*
G02Y1510474I1661J1458D01*
G03X342128Y1510606I-150J132D01*
G01Y1512544D01*
G03X342078Y1512676I-200J0D01*
G02Y1515592I1661J1458D01*
G03X342128Y1515724I-150J132D01*
G01Y1516344D01*
G02X342330Y1516546I202J0D01*
G37*
G36*
G01X636818D02*
X639638D01*
G02X639840Y1516344I0J-202D01*
G01Y1515724D01*
G03X639890Y1515592I200J0D01*
G02Y1512676I-1661J-1458D01*
G03X639840Y1512544I150J-132D01*
G01Y1510606D01*
G03X639890Y1510474I200J0D01*
G02Y1507558I-1661J-1458D01*
G03X639840Y1507426I150J-132D01*
G01Y1506806D01*
G02X639638Y1506604I-202J0D01*
G01X636818D01*
G02X636616Y1506806I0J202D01*
G01Y1507426D01*
G03X636566Y1507558I-200J0D01*
G02Y1510474I1661J1458D01*
G03X636616Y1510606I-150J132D01*
G01Y1512544D01*
G03X636566Y1512676I-200J0D01*
G02Y1515592I1661J1458D01*
G03X636616Y1515724I-150J132D01*
G01Y1516344D01*
G02X636818Y1516546I202J0D01*
G37*
G36*
G01X1156424D02*
X1159244D01*
G02X1159446Y1516344I0J-202D01*
G01Y1515724D01*
G03X1159496Y1515592I200J0D01*
G02Y1512676I-1661J-1458D01*
G03X1159446Y1512544I150J-132D01*
G01Y1510606D01*
G03X1159496Y1510474I200J0D01*
G02Y1507558I-1661J-1458D01*
G03X1159446Y1507426I150J-132D01*
G01Y1506806D01*
G02X1159244Y1506604I-202J0D01*
G01X1156424D01*
G02X1156222Y1506806I0J202D01*
G01Y1507426D01*
G03X1156172Y1507558I-200J0D01*
G02Y1510474I1661J1458D01*
G03X1156222Y1510606I-150J132D01*
G01Y1512544D01*
G03X1156172Y1512676I-200J0D01*
G02Y1515592I1661J1458D01*
G03X1156222Y1515724I-150J132D01*
G01Y1516344D01*
G02X1156424Y1516546I202J0D01*
G37*
G36*
G01X1658786D02*
X1661606D01*
G02X1661808Y1516344I0J-202D01*
G01Y1515724D01*
G03X1661858Y1515592I200J0D01*
G02Y1512676I-1661J-1458D01*
G03X1661808Y1512544I150J-132D01*
G01Y1510606D01*
G03X1661858Y1510474I200J0D01*
G02Y1507558I-1661J-1458D01*
G03X1661808Y1507426I150J-132D01*
G01Y1506806D01*
G02X1661606Y1506604I-202J0D01*
G01X1658786D01*
G02X1658584Y1506806I0J202D01*
G01Y1507426D01*
G03X1658534Y1507558I-200J0D01*
G02Y1510474I1661J1458D01*
G03X1658584Y1510606I-150J132D01*
G01Y1512544D01*
G03X1658534Y1512676I-200J0D01*
G02Y1515592I1661J1458D01*
G03X1658584Y1515724I-150J132D01*
G01Y1516344D01*
G02X1658786Y1516546I202J0D01*
G37*
G36*
G01X117132Y1506604D02*
G02X116930Y1506806I0J202D01*
G01Y1507428D01*
G03X116880Y1507560I-200J0D01*
G02Y1510472I1664J1456D01*
G03X116930Y1510604I-150J132D01*
G01Y1512546D01*
G03X116880Y1512678I-200J0D01*
G02Y1515590I1664J1456D01*
G03X116930Y1515722I-150J132D01*
G01Y1516344D01*
G02X117133Y1516546I203J-1D01*
G01X119954D01*
G02X120156Y1516344I0J-202D01*
G01Y1515722D01*
G03X120206Y1515590I200J0D01*
G02Y1512678I-1664J-1456D01*
G03X120156Y1512546I150J-132D01*
G01Y1510604D01*
G03X120206Y1510472I200J0D01*
G02Y1507560I-1664J-1456D01*
G03X120156Y1507428I150J-132D01*
G01Y1506806D01*
G02X119953Y1506604I-203J1D01*
G01X117132D01*
G37*
G36*
G01X325006D02*
G02X324804Y1506806I0J202D01*
G01Y1507428D01*
G03X324754Y1507560I-200J0D01*
G02Y1510472I1664J1456D01*
G03X324804Y1510604I-150J132D01*
G01Y1512546D01*
G03X324754Y1512678I-200J0D01*
G02Y1515590I1664J1456D01*
G03X324804Y1515722I-150J132D01*
G01Y1516344D01*
G02X325007Y1516546I203J-1D01*
G01X327828D01*
G02X328030Y1516344I0J-202D01*
G01Y1515722D01*
G03X328080Y1515590I200J0D01*
G02Y1512678I-1664J-1456D01*
G03X328030Y1512546I150J-132D01*
G01Y1510604D01*
G03X328080Y1510472I200J0D01*
G02Y1507560I-1664J-1456D01*
G03X328030Y1507428I150J-132D01*
G01Y1506806D01*
G02X327827Y1506604I-203J1D01*
G01X325006D01*
G37*
G36*
G01X1139100D02*
G02X1138898Y1506806I0J202D01*
G01Y1507428D01*
G03X1138848Y1507560I-200J0D01*
G02Y1510472I1664J1456D01*
G03X1138898Y1510604I-150J132D01*
G01Y1512546D01*
G03X1138848Y1512678I-200J0D01*
G02Y1515590I1664J1456D01*
G03X1138898Y1515722I-150J132D01*
G01Y1516344D01*
G02X1139101Y1516546I203J-1D01*
G01X1141922D01*
G02X1142124Y1516344I0J-202D01*
G01Y1515722D01*
G03X1142174Y1515590I200J0D01*
G02Y1512678I-1664J-1456D01*
G03X1142124Y1512546I150J-132D01*
G01Y1510604D01*
G03X1142174Y1510472I200J0D01*
G02Y1507560I-1664J-1456D01*
G03X1142124Y1507428I150J-132D01*
G01Y1506806D01*
G02X1141921Y1506604I-203J1D01*
G01X1139100D01*
G37*
G36*
G01X1676108D02*
G02X1675906Y1506806I0J202D01*
G01Y1507428D01*
G03X1675856Y1507560I-200J0D01*
G02Y1510472I1664J1456D01*
G03X1675906Y1510604I-150J132D01*
G01Y1512546D01*
G03X1675856Y1512678I-200J0D01*
G02Y1515590I1664J1456D01*
G03X1675906Y1515722I-150J132D01*
G01Y1516344D01*
G02X1676109Y1516546I203J-1D01*
G01X1678930D01*
G02X1679132Y1516344I0J-202D01*
G01Y1515722D01*
G03X1679182Y1515590I200J0D01*
G02Y1512678I-1664J-1456D01*
G03X1679132Y1512546I150J-132D01*
G01Y1510604D01*
G03X1679182Y1510472I200J0D01*
G02Y1507560I-1664J-1456D01*
G03X1679132Y1507428I150J-132D01*
G01Y1506806D01*
G02X1678929Y1506604I-203J1D01*
G01X1676108D01*
G37*
G36*
G01X454929Y1568516D02*
X457749D01*
G02X457952Y1568313I0J-203D01*
G01Y1567691D01*
G03X458002Y1567559I200J0D01*
G02Y1564647I-1664J-1456D01*
G03X457952Y1564515I150J-132D01*
G01Y1562573D01*
G03X458002Y1562441I200J0D01*
G02Y1559529I-1664J-1456D01*
G03X457952Y1559397I150J-132D01*
G01Y1558775D01*
G02X457749Y1558572I-203J0D01*
G01X454929D01*
G02X454726Y1558775I0J203D01*
G01Y1559397D01*
G03X454676Y1559529I-200J0D01*
G02Y1562441I1664J1456D01*
G03X454726Y1562573I-150J132D01*
G01Y1564515D01*
G03X454676Y1564647I-200J0D01*
G02Y1567559I1664J1456D01*
G03X454726Y1567691I-150J132D01*
G01Y1568313D01*
G02X454929Y1568516I203J0D01*
G37*
G36*
G01X475274Y1558774D02*
G02X475072Y1558572I-202J0D01*
G01X472252D01*
G02X472050Y1558775I1J203D01*
G01Y1559395D01*
G03X472000Y1559527I-200J0D01*
G02Y1562443I1661J1458D01*
G03X472050Y1562575I-150J132D01*
G01Y1564513D01*
G03X472000Y1564645I-200J0D01*
G02Y1567561I1661J1458D01*
G03X472050Y1567693I-150J132D01*
G01Y1568314D01*
G02X472252Y1568516I202J0D01*
G01X475072D01*
G02X475274Y1568313I-1J-203D01*
G01Y1567693D01*
G03X475324Y1567561I200J0D01*
G02Y1564645I-1661J-1458D01*
G03X475274Y1564513I150J-132D01*
G01Y1562575D01*
G03X475324Y1562443I200J0D01*
G02Y1559527I-1661J-1458D01*
G03X475274Y1559395I150J-132D01*
G01Y1558774D01*
G37*
G36*
G01X489575Y1568516D02*
X492395D01*
G02X492598Y1568313I0J-203D01*
G01Y1567691D01*
G03X492648Y1567559I200J0D01*
G02Y1564647I-1664J-1456D01*
G03X492598Y1564515I150J-132D01*
G01Y1562573D01*
G03X492648Y1562441I200J0D01*
G02Y1559529I-1664J-1456D01*
G03X492598Y1559397I150J-132D01*
G01Y1558775D01*
G02X492395Y1558572I-203J0D01*
G01X489575D01*
G02X489372Y1558775I0J203D01*
G01Y1559397D01*
G03X489322Y1559529I-200J0D01*
G02Y1562441I1664J1456D01*
G03X489372Y1562573I-150J132D01*
G01Y1564515D01*
G03X489322Y1564647I-200J0D01*
G02Y1567559I1664J1456D01*
G03X489372Y1567691I-150J132D01*
G01Y1568313D01*
G02X489575Y1568516I203J0D01*
G37*
G36*
G01X506897D02*
X509717D01*
G02X509920Y1568313I0J-203D01*
G01Y1567691D01*
G03X509970Y1567559I200J0D01*
G02Y1564647I-1664J-1456D01*
G03X509920Y1564515I150J-132D01*
G01Y1562573D01*
G03X509970Y1562441I200J0D01*
G02Y1559529I-1664J-1456D01*
G03X509920Y1559397I150J-132D01*
G01Y1558775D01*
G02X509717Y1558572I-203J0D01*
G01X506897D01*
G02X506694Y1558775I0J203D01*
G01Y1559397D01*
G03X506644Y1559529I-200J0D01*
G02Y1562441I1664J1456D01*
G03X506694Y1562573I-150J132D01*
G01Y1564515D01*
G03X506644Y1564647I-200J0D01*
G02Y1567559I1664J1456D01*
G03X506694Y1567691I-150J132D01*
G01Y1568313D01*
G02X506897Y1568516I203J0D01*
G37*
G36*
G01X1497242Y1558774D02*
G02X1497040Y1558572I-202J0D01*
G01X1494220D01*
G02X1494018Y1558775I1J203D01*
G01Y1559395D01*
G03X1493968Y1559527I-200J0D01*
G02Y1562443I1661J1458D01*
G03X1494018Y1562575I-150J132D01*
G01Y1564513D01*
G03X1493968Y1564645I-200J0D01*
G02Y1567561I1661J1458D01*
G03X1494018Y1567693I-150J132D01*
G01Y1568314D01*
G02X1494220Y1568516I202J0D01*
G01X1497040D01*
G02X1497242Y1568313I-1J-203D01*
G01Y1567693D01*
G03X1497292Y1567561I200J0D01*
G02Y1564645I-1661J-1458D01*
G03X1497242Y1564513I150J-132D01*
G01Y1562575D01*
G03X1497292Y1562443I200J0D01*
G02Y1559527I-1661J-1458D01*
G03X1497242Y1559395I150J-132D01*
G01Y1558774D01*
G37*
G36*
G01X1511543Y1568516D02*
X1514363D01*
G02X1514566Y1568313I0J-203D01*
G01Y1567691D01*
G03X1514616Y1567559I200J0D01*
G02Y1564647I-1664J-1456D01*
G03X1514566Y1564515I150J-132D01*
G01Y1562573D01*
G03X1514616Y1562441I200J0D01*
G02Y1559529I-1664J-1456D01*
G03X1514566Y1559397I150J-132D01*
G01Y1558775D01*
G02X1514363Y1558572I-203J0D01*
G01X1511543D01*
G02X1511340Y1558775I0J203D01*
G01Y1559397D01*
G03X1511290Y1559529I-200J0D01*
G02Y1562441I1664J1456D01*
G03X1511340Y1562573I-150J132D01*
G01Y1564515D01*
G03X1511290Y1564647I-200J0D01*
G02Y1567559I1664J1456D01*
G03X1511340Y1567691I-150J132D01*
G01Y1568313D01*
G02X1511543Y1568516I203J0D01*
G37*
G36*
G01X1528865D02*
X1531685D01*
G02X1531888Y1568313I0J-203D01*
G01Y1567691D01*
G03X1531938Y1567559I200J0D01*
G02Y1564647I-1664J-1456D01*
G03X1531888Y1564515I150J-132D01*
G01Y1562573D01*
G03X1531938Y1562441I200J0D01*
G02Y1559529I-1664J-1456D01*
G03X1531888Y1559397I150J-132D01*
G01Y1558775D01*
G02X1531685Y1558572I-203J0D01*
G01X1528865D01*
G02X1528662Y1558775I0J203D01*
G01Y1559397D01*
G03X1528612Y1559529I-200J0D01*
G02Y1562441I1664J1456D01*
G03X1528662Y1562573I-150J132D01*
G01Y1564515D01*
G03X1528612Y1564647I-200J0D01*
G02Y1567559I1664J1456D01*
G03X1528662Y1567691I-150J132D01*
G01Y1568313D01*
G02X1528865Y1568516I203J0D01*
G37*
G36*
G01X463590Y1572846D02*
X466410D01*
G02X466612Y1572644I0J-202D01*
G01Y1572024D01*
G03X466662Y1571892I200J0D01*
G02Y1568976I-1661J-1458D01*
G03X466612Y1568844I150J-132D01*
G01Y1566905D01*
G03X466662Y1566773I200J0D01*
G02Y1563857I-1661J-1458D01*
G03X466612Y1563725I150J-132D01*
G01Y1563106D01*
G02X466410Y1562904I-202J0D01*
G01X463590D01*
G02X463388Y1563106I0J202D01*
G01Y1563725D01*
G03X463338Y1563857I-200J0D01*
G02Y1566773I1661J1458D01*
G03X463388Y1566905I-150J132D01*
G01Y1568844D01*
G03X463338Y1568976I-200J0D01*
G02Y1571892I1661J1458D01*
G03X463388Y1572024I-150J132D01*
G01Y1572644D01*
G02X463590Y1572846I202J0D01*
G37*
G36*
G01X498236D02*
X501056D01*
G02X501258Y1572644I0J-202D01*
G01Y1572024D01*
G03X501308Y1571892I200J0D01*
G02Y1568976I-1661J-1458D01*
G03X501258Y1568844I150J-132D01*
G01Y1566905D01*
G03X501308Y1566773I200J0D01*
G02Y1563857I-1661J-1458D01*
G03X501258Y1563725I150J-132D01*
G01Y1563106D01*
G02X501056Y1562904I-202J0D01*
G01X498236D01*
G02X498034Y1563106I0J202D01*
G01Y1563725D01*
G03X497984Y1563857I-200J0D01*
G02Y1566773I1661J1458D01*
G03X498034Y1566905I-150J132D01*
G01Y1568844D01*
G03X497984Y1568976I-200J0D01*
G02Y1571892I1661J1458D01*
G03X498034Y1572024I-150J132D01*
G01Y1572644D01*
G02X498236Y1572846I202J0D01*
G37*
G36*
G01X1485558D02*
X1488378D01*
G02X1488580Y1572644I0J-202D01*
G01Y1572024D01*
G03X1488630Y1571892I200J0D01*
G02Y1568976I-1661J-1458D01*
G03X1488580Y1568844I150J-132D01*
G01Y1566905D01*
G03X1488630Y1566773I200J0D01*
G02Y1563857I-1661J-1458D01*
G03X1488580Y1563725I150J-132D01*
G01Y1563106D01*
G02X1488378Y1562904I-202J0D01*
G01X1485558D01*
G02X1485356Y1563106I0J202D01*
G01Y1563725D01*
G03X1485306Y1563857I-200J0D01*
G02Y1566773I1661J1458D01*
G03X1485356Y1566905I-150J132D01*
G01Y1568844D01*
G03X1485306Y1568976I-200J0D01*
G02Y1571892I1661J1458D01*
G03X1485356Y1572024I-150J132D01*
G01Y1572644D01*
G02X1485558Y1572846I202J0D01*
G37*
G36*
G01X1520204D02*
X1523024D01*
G02X1523226Y1572644I0J-202D01*
G01Y1572024D01*
G03X1523276Y1571892I200J0D01*
G02Y1568976I-1661J-1458D01*
G03X1523226Y1568844I150J-132D01*
G01Y1566905D01*
G03X1523276Y1566773I200J0D01*
G02Y1563857I-1661J-1458D01*
G03X1523226Y1563725I150J-132D01*
G01Y1563106D01*
G02X1523024Y1562904I-202J0D01*
G01X1520204D01*
G02X1520002Y1563106I0J202D01*
G01Y1563725D01*
G03X1519952Y1563857I-200J0D01*
G02Y1566773I1661J1458D01*
G03X1520002Y1566905I-150J132D01*
G01Y1568844D01*
G03X1519952Y1568976I-200J0D01*
G02Y1571892I1661J1458D01*
G03X1520002Y1572024I-150J132D01*
G01Y1572644D01*
G02X1520204Y1572846I202J0D01*
G37*
G36*
G01X480912Y1562904D02*
G02X480710Y1563106I0J202D01*
G01Y1563727D01*
G03X480660Y1563859I-200J0D01*
G02Y1566771I1664J1456D01*
G03X480710Y1566903I-150J132D01*
G01Y1568846D01*
G03X480660Y1568978I-200J0D01*
G02Y1571890I1664J1456D01*
G03X480710Y1572022I-150J132D01*
G01Y1572644D01*
G02X480913Y1572846I203J-1D01*
G01X483734D01*
G02X483936Y1572644I0J-202D01*
G01Y1572022D01*
G03X483986Y1571890I200J0D01*
G02Y1568978I-1664J-1456D01*
G03X483936Y1568846I150J-132D01*
G01Y1566903D01*
G03X483986Y1566771I200J0D01*
G02Y1563859I-1664J-1456D01*
G03X483936Y1563727I150J-132D01*
G01Y1563106D01*
G02X483733Y1562904I-203J1D01*
G01X480912D01*
G37*
G36*
G01X1502880D02*
G02X1502678Y1563106I0J202D01*
G01Y1563727D01*
G03X1502628Y1563859I-200J0D01*
G02Y1566771I1664J1456D01*
G03X1502678Y1566903I-150J132D01*
G01Y1568846D01*
G03X1502628Y1568978I-200J0D01*
G02Y1571890I1664J1456D01*
G03X1502678Y1572022I-150J132D01*
G01Y1572644D01*
G02X1502881Y1572846I203J-1D01*
G01X1505702D01*
G02X1505904Y1572644I0J-202D01*
G01Y1572022D01*
G03X1505954Y1571890I200J0D01*
G02Y1568978I-1664J-1456D01*
G03X1505904Y1568846I150J-132D01*
G01Y1566903D01*
G03X1505954Y1566771I200J0D01*
G02Y1563859I-1664J-1456D01*
G03X1505904Y1563727I150J-132D01*
G01Y1563106D01*
G02X1505701Y1562904I-203J1D01*
G01X1502880D01*
G37*
G36*
G01X1537526D02*
G02X1537324Y1563106I0J202D01*
G01Y1563727D01*
G03X1537274Y1563859I-200J0D01*
G02Y1566771I1664J1456D01*
G03X1537324Y1566903I-150J132D01*
G01Y1568846D01*
G03X1537274Y1568978I-200J0D01*
G02Y1571890I1664J1456D01*
G03X1537324Y1572022I-150J132D01*
G01Y1572644D01*
G02X1537527Y1572846I203J-1D01*
G01X1540348D01*
G02X1540550Y1572644I0J-202D01*
G01Y1572022D01*
G03X1540600Y1571890I200J0D01*
G02Y1568978I-1664J-1456D01*
G03X1540550Y1568846I150J-132D01*
G01Y1566903D01*
G03X1540600Y1566771I200J0D01*
G02Y1563859I-1664J-1456D01*
G03X1540550Y1563727I150J-132D01*
G01Y1563106D01*
G02X1540347Y1562904I-203J1D01*
G01X1537526D01*
G37*
G36*
G01X454929Y1583870D02*
X457749D01*
G02X457952Y1583667I0J-203D01*
G01Y1583045D01*
G03X458002Y1582913I200J0D01*
G02Y1580001I-1664J-1456D01*
G03X457952Y1579869I150J-132D01*
G01Y1577927D01*
G03X458002Y1577795I200J0D01*
G02Y1574883I-1664J-1456D01*
G03X457952Y1574751I150J-132D01*
G01Y1574129D01*
G02X457749Y1573926I-203J0D01*
G01X454929D01*
G02X454726Y1574129I0J203D01*
G01Y1574751D01*
G03X454676Y1574883I-200J0D01*
G02Y1577795I1664J1456D01*
G03X454726Y1577927I-150J132D01*
G01Y1579869D01*
G03X454676Y1580001I-200J0D01*
G02Y1582913I1664J1456D01*
G03X454726Y1583045I-150J132D01*
G01Y1583667D01*
G02X454929Y1583870I203J0D01*
G37*
G36*
G01X475274Y1574128D02*
G02X475072Y1573926I-202J0D01*
G01X472252D01*
G02X472050Y1574129I1J203D01*
G01Y1574749D01*
G03X472000Y1574881I-200J0D01*
G02Y1577797I1661J1458D01*
G03X472050Y1577929I-150J132D01*
G01Y1579867D01*
G03X472000Y1579999I-200J0D01*
G02Y1582915I1661J1458D01*
G03X472050Y1583047I-150J132D01*
G01Y1583668D01*
G02X472252Y1583870I202J0D01*
G01X475072D01*
G02X475274Y1583667I-1J-203D01*
G01Y1583047D01*
G03X475324Y1582915I200J0D01*
G02Y1579999I-1661J-1458D01*
G03X475274Y1579867I150J-132D01*
G01Y1577929D01*
G03X475324Y1577797I200J0D01*
G02Y1574881I-1661J-1458D01*
G03X475274Y1574749I150J-132D01*
G01Y1574128D01*
G37*
G36*
G01X489575Y1583870D02*
X492395D01*
G02X492598Y1583667I0J-203D01*
G01Y1583045D01*
G03X492648Y1582913I200J0D01*
G02Y1580001I-1664J-1456D01*
G03X492598Y1579869I150J-132D01*
G01Y1577927D01*
G03X492648Y1577795I200J0D01*
G02Y1574883I-1664J-1456D01*
G03X492598Y1574751I150J-132D01*
G01Y1574129D01*
G02X492395Y1573926I-203J0D01*
G01X489575D01*
G02X489372Y1574129I0J203D01*
G01Y1574751D01*
G03X489322Y1574883I-200J0D01*
G02Y1577795I1664J1456D01*
G03X489372Y1577927I-150J132D01*
G01Y1579869D01*
G03X489322Y1580001I-200J0D01*
G02Y1582913I1664J1456D01*
G03X489372Y1583045I-150J132D01*
G01Y1583667D01*
G02X489575Y1583870I203J0D01*
G37*
G36*
G01X506897D02*
X509717D01*
G02X509920Y1583667I0J-203D01*
G01Y1583045D01*
G03X509970Y1582913I200J0D01*
G02Y1580001I-1664J-1456D01*
G03X509920Y1579869I150J-132D01*
G01Y1577927D01*
G03X509970Y1577795I200J0D01*
G02Y1574883I-1664J-1456D01*
G03X509920Y1574751I150J-132D01*
G01Y1574129D01*
G02X509717Y1573926I-203J0D01*
G01X506897D01*
G02X506694Y1574129I0J203D01*
G01Y1574751D01*
G03X506644Y1574883I-200J0D01*
G02Y1577795I1664J1456D01*
G03X506694Y1577927I-150J132D01*
G01Y1579869D01*
G03X506644Y1580001I-200J0D01*
G02Y1582913I1664J1456D01*
G03X506694Y1583045I-150J132D01*
G01Y1583667D01*
G02X506897Y1583870I203J0D01*
G37*
G36*
G01X1497242Y1574128D02*
G02X1497040Y1573926I-202J0D01*
G01X1494220D01*
G02X1494018Y1574129I1J203D01*
G01Y1574749D01*
G03X1493968Y1574881I-200J0D01*
G02Y1577797I1661J1458D01*
G03X1494018Y1577929I-150J132D01*
G01Y1579867D01*
G03X1493968Y1579999I-200J0D01*
G02Y1582915I1661J1458D01*
G03X1494018Y1583047I-150J132D01*
G01Y1583668D01*
G02X1494220Y1583870I202J0D01*
G01X1497040D01*
G02X1497242Y1583667I-1J-203D01*
G01Y1583047D01*
G03X1497292Y1582915I200J0D01*
G02Y1579999I-1661J-1458D01*
G03X1497242Y1579867I150J-132D01*
G01Y1577929D01*
G03X1497292Y1577797I200J0D01*
G02Y1574881I-1661J-1458D01*
G03X1497242Y1574749I150J-132D01*
G01Y1574128D01*
G37*
G36*
G01X1511543Y1583870D02*
X1514363D01*
G02X1514566Y1583667I0J-203D01*
G01Y1583045D01*
G03X1514616Y1582913I200J0D01*
G02Y1580001I-1664J-1456D01*
G03X1514566Y1579869I150J-132D01*
G01Y1577927D01*
G03X1514616Y1577795I200J0D01*
G02Y1574883I-1664J-1456D01*
G03X1514566Y1574751I150J-132D01*
G01Y1574129D01*
G02X1514363Y1573926I-203J0D01*
G01X1511543D01*
G02X1511340Y1574129I0J203D01*
G01Y1574751D01*
G03X1511290Y1574883I-200J0D01*
G02Y1577795I1664J1456D01*
G03X1511340Y1577927I-150J132D01*
G01Y1579869D01*
G03X1511290Y1580001I-200J0D01*
G02Y1582913I1664J1456D01*
G03X1511340Y1583045I-150J132D01*
G01Y1583667D01*
G02X1511543Y1583870I203J0D01*
G37*
G36*
G01X1528865D02*
X1531685D01*
G02X1531888Y1583667I0J-203D01*
G01Y1583045D01*
G03X1531938Y1582913I200J0D01*
G02Y1580001I-1664J-1456D01*
G03X1531888Y1579869I150J-132D01*
G01Y1577927D01*
G03X1531938Y1577795I200J0D01*
G02Y1574883I-1664J-1456D01*
G03X1531888Y1574751I150J-132D01*
G01Y1574129D01*
G02X1531685Y1573926I-203J0D01*
G01X1528865D01*
G02X1528662Y1574129I0J203D01*
G01Y1574751D01*
G03X1528612Y1574883I-200J0D01*
G02Y1577795I1664J1456D01*
G03X1528662Y1577927I-150J132D01*
G01Y1579869D01*
G03X1528612Y1580001I-200J0D01*
G02Y1582913I1664J1456D01*
G03X1528662Y1583045I-150J132D01*
G01Y1583667D01*
G02X1528865Y1583870I203J0D01*
G37*
G36*
G01X463590Y1588200D02*
X466410D01*
G02X466612Y1587998I0J-202D01*
G01Y1587378D01*
G03X466662Y1587246I200J0D01*
G02Y1584330I-1661J-1458D01*
G03X466612Y1584198I150J-132D01*
G01Y1582260D01*
G03X466662Y1582128I200J0D01*
G02Y1579212I-1661J-1458D01*
G03X466612Y1579080I150J-132D01*
G01Y1578460D01*
G02X466410Y1578258I-202J0D01*
G01X463590D01*
G02X463388Y1578460I0J202D01*
G01Y1579080D01*
G03X463338Y1579212I-200J0D01*
G02Y1582128I1661J1458D01*
G03X463388Y1582260I-150J132D01*
G01Y1584198D01*
G03X463338Y1584330I-200J0D01*
G02Y1587246I1661J1458D01*
G03X463388Y1587378I-150J132D01*
G01Y1587998D01*
G02X463590Y1588200I202J0D01*
G37*
G36*
G01X498236D02*
X501056D01*
G02X501258Y1587998I0J-202D01*
G01Y1587378D01*
G03X501308Y1587246I200J0D01*
G02Y1584330I-1661J-1458D01*
G03X501258Y1584198I150J-132D01*
G01Y1582260D01*
G03X501308Y1582128I200J0D01*
G02Y1579212I-1661J-1458D01*
G03X501258Y1579080I150J-132D01*
G01Y1578460D01*
G02X501056Y1578258I-202J0D01*
G01X498236D01*
G02X498034Y1578460I0J202D01*
G01Y1579080D01*
G03X497984Y1579212I-200J0D01*
G02Y1582128I1661J1458D01*
G03X498034Y1582260I-150J132D01*
G01Y1584198D01*
G03X497984Y1584330I-200J0D01*
G02Y1587246I1661J1458D01*
G03X498034Y1587378I-150J132D01*
G01Y1587998D01*
G02X498236Y1588200I202J0D01*
G37*
G36*
G01X1485558D02*
X1488378D01*
G02X1488580Y1587998I0J-202D01*
G01Y1587378D01*
G03X1488630Y1587246I200J0D01*
G02Y1584330I-1661J-1458D01*
G03X1488580Y1584198I150J-132D01*
G01Y1582260D01*
G03X1488630Y1582128I200J0D01*
G02Y1579212I-1661J-1458D01*
G03X1488580Y1579080I150J-132D01*
G01Y1578460D01*
G02X1488378Y1578258I-202J0D01*
G01X1485558D01*
G02X1485356Y1578460I0J202D01*
G01Y1579080D01*
G03X1485306Y1579212I-200J0D01*
G02Y1582128I1661J1458D01*
G03X1485356Y1582260I-150J132D01*
G01Y1584198D01*
G03X1485306Y1584330I-200J0D01*
G02Y1587246I1661J1458D01*
G03X1485356Y1587378I-150J132D01*
G01Y1587998D01*
G02X1485558Y1588200I202J0D01*
G37*
G36*
G01X1520204D02*
X1523024D01*
G02X1523226Y1587998I0J-202D01*
G01Y1587378D01*
G03X1523276Y1587246I200J0D01*
G02Y1584330I-1661J-1458D01*
G03X1523226Y1584198I150J-132D01*
G01Y1582260D01*
G03X1523276Y1582128I200J0D01*
G02Y1579212I-1661J-1458D01*
G03X1523226Y1579080I150J-132D01*
G01Y1578460D01*
G02X1523024Y1578258I-202J0D01*
G01X1520204D01*
G02X1520002Y1578460I0J202D01*
G01Y1579080D01*
G03X1519952Y1579212I-200J0D01*
G02Y1582128I1661J1458D01*
G03X1520002Y1582260I-150J132D01*
G01Y1584198D01*
G03X1519952Y1584330I-200J0D01*
G02Y1587246I1661J1458D01*
G03X1520002Y1587378I-150J132D01*
G01Y1587998D01*
G02X1520204Y1588200I202J0D01*
G37*
G36*
G01X480912Y1578258D02*
G02X480710Y1578460I0J202D01*
G01Y1579082D01*
G03X480660Y1579214I-200J0D01*
G02Y1582126I1664J1456D01*
G03X480710Y1582258I-150J132D01*
G01Y1584200D01*
G03X480660Y1584332I-200J0D01*
G02Y1587244I1664J1456D01*
G03X480710Y1587376I-150J132D01*
G01Y1587998D01*
G02X480913Y1588200I203J-1D01*
G01X483734D01*
G02X483936Y1587998I0J-202D01*
G01Y1587376D01*
G03X483986Y1587244I200J0D01*
G02Y1584332I-1664J-1456D01*
G03X483936Y1584200I150J-132D01*
G01Y1582258D01*
G03X483986Y1582126I200J0D01*
G02Y1579214I-1664J-1456D01*
G03X483936Y1579082I150J-132D01*
G01Y1578460D01*
G02X483733Y1578258I-203J1D01*
G01X480912D01*
G37*
G36*
G01X1502880D02*
G02X1502678Y1578460I0J202D01*
G01Y1579082D01*
G03X1502628Y1579214I-200J0D01*
G02Y1582126I1664J1456D01*
G03X1502678Y1582258I-150J132D01*
G01Y1584200D01*
G03X1502628Y1584332I-200J0D01*
G02Y1587244I1664J1456D01*
G03X1502678Y1587376I-150J132D01*
G01Y1587998D01*
G02X1502881Y1588200I203J-1D01*
G01X1505702D01*
G02X1505904Y1587998I0J-202D01*
G01Y1587376D01*
G03X1505954Y1587244I200J0D01*
G02Y1584332I-1664J-1456D01*
G03X1505904Y1584200I150J-132D01*
G01Y1582258D01*
G03X1505954Y1582126I200J0D01*
G02Y1579214I-1664J-1456D01*
G03X1505904Y1579082I150J-132D01*
G01Y1578460D01*
G02X1505701Y1578258I-203J1D01*
G01X1502880D01*
G37*
G36*
G01X1537526D02*
G02X1537324Y1578460I0J202D01*
G01Y1579082D01*
G03X1537274Y1579214I-200J0D01*
G02Y1582126I1664J1456D01*
G03X1537324Y1582258I-150J132D01*
G01Y1584200D01*
G03X1537274Y1584332I-200J0D01*
G02Y1587244I1664J1456D01*
G03X1537324Y1587376I-150J132D01*
G01Y1587998D01*
G02X1537527Y1588200I203J-1D01*
G01X1540348D01*
G02X1540550Y1587998I0J-202D01*
G01Y1587376D01*
G03X1540600Y1587244I200J0D01*
G02Y1584332I-1664J-1456D01*
G03X1540550Y1584200I150J-132D01*
G01Y1582258D01*
G03X1540600Y1582126I200J0D01*
G02Y1579214I-1664J-1456D01*
G03X1540550Y1579082I150J-132D01*
G01Y1578460D01*
G02X1540347Y1578258I-203J1D01*
G01X1537526D01*
G37*
G36*
G01X454929Y1599224D02*
X457749D01*
G02X457952Y1599021I0J-203D01*
G01Y1598399D01*
G03X458002Y1598267I200J0D01*
G02Y1595355I-1664J-1456D01*
G03X457952Y1595223I150J-132D01*
G01Y1593281D01*
G03X458002Y1593149I200J0D01*
G02Y1590237I-1664J-1456D01*
G03X457952Y1590105I150J-132D01*
G01Y1589483D01*
G02X457749Y1589280I-203J0D01*
G01X454929D01*
G02X454726Y1589483I0J203D01*
G01Y1590105D01*
G03X454676Y1590237I-200J0D01*
G02Y1593149I1664J1456D01*
G03X454726Y1593281I-150J132D01*
G01Y1595223D01*
G03X454676Y1595355I-200J0D01*
G02Y1598267I1664J1456D01*
G03X454726Y1598399I-150J132D01*
G01Y1599021D01*
G02X454929Y1599224I203J0D01*
G37*
G36*
G01X475274Y1589482D02*
G02X475072Y1589280I-202J0D01*
G01X472252D01*
G02X472050Y1589483I1J203D01*
G01Y1590103D01*
G03X472000Y1590235I-200J0D01*
G02Y1593151I1661J1458D01*
G03X472050Y1593283I-150J132D01*
G01Y1595221D01*
G03X472000Y1595353I-200J0D01*
G02Y1598269I1661J1458D01*
G03X472050Y1598401I-150J132D01*
G01Y1599022D01*
G02X472252Y1599224I202J0D01*
G01X475072D01*
G02X475274Y1599021I-1J-203D01*
G01Y1598401D01*
G03X475324Y1598269I200J0D01*
G02Y1595353I-1661J-1458D01*
G03X475274Y1595221I150J-132D01*
G01Y1593283D01*
G03X475324Y1593151I200J0D01*
G02Y1590235I-1661J-1458D01*
G03X475274Y1590103I150J-132D01*
G01Y1589482D01*
G37*
G36*
G01X489575Y1599224D02*
X492395D01*
G02X492598Y1599021I0J-203D01*
G01Y1598399D01*
G03X492648Y1598267I200J0D01*
G02Y1595355I-1664J-1456D01*
G03X492598Y1595223I150J-132D01*
G01Y1593281D01*
G03X492648Y1593149I200J0D01*
G02Y1590237I-1664J-1456D01*
G03X492598Y1590105I150J-132D01*
G01Y1589483D01*
G02X492395Y1589280I-203J0D01*
G01X489575D01*
G02X489372Y1589483I0J203D01*
G01Y1590105D01*
G03X489322Y1590237I-200J0D01*
G02Y1593149I1664J1456D01*
G03X489372Y1593281I-150J132D01*
G01Y1595223D01*
G03X489322Y1595355I-200J0D01*
G02Y1598267I1664J1456D01*
G03X489372Y1598399I-150J132D01*
G01Y1599021D01*
G02X489575Y1599224I203J0D01*
G37*
G36*
G01X506897D02*
X509717D01*
G02X509920Y1599021I0J-203D01*
G01Y1598399D01*
G03X509970Y1598267I200J0D01*
G02Y1595355I-1664J-1456D01*
G03X509920Y1595223I150J-132D01*
G01Y1593281D01*
G03X509970Y1593149I200J0D01*
G02Y1590237I-1664J-1456D01*
G03X509920Y1590105I150J-132D01*
G01Y1589483D01*
G02X509717Y1589280I-203J0D01*
G01X506897D01*
G02X506694Y1589483I0J203D01*
G01Y1590105D01*
G03X506644Y1590237I-200J0D01*
G02Y1593149I1664J1456D01*
G03X506694Y1593281I-150J132D01*
G01Y1595223D01*
G03X506644Y1595355I-200J0D01*
G02Y1598267I1664J1456D01*
G03X506694Y1598399I-150J132D01*
G01Y1599021D01*
G02X506897Y1599224I203J0D01*
G37*
G36*
G01X1497242Y1589482D02*
G02X1497040Y1589280I-202J0D01*
G01X1494220D01*
G02X1494018Y1589483I1J203D01*
G01Y1590103D01*
G03X1493968Y1590235I-200J0D01*
G02Y1593151I1661J1458D01*
G03X1494018Y1593283I-150J132D01*
G01Y1595221D01*
G03X1493968Y1595353I-200J0D01*
G02Y1598269I1661J1458D01*
G03X1494018Y1598401I-150J132D01*
G01Y1599022D01*
G02X1494220Y1599224I202J0D01*
G01X1497040D01*
G02X1497242Y1599021I-1J-203D01*
G01Y1598401D01*
G03X1497292Y1598269I200J0D01*
G02Y1595353I-1661J-1458D01*
G03X1497242Y1595221I150J-132D01*
G01Y1593283D01*
G03X1497292Y1593151I200J0D01*
G02Y1590235I-1661J-1458D01*
G03X1497242Y1590103I150J-132D01*
G01Y1589482D01*
G37*
G36*
G01X1511543Y1599224D02*
X1514363D01*
G02X1514566Y1599021I0J-203D01*
G01Y1598399D01*
G03X1514616Y1598267I200J0D01*
G02Y1595355I-1664J-1456D01*
G03X1514566Y1595223I150J-132D01*
G01Y1593281D01*
G03X1514616Y1593149I200J0D01*
G02Y1590237I-1664J-1456D01*
G03X1514566Y1590105I150J-132D01*
G01Y1589483D01*
G02X1514363Y1589280I-203J0D01*
G01X1511543D01*
G02X1511340Y1589483I0J203D01*
G01Y1590105D01*
G03X1511290Y1590237I-200J0D01*
G02Y1593149I1664J1456D01*
G03X1511340Y1593281I-150J132D01*
G01Y1595223D01*
G03X1511290Y1595355I-200J0D01*
G02Y1598267I1664J1456D01*
G03X1511340Y1598399I-150J132D01*
G01Y1599021D01*
G02X1511543Y1599224I203J0D01*
G37*
G36*
G01X1528865D02*
X1531685D01*
G02X1531888Y1599021I0J-203D01*
G01Y1598399D01*
G03X1531938Y1598267I200J0D01*
G02Y1595355I-1664J-1456D01*
G03X1531888Y1595223I150J-132D01*
G01Y1593281D01*
G03X1531938Y1593149I200J0D01*
G02Y1590237I-1664J-1456D01*
G03X1531888Y1590105I150J-132D01*
G01Y1589483D01*
G02X1531685Y1589280I-203J0D01*
G01X1528865D01*
G02X1528662Y1589483I0J203D01*
G01Y1590105D01*
G03X1528612Y1590237I-200J0D01*
G02Y1593149I1664J1456D01*
G03X1528662Y1593281I-150J132D01*
G01Y1595223D01*
G03X1528612Y1595355I-200J0D01*
G02Y1598267I1664J1456D01*
G03X1528662Y1598399I-150J132D01*
G01Y1599021D01*
G02X1528865Y1599224I203J0D01*
G37*
G36*
G01X463590Y1603554D02*
X466410D01*
G02X466612Y1603352I0J-202D01*
G01Y1602732D01*
G03X466662Y1602600I200J0D01*
G02Y1599684I-1661J-1458D01*
G03X466612Y1599552I150J-132D01*
G01Y1597614D01*
G03X466662Y1597482I200J0D01*
G02Y1594566I-1661J-1458D01*
G03X466612Y1594434I150J-132D01*
G01Y1593814D01*
G02X466410Y1593612I-202J0D01*
G01X463590D01*
G02X463388Y1593814I0J202D01*
G01Y1594434D01*
G03X463338Y1594566I-200J0D01*
G02Y1597482I1661J1458D01*
G03X463388Y1597614I-150J132D01*
G01Y1599552D01*
G03X463338Y1599684I-200J0D01*
G02Y1602600I1661J1458D01*
G03X463388Y1602732I-150J132D01*
G01Y1603352D01*
G02X463590Y1603554I202J0D01*
G37*
G36*
G01X498236D02*
X501056D01*
G02X501258Y1603352I0J-202D01*
G01Y1602732D01*
G03X501308Y1602600I200J0D01*
G02Y1599684I-1661J-1458D01*
G03X501258Y1599552I150J-132D01*
G01Y1597614D01*
G03X501308Y1597482I200J0D01*
G02Y1594566I-1661J-1458D01*
G03X501258Y1594434I150J-132D01*
G01Y1593814D01*
G02X501056Y1593612I-202J0D01*
G01X498236D01*
G02X498034Y1593814I0J202D01*
G01Y1594434D01*
G03X497984Y1594566I-200J0D01*
G02Y1597482I1661J1458D01*
G03X498034Y1597614I-150J132D01*
G01Y1599552D01*
G03X497984Y1599684I-200J0D01*
G02Y1602600I1661J1458D01*
G03X498034Y1602732I-150J132D01*
G01Y1603352D01*
G02X498236Y1603554I202J0D01*
G37*
G36*
G01X1485558D02*
X1488378D01*
G02X1488580Y1603352I0J-202D01*
G01Y1602732D01*
G03X1488630Y1602600I200J0D01*
G02Y1599684I-1661J-1458D01*
G03X1488580Y1599552I150J-132D01*
G01Y1597614D01*
G03X1488630Y1597482I200J0D01*
G02Y1594566I-1661J-1458D01*
G03X1488580Y1594434I150J-132D01*
G01Y1593814D01*
G02X1488378Y1593612I-202J0D01*
G01X1485558D01*
G02X1485356Y1593814I0J202D01*
G01Y1594434D01*
G03X1485306Y1594566I-200J0D01*
G02Y1597482I1661J1458D01*
G03X1485356Y1597614I-150J132D01*
G01Y1599552D01*
G03X1485306Y1599684I-200J0D01*
G02Y1602600I1661J1458D01*
G03X1485356Y1602732I-150J132D01*
G01Y1603352D01*
G02X1485558Y1603554I202J0D01*
G37*
G36*
G01X1520204D02*
X1523024D01*
G02X1523226Y1603352I0J-202D01*
G01Y1602732D01*
G03X1523276Y1602600I200J0D01*
G02Y1599684I-1661J-1458D01*
G03X1523226Y1599552I150J-132D01*
G01Y1597614D01*
G03X1523276Y1597482I200J0D01*
G02Y1594566I-1661J-1458D01*
G03X1523226Y1594434I150J-132D01*
G01Y1593814D01*
G02X1523024Y1593612I-202J0D01*
G01X1520204D01*
G02X1520002Y1593814I0J202D01*
G01Y1594434D01*
G03X1519952Y1594566I-200J0D01*
G02Y1597482I1661J1458D01*
G03X1520002Y1597614I-150J132D01*
G01Y1599552D01*
G03X1519952Y1599684I-200J0D01*
G02Y1602600I1661J1458D01*
G03X1520002Y1602732I-150J132D01*
G01Y1603352D01*
G02X1520204Y1603554I202J0D01*
G37*
G36*
G01X480912Y1593612D02*
G02X480710Y1593814I0J202D01*
G01Y1594436D01*
G03X480660Y1594568I-200J0D01*
G02Y1597480I1664J1456D01*
G03X480710Y1597612I-150J132D01*
G01Y1599554D01*
G03X480660Y1599686I-200J0D01*
G02Y1602598I1664J1456D01*
G03X480710Y1602730I-150J132D01*
G01Y1603352D01*
G02X480913Y1603554I203J-1D01*
G01X483734D01*
G02X483936Y1603352I0J-202D01*
G01Y1602730D01*
G03X483986Y1602598I200J0D01*
G02Y1599686I-1664J-1456D01*
G03X483936Y1599554I150J-132D01*
G01Y1597612D01*
G03X483986Y1597480I200J0D01*
G02Y1594568I-1664J-1456D01*
G03X483936Y1594436I150J-132D01*
G01Y1593814D01*
G02X483733Y1593612I-203J1D01*
G01X480912D01*
G37*
G36*
G01X1502880D02*
G02X1502678Y1593814I0J202D01*
G01Y1594436D01*
G03X1502628Y1594568I-200J0D01*
G02Y1597480I1664J1456D01*
G03X1502678Y1597612I-150J132D01*
G01Y1599554D01*
G03X1502628Y1599686I-200J0D01*
G02Y1602598I1664J1456D01*
G03X1502678Y1602730I-150J132D01*
G01Y1603352D01*
G02X1502881Y1603554I203J-1D01*
G01X1505702D01*
G02X1505904Y1603352I0J-202D01*
G01Y1602730D01*
G03X1505954Y1602598I200J0D01*
G02Y1599686I-1664J-1456D01*
G03X1505904Y1599554I150J-132D01*
G01Y1597612D01*
G03X1505954Y1597480I200J0D01*
G02Y1594568I-1664J-1456D01*
G03X1505904Y1594436I150J-132D01*
G01Y1593814D01*
G02X1505701Y1593612I-203J1D01*
G01X1502880D01*
G37*
G36*
G01X1537526D02*
G02X1537324Y1593814I0J202D01*
G01Y1594436D01*
G03X1537274Y1594568I-200J0D01*
G02Y1597480I1664J1456D01*
G03X1537324Y1597612I-150J132D01*
G01Y1599554D01*
G03X1537274Y1599686I-200J0D01*
G02Y1602598I1664J1456D01*
G03X1537324Y1602730I-150J132D01*
G01Y1603352D01*
G02X1537527Y1603554I203J-1D01*
G01X1540348D01*
G02X1540550Y1603352I0J-202D01*
G01Y1602730D01*
G03X1540600Y1602598I200J0D01*
G02Y1599686I-1664J-1456D01*
G03X1540550Y1599554I150J-132D01*
G01Y1597612D01*
G03X1540600Y1597480I200J0D01*
G02Y1594568I-1664J-1456D01*
G03X1540550Y1594436I150J-132D01*
G01Y1593814D01*
G02X1540347Y1593612I-203J1D01*
G01X1537526D01*
G37*
G36*
G01X472252Y1614578D02*
X475072D01*
G02X475274Y1614376I0J-202D01*
G01Y1613756D01*
G03X475324Y1613624I200J0D01*
G02Y1610708I-1661J-1458D01*
G03X475274Y1610576I150J-132D01*
G01Y1608638D01*
G03X475324Y1608506I200J0D01*
G02Y1605590I-1661J-1458D01*
G03X475274Y1605458I150J-132D01*
G01Y1604838D01*
G02X475072Y1604636I-202J0D01*
G01X472252D01*
G02X472050Y1604838I0J202D01*
G01Y1605458D01*
G03X472000Y1605590I-200J0D01*
G02Y1608506I1661J1458D01*
G03X472050Y1608638I-150J132D01*
G01Y1610576D01*
G03X472000Y1610708I-200J0D01*
G02Y1613624I1661J1458D01*
G03X472050Y1613756I-150J132D01*
G01Y1614376D01*
G02X472252Y1614578I202J0D01*
G37*
G36*
G01X1494220D02*
X1497040D01*
G02X1497242Y1614376I0J-202D01*
G01Y1613756D01*
G03X1497292Y1613624I200J0D01*
G02Y1610708I-1661J-1458D01*
G03X1497242Y1610576I150J-132D01*
G01Y1608638D01*
G03X1497292Y1608506I200J0D01*
G02Y1605590I-1661J-1458D01*
G03X1497242Y1605458I150J-132D01*
G01Y1604838D01*
G02X1497040Y1604636I-202J0D01*
G01X1494220D01*
G02X1494018Y1604838I0J202D01*
G01Y1605458D01*
G03X1493968Y1605590I-200J0D01*
G02Y1608506I1661J1458D01*
G03X1494018Y1608638I-150J132D01*
G01Y1610576D01*
G03X1493968Y1610708I-200J0D01*
G02Y1613624I1661J1458D01*
G03X1494018Y1613756I-150J132D01*
G01Y1614376D01*
G02X1494220Y1614578I202J0D01*
G37*
G36*
G01X454928Y1604636D02*
G02X454726Y1604838I0J202D01*
G01Y1605460D01*
G03X454676Y1605592I-200J0D01*
G02Y1608504I1664J1456D01*
G03X454726Y1608636I-150J132D01*
G01Y1610578D01*
G03X454676Y1610710I-200J0D01*
G02Y1613622I1664J1456D01*
G03X454726Y1613754I-150J132D01*
G01Y1614376D01*
G02X454929Y1614578I203J-1D01*
G01X457750D01*
G02X457952Y1614376I0J-202D01*
G01Y1613754D01*
G03X458002Y1613622I200J0D01*
G02Y1610710I-1664J-1456D01*
G03X457952Y1610578I150J-132D01*
G01Y1608636D01*
G03X458002Y1608504I200J0D01*
G02Y1605592I-1664J-1456D01*
G03X457952Y1605460I150J-132D01*
G01Y1604838D01*
G02X457749Y1604636I-203J1D01*
G01X454928D01*
G37*
G36*
G01X489574D02*
G02X489372Y1604838I0J202D01*
G01Y1605460D01*
G03X489322Y1605592I-200J0D01*
G02Y1608504I1664J1456D01*
G03X489372Y1608636I-150J132D01*
G01Y1610578D01*
G03X489322Y1610710I-200J0D01*
G02Y1613622I1664J1456D01*
G03X489372Y1613754I-150J132D01*
G01Y1614376D01*
G02X489575Y1614578I203J-1D01*
G01X492396D01*
G02X492598Y1614376I0J-202D01*
G01Y1613754D01*
G03X492648Y1613622I200J0D01*
G02Y1610710I-1664J-1456D01*
G03X492598Y1610578I150J-132D01*
G01Y1608636D01*
G03X492648Y1608504I200J0D01*
G02Y1605592I-1664J-1456D01*
G03X492598Y1605460I150J-132D01*
G01Y1604838D01*
G02X492395Y1604636I-203J1D01*
G01X489574D01*
G37*
G36*
G01X506896D02*
G02X506694Y1604838I0J202D01*
G01Y1605460D01*
G03X506644Y1605592I-200J0D01*
G02Y1608504I1664J1456D01*
G03X506694Y1608636I-150J132D01*
G01Y1610578D01*
G03X506644Y1610710I-200J0D01*
G02Y1613622I1664J1456D01*
G03X506694Y1613754I-150J132D01*
G01Y1614376D01*
G02X506897Y1614578I203J-1D01*
G01X509718D01*
G02X509920Y1614376I0J-202D01*
G01Y1613754D01*
G03X509970Y1613622I200J0D01*
G02Y1610710I-1664J-1456D01*
G03X509920Y1610578I150J-132D01*
G01Y1608636D01*
G03X509970Y1608504I200J0D01*
G02Y1605592I-1664J-1456D01*
G03X509920Y1605460I150J-132D01*
G01Y1604838D01*
G02X509717Y1604636I-203J1D01*
G01X506896D01*
G37*
G36*
G01X1511542D02*
G02X1511340Y1604838I0J202D01*
G01Y1605460D01*
G03X1511290Y1605592I-200J0D01*
G02Y1608504I1664J1456D01*
G03X1511340Y1608636I-150J132D01*
G01Y1610578D01*
G03X1511290Y1610710I-200J0D01*
G02Y1613622I1664J1456D01*
G03X1511340Y1613754I-150J132D01*
G01Y1614376D01*
G02X1511543Y1614578I203J-1D01*
G01X1514364D01*
G02X1514566Y1614376I0J-202D01*
G01Y1613754D01*
G03X1514616Y1613622I200J0D01*
G02Y1610710I-1664J-1456D01*
G03X1514566Y1610578I150J-132D01*
G01Y1608636D01*
G03X1514616Y1608504I200J0D01*
G02Y1605592I-1664J-1456D01*
G03X1514566Y1605460I150J-132D01*
G01Y1604838D01*
G02X1514363Y1604636I-203J1D01*
G01X1511542D01*
G37*
G36*
G01X1528864D02*
G02X1528662Y1604838I0J202D01*
G01Y1605460D01*
G03X1528612Y1605592I-200J0D01*
G02Y1608504I1664J1456D01*
G03X1528662Y1608636I-150J132D01*
G01Y1610578D01*
G03X1528612Y1610710I-200J0D01*
G02Y1613622I1664J1456D01*
G03X1528662Y1613754I-150J132D01*
G01Y1614376D01*
G02X1528865Y1614578I203J-1D01*
G01X1531686D01*
G02X1531888Y1614376I0J-202D01*
G01Y1613754D01*
G03X1531938Y1613622I200J0D01*
G02Y1610710I-1664J-1456D01*
G03X1531888Y1610578I150J-132D01*
G01Y1608636D01*
G03X1531938Y1608504I200J0D01*
G02Y1605592I-1664J-1456D01*
G03X1531888Y1605460I150J-132D01*
G01Y1604838D01*
G02X1531685Y1604636I-203J1D01*
G01X1528864D01*
G37*
G36*
G01X463590Y1618908D02*
X466410D01*
G02X466612Y1618706I0J-202D01*
G01Y1618086D01*
G03X466662Y1617954I200J0D01*
G02Y1615038I-1661J-1458D01*
G03X466612Y1614906I150J-132D01*
G01Y1612968D01*
G03X466662Y1612836I200J0D01*
G02Y1609920I-1661J-1458D01*
G03X466612Y1609788I150J-132D01*
G01Y1609168D01*
G02X466410Y1608966I-202J0D01*
G01X463590D01*
G02X463388Y1609168I0J202D01*
G01Y1609788D01*
G03X463338Y1609920I-200J0D01*
G02Y1612836I1661J1458D01*
G03X463388Y1612968I-150J132D01*
G01Y1614906D01*
G03X463338Y1615038I-200J0D01*
G02Y1617954I1661J1458D01*
G03X463388Y1618086I-150J132D01*
G01Y1618706D01*
G02X463590Y1618908I202J0D01*
G37*
G36*
G01X498236D02*
X501056D01*
G02X501258Y1618706I0J-202D01*
G01Y1618086D01*
G03X501308Y1617954I200J0D01*
G02Y1615038I-1661J-1458D01*
G03X501258Y1614906I150J-132D01*
G01Y1612968D01*
G03X501308Y1612836I200J0D01*
G02Y1609920I-1661J-1458D01*
G03X501258Y1609788I150J-132D01*
G01Y1609168D01*
G02X501056Y1608966I-202J0D01*
G01X498236D01*
G02X498034Y1609168I0J202D01*
G01Y1609788D01*
G03X497984Y1609920I-200J0D01*
G02Y1612836I1661J1458D01*
G03X498034Y1612968I-150J132D01*
G01Y1614906D01*
G03X497984Y1615038I-200J0D01*
G02Y1617954I1661J1458D01*
G03X498034Y1618086I-150J132D01*
G01Y1618706D01*
G02X498236Y1618908I202J0D01*
G37*
G36*
G01X1485558D02*
X1488378D01*
G02X1488580Y1618706I0J-202D01*
G01Y1618086D01*
G03X1488630Y1617954I200J0D01*
G02Y1615038I-1661J-1458D01*
G03X1488580Y1614906I150J-132D01*
G01Y1612968D01*
G03X1488630Y1612836I200J0D01*
G02Y1609920I-1661J-1458D01*
G03X1488580Y1609788I150J-132D01*
G01Y1609168D01*
G02X1488378Y1608966I-202J0D01*
G01X1485558D01*
G02X1485356Y1609168I0J202D01*
G01Y1609788D01*
G03X1485306Y1609920I-200J0D01*
G02Y1612836I1661J1458D01*
G03X1485356Y1612968I-150J132D01*
G01Y1614906D01*
G03X1485306Y1615038I-200J0D01*
G02Y1617954I1661J1458D01*
G03X1485356Y1618086I-150J132D01*
G01Y1618706D01*
G02X1485558Y1618908I202J0D01*
G37*
G36*
G01X1520204D02*
X1523024D01*
G02X1523226Y1618706I0J-202D01*
G01Y1618086D01*
G03X1523276Y1617954I200J0D01*
G02Y1615038I-1661J-1458D01*
G03X1523226Y1614906I150J-132D01*
G01Y1612968D01*
G03X1523276Y1612836I200J0D01*
G02Y1609920I-1661J-1458D01*
G03X1523226Y1609788I150J-132D01*
G01Y1609168D01*
G02X1523024Y1608966I-202J0D01*
G01X1520204D01*
G02X1520002Y1609168I0J202D01*
G01Y1609788D01*
G03X1519952Y1609920I-200J0D01*
G02Y1612836I1661J1458D01*
G03X1520002Y1612968I-150J132D01*
G01Y1614906D01*
G03X1519952Y1615038I-200J0D01*
G02Y1617954I1661J1458D01*
G03X1520002Y1618086I-150J132D01*
G01Y1618706D01*
G02X1520204Y1618908I202J0D01*
G37*
G36*
G01X480912Y1608966D02*
G02X480710Y1609168I0J202D01*
G01Y1609790D01*
G03X480660Y1609922I-200J0D01*
G02Y1612834I1664J1456D01*
G03X480710Y1612966I-150J132D01*
G01Y1614908D01*
G03X480660Y1615040I-200J0D01*
G02Y1617952I1664J1456D01*
G03X480710Y1618084I-150J132D01*
G01Y1618706D01*
G02X480913Y1618908I203J-1D01*
G01X483734D01*
G02X483936Y1618706I0J-202D01*
G01Y1618084D01*
G03X483986Y1617952I200J0D01*
G02Y1615040I-1664J-1456D01*
G03X483936Y1614908I150J-132D01*
G01Y1612966D01*
G03X483986Y1612834I200J0D01*
G02Y1609922I-1664J-1456D01*
G03X483936Y1609790I150J-132D01*
G01Y1609168D01*
G02X483733Y1608966I-203J1D01*
G01X480912D01*
G37*
G36*
G01X1502880D02*
G02X1502678Y1609168I0J202D01*
G01Y1609790D01*
G03X1502628Y1609922I-200J0D01*
G02Y1612834I1664J1456D01*
G03X1502678Y1612966I-150J132D01*
G01Y1614908D01*
G03X1502628Y1615040I-200J0D01*
G02Y1617952I1664J1456D01*
G03X1502678Y1618084I-150J132D01*
G01Y1618706D01*
G02X1502881Y1618908I203J-1D01*
G01X1505702D01*
G02X1505904Y1618706I0J-202D01*
G01Y1618084D01*
G03X1505954Y1617952I200J0D01*
G02Y1615040I-1664J-1456D01*
G03X1505904Y1614908I150J-132D01*
G01Y1612966D01*
G03X1505954Y1612834I200J0D01*
G02Y1609922I-1664J-1456D01*
G03X1505904Y1609790I150J-132D01*
G01Y1609168D01*
G02X1505701Y1608966I-203J1D01*
G01X1502880D01*
G37*
G36*
G01X1537526D02*
G02X1537324Y1609168I0J202D01*
G01Y1609790D01*
G03X1537274Y1609922I-200J0D01*
G02Y1612834I1664J1456D01*
G03X1537324Y1612966I-150J132D01*
G01Y1614908D01*
G03X1537274Y1615040I-200J0D01*
G02Y1617952I1664J1456D01*
G03X1537324Y1618084I-150J132D01*
G01Y1618706D01*
G02X1537527Y1618908I203J-1D01*
G01X1540348D01*
G02X1540550Y1618706I0J-202D01*
G01Y1618084D01*
G03X1540600Y1617952I200J0D01*
G02Y1615040I-1664J-1456D01*
G03X1540550Y1614908I150J-132D01*
G01Y1612966D01*
G03X1540600Y1612834I200J0D01*
G02Y1609922I-1664J-1456D01*
G03X1540550Y1609790I150J-132D01*
G01Y1609168D01*
G02X1540347Y1608966I-203J1D01*
G01X1537526D01*
G37*
G36*
G01X125795Y1466154D02*
X128615D01*
G02X128818Y1465951I0J-203D01*
G01Y1465329D01*
G03X128868Y1465197I200J0D01*
G02Y1462285I-1664J-1456D01*
G03X128818Y1462153I150J-132D01*
G01Y1460210D01*
G03X128868Y1460078I200J0D01*
G02Y1457166I-1664J-1456D01*
G03X128818Y1457034I150J-132D01*
G01Y1456413D01*
G02X128615Y1456210I-203J0D01*
G01X125795D01*
G02X125592Y1456413I0J203D01*
G01Y1457034D01*
G03X125542Y1457166I-200J0D01*
G02Y1460078I1664J1456D01*
G03X125592Y1460210I-150J132D01*
G01Y1462153D01*
G03X125542Y1462285I-200J0D01*
G02Y1465197I1664J1456D01*
G03X125592Y1465329I-150J132D01*
G01Y1465951D01*
G02X125795Y1466154I203J0D01*
G37*
G36*
G01X143118D02*
X145938D01*
G02X146140Y1465951I-1J-203D01*
G01Y1465331D01*
G03X146190Y1465199I200J0D01*
G02Y1462283I-1661J-1458D01*
G03X146140Y1462151I150J-132D01*
G01Y1460212D01*
G03X146190Y1460080I200J0D01*
G02Y1457164I-1661J-1458D01*
G03X146140Y1457032I150J-132D01*
G01Y1456413D01*
G02X145938Y1456210I-202J-1D01*
G01X143118D01*
G02X142916Y1456413I1J203D01*
G01Y1457032D01*
G03X142866Y1457164I-200J0D01*
G02Y1460080I1661J1458D01*
G03X142916Y1460212I-150J132D01*
G01Y1462151D01*
G03X142866Y1462283I-200J0D01*
G02Y1465199I1661J1458D01*
G03X142916Y1465331I-150J132D01*
G01Y1465951D01*
G02X143118Y1466154I202J1D01*
G37*
G36*
G01X160440D02*
X163260D01*
G02X163462Y1465951I-1J-203D01*
G01Y1465331D01*
G03X163512Y1465199I200J0D01*
G02Y1462283I-1661J-1458D01*
G03X163462Y1462151I150J-132D01*
G01Y1460212D01*
G03X163512Y1460080I200J0D01*
G02Y1457164I-1661J-1458D01*
G03X163462Y1457032I150J-132D01*
G01Y1456413D01*
G02X163260Y1456210I-202J-1D01*
G01X160440D01*
G02X160238Y1456413I1J203D01*
G01Y1457032D01*
G03X160188Y1457164I-200J0D01*
G02Y1460080I1661J1458D01*
G03X160238Y1460212I-150J132D01*
G01Y1462151D01*
G03X160188Y1462283I-200J0D01*
G02Y1465199I1661J1458D01*
G03X160238Y1465331I-150J132D01*
G01Y1465951D01*
G02X160440Y1466154I202J1D01*
G37*
G36*
G01X177763D02*
X180583D01*
G02X180786Y1465951I0J-203D01*
G01Y1465329D01*
G03X180836Y1465197I200J0D01*
G02Y1462285I-1664J-1456D01*
G03X180786Y1462153I150J-132D01*
G01Y1460210D01*
G03X180836Y1460078I200J0D01*
G02Y1457166I-1664J-1456D01*
G03X180786Y1457034I150J-132D01*
G01Y1456413D01*
G02X180583Y1456210I-203J0D01*
G01X177763D01*
G02X177560Y1456413I0J203D01*
G01Y1457034D01*
G03X177510Y1457166I-200J0D01*
G02Y1460078I1664J1456D01*
G03X177560Y1460210I-150J132D01*
G01Y1462153D01*
G03X177510Y1462285I-200J0D01*
G02Y1465197I1664J1456D01*
G03X177560Y1465329I-150J132D01*
G01Y1465951D01*
G02X177763Y1466154I203J0D01*
G37*
G36*
G01X281700D02*
X284520D01*
G02X284722Y1465951I-1J-203D01*
G01Y1465331D01*
G03X284772Y1465199I200J0D01*
G02Y1462283I-1661J-1458D01*
G03X284722Y1462151I150J-132D01*
G01Y1460212D01*
G03X284772Y1460080I200J0D01*
G02Y1457164I-1661J-1458D01*
G03X284722Y1457032I150J-132D01*
G01Y1456413D01*
G02X284520Y1456210I-202J-1D01*
G01X281700D01*
G02X281498Y1456413I1J203D01*
G01Y1457032D01*
G03X281448Y1457164I-200J0D01*
G02Y1460080I1661J1458D01*
G03X281498Y1460212I-150J132D01*
G01Y1462151D01*
G03X281448Y1462283I-200J0D01*
G02Y1465199I1661J1458D01*
G03X281498Y1465331I-150J132D01*
G01Y1465951D01*
G02X281700Y1466154I202J1D01*
G37*
G36*
G01X299023D02*
X301843D01*
G02X302046Y1465951I0J-203D01*
G01Y1465329D01*
G03X302096Y1465197I200J0D01*
G02Y1462285I-1664J-1456D01*
G03X302046Y1462153I150J-132D01*
G01Y1460210D01*
G03X302096Y1460078I200J0D01*
G02Y1457166I-1664J-1456D01*
G03X302046Y1457034I150J-132D01*
G01Y1456413D01*
G02X301843Y1456210I-203J0D01*
G01X299023D01*
G02X298820Y1456413I0J203D01*
G01Y1457034D01*
G03X298770Y1457166I-200J0D01*
G02Y1460078I1664J1456D01*
G03X298820Y1460210I-150J132D01*
G01Y1462153D01*
G03X298770Y1462285I-200J0D01*
G02Y1465197I1664J1456D01*
G03X298820Y1465329I-150J132D01*
G01Y1465951D01*
G02X299023Y1466154I203J0D01*
G37*
G36*
G01X454929D02*
X457749D01*
G02X457952Y1465951I0J-203D01*
G01Y1465329D01*
G03X458002Y1465197I200J0D01*
G02Y1462285I-1664J-1456D01*
G03X457952Y1462153I150J-132D01*
G01Y1460210D01*
G03X458002Y1460078I200J0D01*
G02Y1457166I-1664J-1456D01*
G03X457952Y1457034I150J-132D01*
G01Y1456413D01*
G02X457749Y1456210I-203J0D01*
G01X454929D01*
G02X454726Y1456413I0J203D01*
G01Y1457034D01*
G03X454676Y1457166I-200J0D01*
G02Y1460078I1664J1456D01*
G03X454726Y1460210I-150J132D01*
G01Y1462153D01*
G03X454676Y1462285I-200J0D01*
G02Y1465197I1664J1456D01*
G03X454726Y1465329I-150J132D01*
G01Y1465951D01*
G02X454929Y1466154I203J0D01*
G37*
G36*
G01X472252D02*
X475072D01*
G02X475274Y1465951I-1J-203D01*
G01Y1465331D01*
G03X475324Y1465199I200J0D01*
G02Y1462283I-1661J-1458D01*
G03X475274Y1462151I150J-132D01*
G01Y1460212D01*
G03X475324Y1460080I200J0D01*
G02Y1457164I-1661J-1458D01*
G03X475274Y1457032I150J-132D01*
G01Y1456413D01*
G02X475072Y1456210I-202J-1D01*
G01X472252D01*
G02X472050Y1456413I1J203D01*
G01Y1457032D01*
G03X472000Y1457164I-200J0D01*
G02Y1460080I1661J1458D01*
G03X472050Y1460212I-150J132D01*
G01Y1462151D01*
G03X472000Y1462283I-200J0D01*
G02Y1465199I1661J1458D01*
G03X472050Y1465331I-150J132D01*
G01Y1465951D01*
G02X472252Y1466154I202J1D01*
G37*
G36*
G01X489575D02*
X492395D01*
G02X492598Y1465951I0J-203D01*
G01Y1465329D01*
G03X492648Y1465197I200J0D01*
G02Y1462285I-1664J-1456D01*
G03X492598Y1462153I150J-132D01*
G01Y1460210D01*
G03X492648Y1460078I200J0D01*
G02Y1457166I-1664J-1456D01*
G03X492598Y1457034I150J-132D01*
G01Y1456413D01*
G02X492395Y1456210I-203J0D01*
G01X489575D01*
G02X489372Y1456413I0J203D01*
G01Y1457034D01*
G03X489322Y1457166I-200J0D01*
G02Y1460078I1664J1456D01*
G03X489372Y1460210I-150J132D01*
G01Y1462153D01*
G03X489322Y1462285I-200J0D01*
G02Y1465197I1664J1456D01*
G03X489372Y1465329I-150J132D01*
G01Y1465951D01*
G02X489575Y1466154I203J0D01*
G37*
G36*
G01X506897D02*
X509717D01*
G02X509920Y1465951I0J-203D01*
G01Y1465329D01*
G03X509970Y1465197I200J0D01*
G02Y1462285I-1664J-1456D01*
G03X509920Y1462153I150J-132D01*
G01Y1460210D01*
G03X509970Y1460078I200J0D01*
G02Y1457166I-1664J-1456D01*
G03X509920Y1457034I150J-132D01*
G01Y1456413D01*
G02X509717Y1456210I-203J0D01*
G01X506897D01*
G02X506694Y1456413I0J203D01*
G01Y1457034D01*
G03X506644Y1457166I-200J0D01*
G02Y1460078I1664J1456D01*
G03X506694Y1460210I-150J132D01*
G01Y1462153D01*
G03X506644Y1462285I-200J0D01*
G02Y1465197I1664J1456D01*
G03X506694Y1465329I-150J132D01*
G01Y1465951D01*
G02X506897Y1466154I203J0D01*
G37*
G36*
G01X645480D02*
X648300D01*
G02X648502Y1465951I-1J-203D01*
G01Y1465331D01*
G03X648552Y1465199I200J0D01*
G02Y1462283I-1661J-1458D01*
G03X648502Y1462151I150J-132D01*
G01Y1460212D01*
G03X648552Y1460080I200J0D01*
G02Y1457164I-1661J-1458D01*
G03X648502Y1457032I150J-132D01*
G01Y1456413D01*
G02X648300Y1456210I-202J-1D01*
G01X645480D01*
G02X645278Y1456413I1J203D01*
G01Y1457032D01*
G03X645228Y1457164I-200J0D01*
G02Y1460080I1661J1458D01*
G03X645278Y1460212I-150J132D01*
G01Y1462151D01*
G03X645228Y1462283I-200J0D01*
G02Y1465199I1661J1458D01*
G03X645278Y1465331I-150J132D01*
G01Y1465951D01*
G02X645480Y1466154I202J1D01*
G37*
G36*
G01X662803D02*
X665623D01*
G02X665826Y1465951I0J-203D01*
G01Y1465329D01*
G03X665876Y1465197I200J0D01*
G02Y1462285I-1664J-1456D01*
G03X665826Y1462153I150J-132D01*
G01Y1460210D01*
G03X665876Y1460078I200J0D01*
G02Y1457166I-1664J-1456D01*
G03X665826Y1457034I150J-132D01*
G01Y1456413D01*
G02X665623Y1456210I-203J0D01*
G01X662803D01*
G02X662600Y1456413I0J203D01*
G01Y1457034D01*
G03X662550Y1457166I-200J0D01*
G02Y1460078I1664J1456D01*
G03X662600Y1460210I-150J132D01*
G01Y1462153D01*
G03X662550Y1462285I-200J0D01*
G02Y1465197I1664J1456D01*
G03X662600Y1465329I-150J132D01*
G01Y1465951D01*
G02X662803Y1466154I203J0D01*
G37*
G36*
G01X680125D02*
X682945D01*
G02X683148Y1465951I0J-203D01*
G01Y1465329D01*
G03X683198Y1465197I200J0D01*
G02Y1462285I-1664J-1456D01*
G03X683148Y1462153I150J-132D01*
G01Y1460210D01*
G03X683198Y1460078I200J0D01*
G02Y1457166I-1664J-1456D01*
G03X683148Y1457034I150J-132D01*
G01Y1456413D01*
G02X682945Y1456210I-203J0D01*
G01X680125D01*
G02X679922Y1456413I0J203D01*
G01Y1457034D01*
G03X679872Y1457166I-200J0D01*
G02Y1460078I1664J1456D01*
G03X679922Y1460210I-150J132D01*
G01Y1462153D01*
G03X679872Y1462285I-200J0D01*
G02Y1465197I1664J1456D01*
G03X679922Y1465329I-150J132D01*
G01Y1465951D01*
G02X680125Y1466154I203J0D01*
G37*
G36*
G01X1165086D02*
X1167906D01*
G02X1168108Y1465951I-1J-203D01*
G01Y1465331D01*
G03X1168158Y1465199I200J0D01*
G02Y1462283I-1661J-1458D01*
G03X1168108Y1462151I150J-132D01*
G01Y1460212D01*
G03X1168158Y1460080I200J0D01*
G02Y1457164I-1661J-1458D01*
G03X1168108Y1457032I150J-132D01*
G01Y1456413D01*
G02X1167906Y1456210I-202J-1D01*
G01X1165086D01*
G02X1164884Y1456413I1J203D01*
G01Y1457032D01*
G03X1164834Y1457164I-200J0D01*
G02Y1460080I1661J1458D01*
G03X1164884Y1460212I-150J132D01*
G01Y1462151D01*
G03X1164834Y1462283I-200J0D01*
G02Y1465199I1661J1458D01*
G03X1164884Y1465331I-150J132D01*
G01Y1465951D01*
G02X1165086Y1466154I202J1D01*
G37*
G36*
G01X1182408D02*
X1185228D01*
G02X1185430Y1465951I-1J-203D01*
G01Y1465331D01*
G03X1185480Y1465199I200J0D01*
G02Y1462283I-1661J-1458D01*
G03X1185430Y1462151I150J-132D01*
G01Y1460212D01*
G03X1185480Y1460080I200J0D01*
G02Y1457164I-1661J-1458D01*
G03X1185430Y1457032I150J-132D01*
G01Y1456413D01*
G02X1185228Y1456210I-202J-1D01*
G01X1182408D01*
G02X1182206Y1456413I1J203D01*
G01Y1457032D01*
G03X1182156Y1457164I-200J0D01*
G02Y1460080I1661J1458D01*
G03X1182206Y1460212I-150J132D01*
G01Y1462151D01*
G03X1182156Y1462283I-200J0D01*
G02Y1465199I1661J1458D01*
G03X1182206Y1465331I-150J132D01*
G01Y1465951D01*
G02X1182408Y1466154I202J1D01*
G37*
G36*
G01X1303669D02*
X1306489D01*
G02X1306692Y1465951I0J-203D01*
G01Y1465329D01*
G03X1306742Y1465197I200J0D01*
G02Y1462285I-1664J-1456D01*
G03X1306692Y1462153I150J-132D01*
G01Y1460210D01*
G03X1306742Y1460078I200J0D01*
G02Y1457166I-1664J-1456D01*
G03X1306692Y1457034I150J-132D01*
G01Y1456413D01*
G02X1306489Y1456210I-203J0D01*
G01X1303669D01*
G02X1303466Y1456413I0J203D01*
G01Y1457034D01*
G03X1303416Y1457166I-200J0D01*
G02Y1460078I1664J1456D01*
G03X1303466Y1460210I-150J132D01*
G01Y1462153D01*
G03X1303416Y1462285I-200J0D01*
G02Y1465197I1664J1456D01*
G03X1303466Y1465329I-150J132D01*
G01Y1465951D01*
G02X1303669Y1466154I203J0D01*
G37*
G36*
G01X1320992D02*
X1323812D01*
G02X1324014Y1465951I-1J-203D01*
G01Y1465331D01*
G03X1324064Y1465199I200J0D01*
G02Y1462283I-1661J-1458D01*
G03X1324014Y1462151I150J-132D01*
G01Y1460212D01*
G03X1324064Y1460080I200J0D01*
G02Y1457164I-1661J-1458D01*
G03X1324014Y1457032I150J-132D01*
G01Y1456413D01*
G02X1323812Y1456210I-202J-1D01*
G01X1320992D01*
G02X1320790Y1456413I1J203D01*
G01Y1457032D01*
G03X1320740Y1457164I-200J0D01*
G02Y1460080I1661J1458D01*
G03X1320790Y1460212I-150J132D01*
G01Y1462151D01*
G03X1320740Y1462283I-200J0D01*
G02Y1465199I1661J1458D01*
G03X1320790Y1465331I-150J132D01*
G01Y1465951D01*
G02X1320992Y1466154I202J1D01*
G37*
G36*
G01X1338315D02*
X1341135D01*
G02X1341338Y1465951I0J-203D01*
G01Y1465329D01*
G03X1341388Y1465197I200J0D01*
G02Y1462285I-1664J-1456D01*
G03X1341338Y1462153I150J-132D01*
G01Y1460210D01*
G03X1341388Y1460078I200J0D01*
G02Y1457166I-1664J-1456D01*
G03X1341338Y1457034I150J-132D01*
G01Y1456413D01*
G02X1341135Y1456210I-203J0D01*
G01X1338315D01*
G02X1338112Y1456413I0J203D01*
G01Y1457034D01*
G03X1338062Y1457166I-200J0D01*
G02Y1460078I1664J1456D01*
G03X1338112Y1460210I-150J132D01*
G01Y1462153D01*
G03X1338062Y1462285I-200J0D01*
G02Y1465197I1664J1456D01*
G03X1338112Y1465329I-150J132D01*
G01Y1465951D01*
G02X1338315Y1466154I203J0D01*
G37*
G36*
G01X1355637D02*
X1358457D01*
G02X1358660Y1465951I0J-203D01*
G01Y1465329D01*
G03X1358710Y1465197I200J0D01*
G02Y1462285I-1664J-1456D01*
G03X1358660Y1462153I150J-132D01*
G01Y1460210D01*
G03X1358710Y1460078I200J0D01*
G02Y1457166I-1664J-1456D01*
G03X1358660Y1457034I150J-132D01*
G01Y1456413D01*
G02X1358457Y1456210I-203J0D01*
G01X1355637D01*
G02X1355434Y1456413I0J203D01*
G01Y1457034D01*
G03X1355384Y1457166I-200J0D01*
G02Y1460078I1664J1456D01*
G03X1355434Y1460210I-150J132D01*
G01Y1462153D01*
G03X1355384Y1462285I-200J0D01*
G02Y1465197I1664J1456D01*
G03X1355434Y1465329I-150J132D01*
G01Y1465951D01*
G02X1355637Y1466154I203J0D01*
G37*
G36*
G01X1476897D02*
X1479717D01*
G02X1479920Y1465951I0J-203D01*
G01Y1465329D01*
G03X1479970Y1465197I200J0D01*
G02Y1462285I-1664J-1456D01*
G03X1479920Y1462153I150J-132D01*
G01Y1460210D01*
G03X1479970Y1460078I200J0D01*
G02Y1457166I-1664J-1456D01*
G03X1479920Y1457034I150J-132D01*
G01Y1456413D01*
G02X1479717Y1456210I-203J0D01*
G01X1476897D01*
G02X1476694Y1456413I0J203D01*
G01Y1457034D01*
G03X1476644Y1457166I-200J0D01*
G02Y1460078I1664J1456D01*
G03X1476694Y1460210I-150J132D01*
G01Y1462153D01*
G03X1476644Y1462285I-200J0D01*
G02Y1465197I1664J1456D01*
G03X1476694Y1465329I-150J132D01*
G01Y1465951D01*
G02X1476897Y1466154I203J0D01*
G37*
G36*
G01X1494220D02*
X1497040D01*
G02X1497242Y1465951I-1J-203D01*
G01Y1465331D01*
G03X1497292Y1465199I200J0D01*
G02Y1462283I-1661J-1458D01*
G03X1497242Y1462151I150J-132D01*
G01Y1460212D01*
G03X1497292Y1460080I200J0D01*
G02Y1457164I-1661J-1458D01*
G03X1497242Y1457032I150J-132D01*
G01Y1456413D01*
G02X1497040Y1456210I-202J-1D01*
G01X1494220D01*
G02X1494018Y1456413I1J203D01*
G01Y1457032D01*
G03X1493968Y1457164I-200J0D01*
G02Y1460080I1661J1458D01*
G03X1494018Y1460212I-150J132D01*
G01Y1462151D01*
G03X1493968Y1462283I-200J0D01*
G02Y1465199I1661J1458D01*
G03X1494018Y1465331I-150J132D01*
G01Y1465951D01*
G02X1494220Y1466154I202J1D01*
G37*
G36*
G01X1511543D02*
X1514363D01*
G02X1514566Y1465951I0J-203D01*
G01Y1465329D01*
G03X1514616Y1465197I200J0D01*
G02Y1462285I-1664J-1456D01*
G03X1514566Y1462153I150J-132D01*
G01Y1460210D01*
G03X1514616Y1460078I200J0D01*
G02Y1457166I-1664J-1456D01*
G03X1514566Y1457034I150J-132D01*
G01Y1456413D01*
G02X1514363Y1456210I-203J0D01*
G01X1511543D01*
G02X1511340Y1456413I0J203D01*
G01Y1457034D01*
G03X1511290Y1457166I-200J0D01*
G02Y1460078I1664J1456D01*
G03X1511340Y1460210I-150J132D01*
G01Y1462153D01*
G03X1511290Y1462285I-200J0D01*
G02Y1465197I1664J1456D01*
G03X1511340Y1465329I-150J132D01*
G01Y1465951D01*
G02X1511543Y1466154I203J0D01*
G37*
G36*
G01X1528865D02*
X1531685D01*
G02X1531888Y1465951I0J-203D01*
G01Y1465329D01*
G03X1531938Y1465197I200J0D01*
G02Y1462285I-1664J-1456D01*
G03X1531888Y1462153I150J-132D01*
G01Y1460210D01*
G03X1531938Y1460078I200J0D01*
G02Y1457166I-1664J-1456D01*
G03X1531888Y1457034I150J-132D01*
G01Y1456413D01*
G02X1531685Y1456210I-203J0D01*
G01X1528865D01*
G02X1528662Y1456413I0J203D01*
G01Y1457034D01*
G03X1528612Y1457166I-200J0D01*
G02Y1460078I1664J1456D01*
G03X1528662Y1460210I-150J132D01*
G01Y1462153D01*
G03X1528612Y1462285I-200J0D01*
G02Y1465197I1664J1456D01*
G03X1528662Y1465329I-150J132D01*
G01Y1465951D01*
G02X1528865Y1466154I203J0D01*
G37*
G36*
G01X1684771D02*
X1687591D01*
G02X1687794Y1465951I0J-203D01*
G01Y1465329D01*
G03X1687844Y1465197I200J0D01*
G02Y1462285I-1664J-1456D01*
G03X1687794Y1462153I150J-132D01*
G01Y1460210D01*
G03X1687844Y1460078I200J0D01*
G02Y1457166I-1664J-1456D01*
G03X1687794Y1457034I150J-132D01*
G01Y1456413D01*
G02X1687591Y1456210I-203J0D01*
G01X1684771D01*
G02X1684568Y1456413I0J203D01*
G01Y1457034D01*
G03X1684518Y1457166I-200J0D01*
G02Y1460078I1664J1456D01*
G03X1684568Y1460210I-150J132D01*
G01Y1462153D01*
G03X1684518Y1462285I-200J0D01*
G02Y1465197I1664J1456D01*
G03X1684568Y1465329I-150J132D01*
G01Y1465951D01*
G02X1684771Y1466154I203J0D01*
G37*
G36*
G01X1702093D02*
X1704913D01*
G02X1705116Y1465951I0J-203D01*
G01Y1465329D01*
G03X1705166Y1465197I200J0D01*
G02Y1462285I-1664J-1456D01*
G03X1705116Y1462153I150J-132D01*
G01Y1460210D01*
G03X1705166Y1460078I200J0D01*
G02Y1457166I-1664J-1456D01*
G03X1705116Y1457034I150J-132D01*
G01Y1456413D01*
G02X1704913Y1456210I-203J0D01*
G01X1702093D01*
G02X1701890Y1456413I0J203D01*
G01Y1457034D01*
G03X1701840Y1457166I-200J0D01*
G02Y1460078I1664J1456D01*
G03X1701890Y1460210I-150J132D01*
G01Y1462153D01*
G03X1701840Y1462285I-200J0D01*
G02Y1465197I1664J1456D01*
G03X1701890Y1465329I-150J132D01*
G01Y1465951D01*
G02X1702093Y1466154I203J0D01*
G37*
G36*
G01X134456Y1470484D02*
X137276D01*
G02X137478Y1470281I-1J-203D01*
G01Y1469661D01*
G03X137528Y1469529I200J0D01*
G02Y1466613I-1661J-1458D01*
G03X137478Y1466481I150J-132D01*
G01Y1464543D01*
G03X137528Y1464411I200J0D01*
G02Y1461495I-1661J-1458D01*
G03X137478Y1461363I150J-132D01*
G01Y1460743D01*
G02X137276Y1460540I-202J-1D01*
G01X134456D01*
G02X134254Y1460743I1J203D01*
G01Y1461363D01*
G03X134204Y1461495I-200J0D01*
G02Y1464411I1661J1458D01*
G03X134254Y1464543I-150J132D01*
G01Y1466481D01*
G03X134204Y1466613I-200J0D01*
G02Y1469529I1661J1458D01*
G03X134254Y1469661I-150J132D01*
G01Y1470281D01*
G02X134456Y1470484I202J1D01*
G37*
G36*
G01X151779D02*
X154599D01*
G02X154802Y1470281I0J-203D01*
G01Y1469659D01*
G03X154852Y1469527I200J0D01*
G02Y1466615I-1664J-1456D01*
G03X154802Y1466483I150J-132D01*
G01Y1464541D01*
G03X154852Y1464409I200J0D01*
G02Y1461497I-1664J-1456D01*
G03X154802Y1461365I150J-132D01*
G01Y1460743D01*
G02X154599Y1460540I-203J0D01*
G01X151779D01*
G02X151576Y1460743I0J203D01*
G01Y1461365D01*
G03X151526Y1461497I-200J0D01*
G02Y1464409I1664J1456D01*
G03X151576Y1464541I-150J132D01*
G01Y1466483D01*
G03X151526Y1466615I-200J0D01*
G02Y1469527I1664J1456D01*
G03X151576Y1469659I-150J132D01*
G01Y1470281D01*
G02X151779Y1470484I203J0D01*
G37*
G36*
G01X169102D02*
X171922D01*
G02X172124Y1470281I-1J-203D01*
G01Y1469661D01*
G03X172174Y1469529I200J0D01*
G02Y1466613I-1661J-1458D01*
G03X172124Y1466481I150J-132D01*
G01Y1464543D01*
G03X172174Y1464411I200J0D01*
G02Y1461495I-1661J-1458D01*
G03X172124Y1461363I150J-132D01*
G01Y1460743D01*
G02X171922Y1460540I-202J-1D01*
G01X169102D01*
G02X168900Y1460743I1J203D01*
G01Y1461363D01*
G03X168850Y1461495I-200J0D01*
G02Y1464411I1661J1458D01*
G03X168900Y1464543I-150J132D01*
G01Y1466481D01*
G03X168850Y1466613I-200J0D01*
G02Y1469529I1661J1458D01*
G03X168900Y1469661I-150J132D01*
G01Y1470281D01*
G02X169102Y1470484I202J1D01*
G37*
G36*
G01X186425D02*
X189245D01*
G02X189448Y1470281I0J-203D01*
G01Y1469659D01*
G03X189498Y1469527I200J0D01*
G02Y1466615I-1664J-1456D01*
G03X189448Y1466483I150J-132D01*
G01Y1464541D01*
G03X189498Y1464409I200J0D01*
G02Y1461497I-1664J-1456D01*
G03X189448Y1461365I150J-132D01*
G01Y1460743D01*
G02X189245Y1460540I-203J0D01*
G01X186425D01*
G02X186222Y1460743I0J203D01*
G01Y1461365D01*
G03X186172Y1461497I-200J0D01*
G02Y1464409I1664J1456D01*
G03X186222Y1464541I-150J132D01*
G01Y1466483D01*
G03X186172Y1466615I-200J0D01*
G02Y1469527I1664J1456D01*
G03X186222Y1469659I-150J132D01*
G01Y1470281D01*
G02X186425Y1470484I203J0D01*
G37*
G36*
G01X290361D02*
X293181D01*
G02X293384Y1470281I0J-203D01*
G01Y1469659D01*
G03X293434Y1469527I200J0D01*
G02Y1466615I-1664J-1456D01*
G03X293384Y1466483I150J-132D01*
G01Y1464541D01*
G03X293434Y1464409I200J0D01*
G02Y1461497I-1664J-1456D01*
G03X293384Y1461365I150J-132D01*
G01Y1460743D01*
G02X293181Y1460540I-203J0D01*
G01X290361D01*
G02X290158Y1460743I0J203D01*
G01Y1461365D01*
G03X290108Y1461497I-200J0D01*
G02Y1464409I1664J1456D01*
G03X290158Y1464541I-150J132D01*
G01Y1466483D01*
G03X290108Y1466615I-200J0D01*
G02Y1469527I1664J1456D01*
G03X290158Y1469659I-150J132D01*
G01Y1470281D01*
G02X290361Y1470484I203J0D01*
G37*
G36*
G01X463590D02*
X466410D01*
G02X466612Y1470281I-1J-203D01*
G01Y1469661D01*
G03X466662Y1469529I200J0D01*
G02Y1466613I-1661J-1458D01*
G03X466612Y1466481I150J-132D01*
G01Y1464543D01*
G03X466662Y1464411I200J0D01*
G02Y1461495I-1661J-1458D01*
G03X466612Y1461363I150J-132D01*
G01Y1460743D01*
G02X466410Y1460540I-202J-1D01*
G01X463590D01*
G02X463388Y1460743I1J203D01*
G01Y1461363D01*
G03X463338Y1461495I-200J0D01*
G02Y1464411I1661J1458D01*
G03X463388Y1464543I-150J132D01*
G01Y1466481D01*
G03X463338Y1466613I-200J0D01*
G02Y1469529I1661J1458D01*
G03X463388Y1469661I-150J132D01*
G01Y1470281D01*
G02X463590Y1470484I202J1D01*
G37*
G36*
G01X480913D02*
X483733D01*
G02X483936Y1470281I0J-203D01*
G01Y1469659D01*
G03X483986Y1469527I200J0D01*
G02Y1466615I-1664J-1456D01*
G03X483936Y1466483I150J-132D01*
G01Y1464541D01*
G03X483986Y1464409I200J0D01*
G02Y1461497I-1664J-1456D01*
G03X483936Y1461365I150J-132D01*
G01Y1460743D01*
G02X483733Y1460540I-203J0D01*
G01X480913D01*
G02X480710Y1460743I0J203D01*
G01Y1461365D01*
G03X480660Y1461497I-200J0D01*
G02Y1464409I1664J1456D01*
G03X480710Y1464541I-150J132D01*
G01Y1466483D01*
G03X480660Y1466615I-200J0D01*
G02Y1469527I1664J1456D01*
G03X480710Y1469659I-150J132D01*
G01Y1470281D01*
G02X480913Y1470484I203J0D01*
G37*
G36*
G01X498236D02*
X501056D01*
G02X501258Y1470281I-1J-203D01*
G01Y1469661D01*
G03X501308Y1469529I200J0D01*
G02Y1466613I-1661J-1458D01*
G03X501258Y1466481I150J-132D01*
G01Y1464543D01*
G03X501308Y1464411I200J0D01*
G02Y1461495I-1661J-1458D01*
G03X501258Y1461363I150J-132D01*
G01Y1460743D01*
G02X501056Y1460540I-202J-1D01*
G01X498236D01*
G02X498034Y1460743I1J203D01*
G01Y1461363D01*
G03X497984Y1461495I-200J0D01*
G02Y1464411I1661J1458D01*
G03X498034Y1464543I-150J132D01*
G01Y1466481D01*
G03X497984Y1466613I-200J0D01*
G02Y1469529I1661J1458D01*
G03X498034Y1469661I-150J132D01*
G01Y1470281D01*
G02X498236Y1470484I202J1D01*
G37*
G36*
G01X515559D02*
X518379D01*
G02X518582Y1470281I0J-203D01*
G01Y1469659D01*
G03X518632Y1469527I200J0D01*
G02Y1466615I-1664J-1456D01*
G03X518582Y1466483I150J-132D01*
G01Y1464541D01*
G03X518632Y1464409I200J0D01*
G02Y1461497I-1664J-1456D01*
G03X518582Y1461365I150J-132D01*
G01Y1460743D01*
G02X518379Y1460540I-203J0D01*
G01X515559D01*
G02X515356Y1460743I0J203D01*
G01Y1461365D01*
G03X515306Y1461497I-200J0D01*
G02Y1464409I1664J1456D01*
G03X515356Y1464541I-150J132D01*
G01Y1466483D01*
G03X515306Y1466615I-200J0D01*
G02Y1469527I1664J1456D01*
G03X515356Y1469659I-150J132D01*
G01Y1470281D01*
G02X515559Y1470484I203J0D01*
G37*
G36*
G01X654141D02*
X656961D01*
G02X657164Y1470281I0J-203D01*
G01Y1469659D01*
G03X657214Y1469527I200J0D01*
G02Y1466615I-1664J-1456D01*
G03X657164Y1466483I150J-132D01*
G01Y1464541D01*
G03X657214Y1464409I200J0D01*
G02Y1461497I-1664J-1456D01*
G03X657164Y1461365I150J-132D01*
G01Y1460743D01*
G02X656961Y1460540I-203J0D01*
G01X654141D01*
G02X653938Y1460743I0J203D01*
G01Y1461365D01*
G03X653888Y1461497I-200J0D01*
G02Y1464409I1664J1456D01*
G03X653938Y1464541I-150J132D01*
G01Y1466483D01*
G03X653888Y1466615I-200J0D01*
G02Y1469527I1664J1456D01*
G03X653938Y1469659I-150J132D01*
G01Y1470281D01*
G02X654141Y1470484I203J0D01*
G37*
G36*
G01X671464D02*
X674284D01*
G02X674486Y1470281I-1J-203D01*
G01Y1469661D01*
G03X674536Y1469529I200J0D01*
G02Y1466613I-1661J-1458D01*
G03X674486Y1466481I150J-132D01*
G01Y1464543D01*
G03X674536Y1464411I200J0D01*
G02Y1461495I-1661J-1458D01*
G03X674486Y1461363I150J-132D01*
G01Y1460743D01*
G02X674284Y1460540I-202J-1D01*
G01X671464D01*
G02X671262Y1460743I1J203D01*
G01Y1461363D01*
G03X671212Y1461495I-200J0D01*
G02Y1464411I1661J1458D01*
G03X671262Y1464543I-150J132D01*
G01Y1466481D01*
G03X671212Y1466613I-200J0D01*
G02Y1469529I1661J1458D01*
G03X671262Y1469661I-150J132D01*
G01Y1470281D01*
G02X671464Y1470484I202J1D01*
G37*
G36*
G01X688787D02*
X691607D01*
G02X691810Y1470281I0J-203D01*
G01Y1469659D01*
G03X691860Y1469527I200J0D01*
G02Y1466615I-1664J-1456D01*
G03X691810Y1466483I150J-132D01*
G01Y1464541D01*
G03X691860Y1464409I200J0D01*
G02Y1461497I-1664J-1456D01*
G03X691810Y1461365I150J-132D01*
G01Y1460743D01*
G02X691607Y1460540I-203J0D01*
G01X688787D01*
G02X688584Y1460743I0J203D01*
G01Y1461365D01*
G03X688534Y1461497I-200J0D01*
G02Y1464409I1664J1456D01*
G03X688584Y1464541I-150J132D01*
G01Y1466483D01*
G03X688534Y1466615I-200J0D01*
G02Y1469527I1664J1456D01*
G03X688584Y1469659I-150J132D01*
G01Y1470281D01*
G02X688787Y1470484I203J0D01*
G37*
G36*
G01X1173747D02*
X1176567D01*
G02X1176770Y1470281I0J-203D01*
G01Y1469659D01*
G03X1176820Y1469527I200J0D01*
G02Y1466615I-1664J-1456D01*
G03X1176770Y1466483I150J-132D01*
G01Y1464541D01*
G03X1176820Y1464409I200J0D01*
G02Y1461497I-1664J-1456D01*
G03X1176770Y1461365I150J-132D01*
G01Y1460743D01*
G02X1176567Y1460540I-203J0D01*
G01X1173747D01*
G02X1173544Y1460743I0J203D01*
G01Y1461365D01*
G03X1173494Y1461497I-200J0D01*
G02Y1464409I1664J1456D01*
G03X1173544Y1464541I-150J132D01*
G01Y1466483D01*
G03X1173494Y1466615I-200J0D01*
G02Y1469527I1664J1456D01*
G03X1173544Y1469659I-150J132D01*
G01Y1470281D01*
G02X1173747Y1470484I203J0D01*
G37*
G36*
G01X1191070D02*
X1193890D01*
G02X1194092Y1470281I-1J-203D01*
G01Y1469661D01*
G03X1194142Y1469529I200J0D01*
G02Y1466613I-1661J-1458D01*
G03X1194092Y1466481I150J-132D01*
G01Y1464543D01*
G03X1194142Y1464411I200J0D01*
G02Y1461495I-1661J-1458D01*
G03X1194092Y1461363I150J-132D01*
G01Y1460743D01*
G02X1193890Y1460540I-202J-1D01*
G01X1191070D01*
G02X1190868Y1460743I1J203D01*
G01Y1461363D01*
G03X1190818Y1461495I-200J0D01*
G02Y1464411I1661J1458D01*
G03X1190868Y1464543I-150J132D01*
G01Y1466481D01*
G03X1190818Y1466613I-200J0D01*
G02Y1469529I1661J1458D01*
G03X1190868Y1469661I-150J132D01*
G01Y1470281D01*
G02X1191070Y1470484I202J1D01*
G37*
G36*
G01X1312330D02*
X1315150D01*
G02X1315352Y1470281I-1J-203D01*
G01Y1469661D01*
G03X1315402Y1469529I200J0D01*
G02Y1466613I-1661J-1458D01*
G03X1315352Y1466481I150J-132D01*
G01Y1464543D01*
G03X1315402Y1464411I200J0D01*
G02Y1461495I-1661J-1458D01*
G03X1315352Y1461363I150J-132D01*
G01Y1460743D01*
G02X1315150Y1460540I-202J-1D01*
G01X1312330D01*
G02X1312128Y1460743I1J203D01*
G01Y1461363D01*
G03X1312078Y1461495I-200J0D01*
G02Y1464411I1661J1458D01*
G03X1312128Y1464543I-150J132D01*
G01Y1466481D01*
G03X1312078Y1466613I-200J0D01*
G02Y1469529I1661J1458D01*
G03X1312128Y1469661I-150J132D01*
G01Y1470281D01*
G02X1312330Y1470484I202J1D01*
G37*
G36*
G01X1329653D02*
X1332473D01*
G02X1332676Y1470281I0J-203D01*
G01Y1469659D01*
G03X1332726Y1469527I200J0D01*
G02Y1466615I-1664J-1456D01*
G03X1332676Y1466483I150J-132D01*
G01Y1464541D01*
G03X1332726Y1464409I200J0D01*
G02Y1461497I-1664J-1456D01*
G03X1332676Y1461365I150J-132D01*
G01Y1460743D01*
G02X1332473Y1460540I-203J0D01*
G01X1329653D01*
G02X1329450Y1460743I0J203D01*
G01Y1461365D01*
G03X1329400Y1461497I-200J0D01*
G02Y1464409I1664J1456D01*
G03X1329450Y1464541I-150J132D01*
G01Y1466483D01*
G03X1329400Y1466615I-200J0D01*
G02Y1469527I1664J1456D01*
G03X1329450Y1469659I-150J132D01*
G01Y1470281D01*
G02X1329653Y1470484I203J0D01*
G37*
G36*
G01X1346976D02*
X1349796D01*
G02X1349998Y1470281I-1J-203D01*
G01Y1469661D01*
G03X1350048Y1469529I200J0D01*
G02Y1466613I-1661J-1458D01*
G03X1349998Y1466481I150J-132D01*
G01Y1464543D01*
G03X1350048Y1464411I200J0D01*
G02Y1461495I-1661J-1458D01*
G03X1349998Y1461363I150J-132D01*
G01Y1460743D01*
G02X1349796Y1460540I-202J-1D01*
G01X1346976D01*
G02X1346774Y1460743I1J203D01*
G01Y1461363D01*
G03X1346724Y1461495I-200J0D01*
G02Y1464411I1661J1458D01*
G03X1346774Y1464543I-150J132D01*
G01Y1466481D01*
G03X1346724Y1466613I-200J0D01*
G02Y1469529I1661J1458D01*
G03X1346774Y1469661I-150J132D01*
G01Y1470281D01*
G02X1346976Y1470484I202J1D01*
G37*
G36*
G01X1364299D02*
X1367119D01*
G02X1367322Y1470281I0J-203D01*
G01Y1469659D01*
G03X1367372Y1469527I200J0D01*
G02Y1466615I-1664J-1456D01*
G03X1367322Y1466483I150J-132D01*
G01Y1464541D01*
G03X1367372Y1464409I200J0D01*
G02Y1461497I-1664J-1456D01*
G03X1367322Y1461365I150J-132D01*
G01Y1460743D01*
G02X1367119Y1460540I-203J0D01*
G01X1364299D01*
G02X1364096Y1460743I0J203D01*
G01Y1461365D01*
G03X1364046Y1461497I-200J0D01*
G02Y1464409I1664J1456D01*
G03X1364096Y1464541I-150J132D01*
G01Y1466483D01*
G03X1364046Y1466615I-200J0D01*
G02Y1469527I1664J1456D01*
G03X1364096Y1469659I-150J132D01*
G01Y1470281D01*
G02X1364299Y1470484I203J0D01*
G37*
G36*
G01X1485558D02*
X1488378D01*
G02X1488580Y1470281I-1J-203D01*
G01Y1469661D01*
G03X1488630Y1469529I200J0D01*
G02Y1466613I-1661J-1458D01*
G03X1488580Y1466481I150J-132D01*
G01Y1464543D01*
G03X1488630Y1464411I200J0D01*
G02Y1461495I-1661J-1458D01*
G03X1488580Y1461363I150J-132D01*
G01Y1460743D01*
G02X1488378Y1460540I-202J-1D01*
G01X1485558D01*
G02X1485356Y1460743I1J203D01*
G01Y1461363D01*
G03X1485306Y1461495I-200J0D01*
G02Y1464411I1661J1458D01*
G03X1485356Y1464543I-150J132D01*
G01Y1466481D01*
G03X1485306Y1466613I-200J0D01*
G02Y1469529I1661J1458D01*
G03X1485356Y1469661I-150J132D01*
G01Y1470281D01*
G02X1485558Y1470484I202J1D01*
G37*
G36*
G01X1502881D02*
X1505701D01*
G02X1505904Y1470281I0J-203D01*
G01Y1469659D01*
G03X1505954Y1469527I200J0D01*
G02Y1466615I-1664J-1456D01*
G03X1505904Y1466483I150J-132D01*
G01Y1464541D01*
G03X1505954Y1464409I200J0D01*
G02Y1461497I-1664J-1456D01*
G03X1505904Y1461365I150J-132D01*
G01Y1460743D01*
G02X1505701Y1460540I-203J0D01*
G01X1502881D01*
G02X1502678Y1460743I0J203D01*
G01Y1461365D01*
G03X1502628Y1461497I-200J0D01*
G02Y1464409I1664J1456D01*
G03X1502678Y1464541I-150J132D01*
G01Y1466483D01*
G03X1502628Y1466615I-200J0D01*
G02Y1469527I1664J1456D01*
G03X1502678Y1469659I-150J132D01*
G01Y1470281D01*
G02X1502881Y1470484I203J0D01*
G37*
G36*
G01X1520204D02*
X1523024D01*
G02X1523226Y1470281I-1J-203D01*
G01Y1469661D01*
G03X1523276Y1469529I200J0D01*
G02Y1466613I-1661J-1458D01*
G03X1523226Y1466481I150J-132D01*
G01Y1464543D01*
G03X1523276Y1464411I200J0D01*
G02Y1461495I-1661J-1458D01*
G03X1523226Y1461363I150J-132D01*
G01Y1460743D01*
G02X1523024Y1460540I-202J-1D01*
G01X1520204D01*
G02X1520002Y1460743I1J203D01*
G01Y1461363D01*
G03X1519952Y1461495I-200J0D01*
G02Y1464411I1661J1458D01*
G03X1520002Y1464543I-150J132D01*
G01Y1466481D01*
G03X1519952Y1466613I-200J0D01*
G02Y1469529I1661J1458D01*
G03X1520002Y1469661I-150J132D01*
G01Y1470281D01*
G02X1520204Y1470484I202J1D01*
G37*
G36*
G01X1537527D02*
X1540347D01*
G02X1540550Y1470281I0J-203D01*
G01Y1469659D01*
G03X1540600Y1469527I200J0D01*
G02Y1466615I-1664J-1456D01*
G03X1540550Y1466483I150J-132D01*
G01Y1464541D01*
G03X1540600Y1464409I200J0D01*
G02Y1461497I-1664J-1456D01*
G03X1540550Y1461365I150J-132D01*
G01Y1460743D01*
G02X1540347Y1460540I-203J0D01*
G01X1537527D01*
G02X1537324Y1460743I0J203D01*
G01Y1461365D01*
G03X1537274Y1461497I-200J0D01*
G02Y1464409I1664J1456D01*
G03X1537324Y1464541I-150J132D01*
G01Y1466483D01*
G03X1537274Y1466615I-200J0D01*
G02Y1469527I1664J1456D01*
G03X1537324Y1469659I-150J132D01*
G01Y1470281D01*
G02X1537527Y1470484I203J0D01*
G37*
G36*
G01X1693432D02*
X1696252D01*
G02X1696454Y1470281I-1J-203D01*
G01Y1469661D01*
G03X1696504Y1469529I200J0D01*
G02Y1466613I-1661J-1458D01*
G03X1696454Y1466481I150J-132D01*
G01Y1464543D01*
G03X1696504Y1464411I200J0D01*
G02Y1461495I-1661J-1458D01*
G03X1696454Y1461363I150J-132D01*
G01Y1460743D01*
G02X1696252Y1460540I-202J-1D01*
G01X1693432D01*
G02X1693230Y1460743I1J203D01*
G01Y1461363D01*
G03X1693180Y1461495I-200J0D01*
G02Y1464411I1661J1458D01*
G03X1693230Y1464543I-150J132D01*
G01Y1466481D01*
G03X1693180Y1466613I-200J0D01*
G02Y1469529I1661J1458D01*
G03X1693230Y1469661I-150J132D01*
G01Y1470281D01*
G02X1693432Y1470484I202J1D01*
G37*
G36*
G01X1710755D02*
X1713575D01*
G02X1713778Y1470281I0J-203D01*
G01Y1469659D01*
G03X1713828Y1469527I200J0D01*
G02Y1466615I-1664J-1456D01*
G03X1713778Y1466483I150J-132D01*
G01Y1464541D01*
G03X1713828Y1464409I200J0D01*
G02Y1461497I-1664J-1456D01*
G03X1713778Y1461365I150J-132D01*
G01Y1460743D01*
G02X1713575Y1460540I-203J0D01*
G01X1710755D01*
G02X1710552Y1460743I0J203D01*
G01Y1461365D01*
G03X1710502Y1461497I-200J0D01*
G02Y1464409I1664J1456D01*
G03X1710552Y1464541I-150J132D01*
G01Y1466483D01*
G03X1710502Y1466615I-200J0D01*
G02Y1469527I1664J1456D01*
G03X1710552Y1469659I-150J132D01*
G01Y1470281D01*
G02X1710755Y1470484I203J0D01*
G37*
G36*
G01X125795Y1481508D02*
X128615D01*
G02X128818Y1481305I0J-203D01*
G01Y1480683D01*
G03X128868Y1480551I200J0D01*
G02Y1477639I-1664J-1456D01*
G03X128818Y1477507I150J-132D01*
G01Y1475565D01*
G03X128868Y1475433I200J0D01*
G02Y1472521I-1664J-1456D01*
G03X128818Y1472389I150J-132D01*
G01Y1471767D01*
G02X128615Y1471564I-203J0D01*
G01X125795D01*
G02X125592Y1471767I0J203D01*
G01Y1472389D01*
G03X125542Y1472521I-200J0D01*
G02Y1475433I1664J1456D01*
G03X125592Y1475565I-150J132D01*
G01Y1477507D01*
G03X125542Y1477639I-200J0D01*
G02Y1480551I1664J1456D01*
G03X125592Y1480683I-150J132D01*
G01Y1481305D01*
G02X125795Y1481508I203J0D01*
G37*
G36*
G01X143118D02*
X145938D01*
G02X146140Y1481305I-1J-203D01*
G01Y1480685D01*
G03X146190Y1480553I200J0D01*
G02Y1477637I-1661J-1458D01*
G03X146140Y1477505I150J-132D01*
G01Y1475567D01*
G03X146190Y1475435I200J0D01*
G02Y1472519I-1661J-1458D01*
G03X146140Y1472387I150J-132D01*
G01Y1471767D01*
G02X145938Y1471564I-202J-1D01*
G01X143118D01*
G02X142916Y1471767I1J203D01*
G01Y1472387D01*
G03X142866Y1472519I-200J0D01*
G02Y1475435I1661J1458D01*
G03X142916Y1475567I-150J132D01*
G01Y1477505D01*
G03X142866Y1477637I-200J0D01*
G02Y1480553I1661J1458D01*
G03X142916Y1480685I-150J132D01*
G01Y1481305D01*
G02X143118Y1481508I202J1D01*
G37*
G36*
G01X160440D02*
X163260D01*
G02X163462Y1481305I-1J-203D01*
G01Y1480685D01*
G03X163512Y1480553I200J0D01*
G02Y1477637I-1661J-1458D01*
G03X163462Y1477505I150J-132D01*
G01Y1475567D01*
G03X163512Y1475435I200J0D01*
G02Y1472519I-1661J-1458D01*
G03X163462Y1472387I150J-132D01*
G01Y1471767D01*
G02X163260Y1471564I-202J-1D01*
G01X160440D01*
G02X160238Y1471767I1J203D01*
G01Y1472387D01*
G03X160188Y1472519I-200J0D01*
G02Y1475435I1661J1458D01*
G03X160238Y1475567I-150J132D01*
G01Y1477505D01*
G03X160188Y1477637I-200J0D01*
G02Y1480553I1661J1458D01*
G03X160238Y1480685I-150J132D01*
G01Y1481305D01*
G02X160440Y1481508I202J1D01*
G37*
G36*
G01X177763D02*
X180583D01*
G02X180786Y1481305I0J-203D01*
G01Y1480683D01*
G03X180836Y1480551I200J0D01*
G02Y1477639I-1664J-1456D01*
G03X180786Y1477507I150J-132D01*
G01Y1475565D01*
G03X180836Y1475433I200J0D01*
G02Y1472521I-1664J-1456D01*
G03X180786Y1472389I150J-132D01*
G01Y1471767D01*
G02X180583Y1471564I-203J0D01*
G01X177763D01*
G02X177560Y1471767I0J203D01*
G01Y1472389D01*
G03X177510Y1472521I-200J0D01*
G02Y1475433I1664J1456D01*
G03X177560Y1475565I-150J132D01*
G01Y1477507D01*
G03X177510Y1477639I-200J0D01*
G02Y1480551I1664J1456D01*
G03X177560Y1480683I-150J132D01*
G01Y1481305D01*
G02X177763Y1481508I203J0D01*
G37*
G36*
G01X281700D02*
X284520D01*
G02X284722Y1481305I-1J-203D01*
G01Y1480685D01*
G03X284772Y1480553I200J0D01*
G02Y1477637I-1661J-1458D01*
G03X284722Y1477505I150J-132D01*
G01Y1475567D01*
G03X284772Y1475435I200J0D01*
G02Y1472519I-1661J-1458D01*
G03X284722Y1472387I150J-132D01*
G01Y1471767D01*
G02X284520Y1471564I-202J-1D01*
G01X281700D01*
G02X281498Y1471767I1J203D01*
G01Y1472387D01*
G03X281448Y1472519I-200J0D01*
G02Y1475435I1661J1458D01*
G03X281498Y1475567I-150J132D01*
G01Y1477505D01*
G03X281448Y1477637I-200J0D01*
G02Y1480553I1661J1458D01*
G03X281498Y1480685I-150J132D01*
G01Y1481305D01*
G02X281700Y1481508I202J1D01*
G37*
G36*
G01X299023D02*
X301843D01*
G02X302046Y1481305I0J-203D01*
G01Y1480683D01*
G03X302096Y1480551I200J0D01*
G02Y1477639I-1664J-1456D01*
G03X302046Y1477507I150J-132D01*
G01Y1475565D01*
G03X302096Y1475433I200J0D01*
G02Y1472521I-1664J-1456D01*
G03X302046Y1472389I150J-132D01*
G01Y1471767D01*
G02X301843Y1471564I-203J0D01*
G01X299023D01*
G02X298820Y1471767I0J203D01*
G01Y1472389D01*
G03X298770Y1472521I-200J0D01*
G02Y1475433I1664J1456D01*
G03X298820Y1475565I-150J132D01*
G01Y1477507D01*
G03X298770Y1477639I-200J0D01*
G02Y1480551I1664J1456D01*
G03X298820Y1480683I-150J132D01*
G01Y1481305D01*
G02X299023Y1481508I203J0D01*
G37*
G36*
G01X454929D02*
X457749D01*
G02X457952Y1481305I0J-203D01*
G01Y1480683D01*
G03X458002Y1480551I200J0D01*
G02Y1477639I-1664J-1456D01*
G03X457952Y1477507I150J-132D01*
G01Y1475565D01*
G03X458002Y1475433I200J0D01*
G02Y1472521I-1664J-1456D01*
G03X457952Y1472389I150J-132D01*
G01Y1471767D01*
G02X457749Y1471564I-203J0D01*
G01X454929D01*
G02X454726Y1471767I0J203D01*
G01Y1472389D01*
G03X454676Y1472521I-200J0D01*
G02Y1475433I1664J1456D01*
G03X454726Y1475565I-150J132D01*
G01Y1477507D01*
G03X454676Y1477639I-200J0D01*
G02Y1480551I1664J1456D01*
G03X454726Y1480683I-150J132D01*
G01Y1481305D01*
G02X454929Y1481508I203J0D01*
G37*
G36*
G01X472252D02*
X475072D01*
G02X475274Y1481305I-1J-203D01*
G01Y1480685D01*
G03X475324Y1480553I200J0D01*
G02Y1477637I-1661J-1458D01*
G03X475274Y1477505I150J-132D01*
G01Y1475567D01*
G03X475324Y1475435I200J0D01*
G02Y1472519I-1661J-1458D01*
G03X475274Y1472387I150J-132D01*
G01Y1471767D01*
G02X475072Y1471564I-202J-1D01*
G01X472252D01*
G02X472050Y1471767I1J203D01*
G01Y1472387D01*
G03X472000Y1472519I-200J0D01*
G02Y1475435I1661J1458D01*
G03X472050Y1475567I-150J132D01*
G01Y1477505D01*
G03X472000Y1477637I-200J0D01*
G02Y1480553I1661J1458D01*
G03X472050Y1480685I-150J132D01*
G01Y1481305D01*
G02X472252Y1481508I202J1D01*
G37*
G36*
G01X489575D02*
X492395D01*
G02X492598Y1481305I0J-203D01*
G01Y1480683D01*
G03X492648Y1480551I200J0D01*
G02Y1477639I-1664J-1456D01*
G03X492598Y1477507I150J-132D01*
G01Y1475565D01*
G03X492648Y1475433I200J0D01*
G02Y1472521I-1664J-1456D01*
G03X492598Y1472389I150J-132D01*
G01Y1471767D01*
G02X492395Y1471564I-203J0D01*
G01X489575D01*
G02X489372Y1471767I0J203D01*
G01Y1472389D01*
G03X489322Y1472521I-200J0D01*
G02Y1475433I1664J1456D01*
G03X489372Y1475565I-150J132D01*
G01Y1477507D01*
G03X489322Y1477639I-200J0D01*
G02Y1480551I1664J1456D01*
G03X489372Y1480683I-150J132D01*
G01Y1481305D01*
G02X489575Y1481508I203J0D01*
G37*
G36*
G01X506897D02*
X509717D01*
G02X509920Y1481305I0J-203D01*
G01Y1480683D01*
G03X509970Y1480551I200J0D01*
G02Y1477639I-1664J-1456D01*
G03X509920Y1477507I150J-132D01*
G01Y1475565D01*
G03X509970Y1475433I200J0D01*
G02Y1472521I-1664J-1456D01*
G03X509920Y1472389I150J-132D01*
G01Y1471767D01*
G02X509717Y1471564I-203J0D01*
G01X506897D01*
G02X506694Y1471767I0J203D01*
G01Y1472389D01*
G03X506644Y1472521I-200J0D01*
G02Y1475433I1664J1456D01*
G03X506694Y1475565I-150J132D01*
G01Y1477507D01*
G03X506644Y1477639I-200J0D01*
G02Y1480551I1664J1456D01*
G03X506694Y1480683I-150J132D01*
G01Y1481305D01*
G02X506897Y1481508I203J0D01*
G37*
G36*
G01X645480D02*
X648300D01*
G02X648502Y1481305I-1J-203D01*
G01Y1480685D01*
G03X648552Y1480553I200J0D01*
G02Y1477637I-1661J-1458D01*
G03X648502Y1477505I150J-132D01*
G01Y1475567D01*
G03X648552Y1475435I200J0D01*
G02Y1472519I-1661J-1458D01*
G03X648502Y1472387I150J-132D01*
G01Y1471767D01*
G02X648300Y1471564I-202J-1D01*
G01X645480D01*
G02X645278Y1471767I1J203D01*
G01Y1472387D01*
G03X645228Y1472519I-200J0D01*
G02Y1475435I1661J1458D01*
G03X645278Y1475567I-150J132D01*
G01Y1477505D01*
G03X645228Y1477637I-200J0D01*
G02Y1480553I1661J1458D01*
G03X645278Y1480685I-150J132D01*
G01Y1481305D01*
G02X645480Y1481508I202J1D01*
G37*
G36*
G01X662803D02*
X665623D01*
G02X665826Y1481305I0J-203D01*
G01Y1480683D01*
G03X665876Y1480551I200J0D01*
G02Y1477639I-1664J-1456D01*
G03X665826Y1477507I150J-132D01*
G01Y1475565D01*
G03X665876Y1475433I200J0D01*
G02Y1472521I-1664J-1456D01*
G03X665826Y1472389I150J-132D01*
G01Y1471767D01*
G02X665623Y1471564I-203J0D01*
G01X662803D01*
G02X662600Y1471767I0J203D01*
G01Y1472389D01*
G03X662550Y1472521I-200J0D01*
G02Y1475433I1664J1456D01*
G03X662600Y1475565I-150J132D01*
G01Y1477507D01*
G03X662550Y1477639I-200J0D01*
G02Y1480551I1664J1456D01*
G03X662600Y1480683I-150J132D01*
G01Y1481305D01*
G02X662803Y1481508I203J0D01*
G37*
G36*
G01X680125D02*
X682945D01*
G02X683148Y1481305I0J-203D01*
G01Y1480683D01*
G03X683198Y1480551I200J0D01*
G02Y1477639I-1664J-1456D01*
G03X683148Y1477507I150J-132D01*
G01Y1475565D01*
G03X683198Y1475433I200J0D01*
G02Y1472521I-1664J-1456D01*
G03X683148Y1472389I150J-132D01*
G01Y1471767D01*
G02X682945Y1471564I-203J0D01*
G01X680125D01*
G02X679922Y1471767I0J203D01*
G01Y1472389D01*
G03X679872Y1472521I-200J0D01*
G02Y1475433I1664J1456D01*
G03X679922Y1475565I-150J132D01*
G01Y1477507D01*
G03X679872Y1477639I-200J0D01*
G02Y1480551I1664J1456D01*
G03X679922Y1480683I-150J132D01*
G01Y1481305D01*
G02X680125Y1481508I203J0D01*
G37*
G36*
G01X1165086D02*
X1167906D01*
G02X1168108Y1481305I-1J-203D01*
G01Y1480685D01*
G03X1168158Y1480553I200J0D01*
G02Y1477637I-1661J-1458D01*
G03X1168108Y1477505I150J-132D01*
G01Y1475567D01*
G03X1168158Y1475435I200J0D01*
G02Y1472519I-1661J-1458D01*
G03X1168108Y1472387I150J-132D01*
G01Y1471767D01*
G02X1167906Y1471564I-202J-1D01*
G01X1165086D01*
G02X1164884Y1471767I1J203D01*
G01Y1472387D01*
G03X1164834Y1472519I-200J0D01*
G02Y1475435I1661J1458D01*
G03X1164884Y1475567I-150J132D01*
G01Y1477505D01*
G03X1164834Y1477637I-200J0D01*
G02Y1480553I1661J1458D01*
G03X1164884Y1480685I-150J132D01*
G01Y1481305D01*
G02X1165086Y1481508I202J1D01*
G37*
G36*
G01X1182408D02*
X1185228D01*
G02X1185430Y1481305I-1J-203D01*
G01Y1480685D01*
G03X1185480Y1480553I200J0D01*
G02Y1477637I-1661J-1458D01*
G03X1185430Y1477505I150J-132D01*
G01Y1475567D01*
G03X1185480Y1475435I200J0D01*
G02Y1472519I-1661J-1458D01*
G03X1185430Y1472387I150J-132D01*
G01Y1471767D01*
G02X1185228Y1471564I-202J-1D01*
G01X1182408D01*
G02X1182206Y1471767I1J203D01*
G01Y1472387D01*
G03X1182156Y1472519I-200J0D01*
G02Y1475435I1661J1458D01*
G03X1182206Y1475567I-150J132D01*
G01Y1477505D01*
G03X1182156Y1477637I-200J0D01*
G02Y1480553I1661J1458D01*
G03X1182206Y1480685I-150J132D01*
G01Y1481305D01*
G02X1182408Y1481508I202J1D01*
G37*
G36*
G01X1303669D02*
X1306489D01*
G02X1306692Y1481305I0J-203D01*
G01Y1480683D01*
G03X1306742Y1480551I200J0D01*
G02Y1477639I-1664J-1456D01*
G03X1306692Y1477507I150J-132D01*
G01Y1475565D01*
G03X1306742Y1475433I200J0D01*
G02Y1472521I-1664J-1456D01*
G03X1306692Y1472389I150J-132D01*
G01Y1471767D01*
G02X1306489Y1471564I-203J0D01*
G01X1303669D01*
G02X1303466Y1471767I0J203D01*
G01Y1472389D01*
G03X1303416Y1472521I-200J0D01*
G02Y1475433I1664J1456D01*
G03X1303466Y1475565I-150J132D01*
G01Y1477507D01*
G03X1303416Y1477639I-200J0D01*
G02Y1480551I1664J1456D01*
G03X1303466Y1480683I-150J132D01*
G01Y1481305D01*
G02X1303669Y1481508I203J0D01*
G37*
G36*
G01X1320992D02*
X1323812D01*
G02X1324014Y1481305I-1J-203D01*
G01Y1480685D01*
G03X1324064Y1480553I200J0D01*
G02Y1477637I-1661J-1458D01*
G03X1324014Y1477505I150J-132D01*
G01Y1475567D01*
G03X1324064Y1475435I200J0D01*
G02Y1472519I-1661J-1458D01*
G03X1324014Y1472387I150J-132D01*
G01Y1471767D01*
G02X1323812Y1471564I-202J-1D01*
G01X1320992D01*
G02X1320790Y1471767I1J203D01*
G01Y1472387D01*
G03X1320740Y1472519I-200J0D01*
G02Y1475435I1661J1458D01*
G03X1320790Y1475567I-150J132D01*
G01Y1477505D01*
G03X1320740Y1477637I-200J0D01*
G02Y1480553I1661J1458D01*
G03X1320790Y1480685I-150J132D01*
G01Y1481305D01*
G02X1320992Y1481508I202J1D01*
G37*
G36*
G01X1338315D02*
X1341135D01*
G02X1341338Y1481305I0J-203D01*
G01Y1480683D01*
G03X1341388Y1480551I200J0D01*
G02Y1477639I-1664J-1456D01*
G03X1341338Y1477507I150J-132D01*
G01Y1475565D01*
G03X1341388Y1475433I200J0D01*
G02Y1472521I-1664J-1456D01*
G03X1341338Y1472389I150J-132D01*
G01Y1471767D01*
G02X1341135Y1471564I-203J0D01*
G01X1338315D01*
G02X1338112Y1471767I0J203D01*
G01Y1472389D01*
G03X1338062Y1472521I-200J0D01*
G02Y1475433I1664J1456D01*
G03X1338112Y1475565I-150J132D01*
G01Y1477507D01*
G03X1338062Y1477639I-200J0D01*
G02Y1480551I1664J1456D01*
G03X1338112Y1480683I-150J132D01*
G01Y1481305D01*
G02X1338315Y1481508I203J0D01*
G37*
G36*
G01X1355637D02*
X1358457D01*
G02X1358660Y1481305I0J-203D01*
G01Y1480683D01*
G03X1358710Y1480551I200J0D01*
G02Y1477639I-1664J-1456D01*
G03X1358660Y1477507I150J-132D01*
G01Y1475565D01*
G03X1358710Y1475433I200J0D01*
G02Y1472521I-1664J-1456D01*
G03X1358660Y1472389I150J-132D01*
G01Y1471767D01*
G02X1358457Y1471564I-203J0D01*
G01X1355637D01*
G02X1355434Y1471767I0J203D01*
G01Y1472389D01*
G03X1355384Y1472521I-200J0D01*
G02Y1475433I1664J1456D01*
G03X1355434Y1475565I-150J132D01*
G01Y1477507D01*
G03X1355384Y1477639I-200J0D01*
G02Y1480551I1664J1456D01*
G03X1355434Y1480683I-150J132D01*
G01Y1481305D01*
G02X1355637Y1481508I203J0D01*
G37*
G36*
G01X1476897D02*
X1479717D01*
G02X1479920Y1481305I0J-203D01*
G01Y1480683D01*
G03X1479970Y1480551I200J0D01*
G02Y1477639I-1664J-1456D01*
G03X1479920Y1477507I150J-132D01*
G01Y1475565D01*
G03X1479970Y1475433I200J0D01*
G02Y1472521I-1664J-1456D01*
G03X1479920Y1472389I150J-132D01*
G01Y1471767D01*
G02X1479717Y1471564I-203J0D01*
G01X1476897D01*
G02X1476694Y1471767I0J203D01*
G01Y1472389D01*
G03X1476644Y1472521I-200J0D01*
G02Y1475433I1664J1456D01*
G03X1476694Y1475565I-150J132D01*
G01Y1477507D01*
G03X1476644Y1477639I-200J0D01*
G02Y1480551I1664J1456D01*
G03X1476694Y1480683I-150J132D01*
G01Y1481305D01*
G02X1476897Y1481508I203J0D01*
G37*
G36*
G01X1494220D02*
X1497040D01*
G02X1497242Y1481305I-1J-203D01*
G01Y1480685D01*
G03X1497292Y1480553I200J0D01*
G02Y1477637I-1661J-1458D01*
G03X1497242Y1477505I150J-132D01*
G01Y1475567D01*
G03X1497292Y1475435I200J0D01*
G02Y1472519I-1661J-1458D01*
G03X1497242Y1472387I150J-132D01*
G01Y1471767D01*
G02X1497040Y1471564I-202J-1D01*
G01X1494220D01*
G02X1494018Y1471767I1J203D01*
G01Y1472387D01*
G03X1493968Y1472519I-200J0D01*
G02Y1475435I1661J1458D01*
G03X1494018Y1475567I-150J132D01*
G01Y1477505D01*
G03X1493968Y1477637I-200J0D01*
G02Y1480553I1661J1458D01*
G03X1494018Y1480685I-150J132D01*
G01Y1481305D01*
G02X1494220Y1481508I202J1D01*
G37*
G36*
G01X1511543D02*
X1514363D01*
G02X1514566Y1481305I0J-203D01*
G01Y1480683D01*
G03X1514616Y1480551I200J0D01*
G02Y1477639I-1664J-1456D01*
G03X1514566Y1477507I150J-132D01*
G01Y1475565D01*
G03X1514616Y1475433I200J0D01*
G02Y1472521I-1664J-1456D01*
G03X1514566Y1472389I150J-132D01*
G01Y1471767D01*
G02X1514363Y1471564I-203J0D01*
G01X1511543D01*
G02X1511340Y1471767I0J203D01*
G01Y1472389D01*
G03X1511290Y1472521I-200J0D01*
G02Y1475433I1664J1456D01*
G03X1511340Y1475565I-150J132D01*
G01Y1477507D01*
G03X1511290Y1477639I-200J0D01*
G02Y1480551I1664J1456D01*
G03X1511340Y1480683I-150J132D01*
G01Y1481305D01*
G02X1511543Y1481508I203J0D01*
G37*
G36*
G01X1528865D02*
X1531685D01*
G02X1531888Y1481305I0J-203D01*
G01Y1480683D01*
G03X1531938Y1480551I200J0D01*
G02Y1477639I-1664J-1456D01*
G03X1531888Y1477507I150J-132D01*
G01Y1475565D01*
G03X1531938Y1475433I200J0D01*
G02Y1472521I-1664J-1456D01*
G03X1531888Y1472389I150J-132D01*
G01Y1471767D01*
G02X1531685Y1471564I-203J0D01*
G01X1528865D01*
G02X1528662Y1471767I0J203D01*
G01Y1472389D01*
G03X1528612Y1472521I-200J0D01*
G02Y1475433I1664J1456D01*
G03X1528662Y1475565I-150J132D01*
G01Y1477507D01*
G03X1528612Y1477639I-200J0D01*
G02Y1480551I1664J1456D01*
G03X1528662Y1480683I-150J132D01*
G01Y1481305D01*
G02X1528865Y1481508I203J0D01*
G37*
G36*
G01X1684771D02*
X1687591D01*
G02X1687794Y1481305I0J-203D01*
G01Y1480683D01*
G03X1687844Y1480551I200J0D01*
G02Y1477639I-1664J-1456D01*
G03X1687794Y1477507I150J-132D01*
G01Y1475565D01*
G03X1687844Y1475433I200J0D01*
G02Y1472521I-1664J-1456D01*
G03X1687794Y1472389I150J-132D01*
G01Y1471767D01*
G02X1687591Y1471564I-203J0D01*
G01X1684771D01*
G02X1684568Y1471767I0J203D01*
G01Y1472389D01*
G03X1684518Y1472521I-200J0D01*
G02Y1475433I1664J1456D01*
G03X1684568Y1475565I-150J132D01*
G01Y1477507D01*
G03X1684518Y1477639I-200J0D01*
G02Y1480551I1664J1456D01*
G03X1684568Y1480683I-150J132D01*
G01Y1481305D01*
G02X1684771Y1481508I203J0D01*
G37*
G36*
G01X1702093D02*
X1704913D01*
G02X1705116Y1481305I0J-203D01*
G01Y1480683D01*
G03X1705166Y1480551I200J0D01*
G02Y1477639I-1664J-1456D01*
G03X1705116Y1477507I150J-132D01*
G01Y1475565D01*
G03X1705166Y1475433I200J0D01*
G02Y1472521I-1664J-1456D01*
G03X1705116Y1472389I150J-132D01*
G01Y1471767D01*
G02X1704913Y1471564I-203J0D01*
G01X1702093D01*
G02X1701890Y1471767I0J203D01*
G01Y1472389D01*
G03X1701840Y1472521I-200J0D01*
G02Y1475433I1664J1456D01*
G03X1701890Y1475565I-150J132D01*
G01Y1477507D01*
G03X1701840Y1477639I-200J0D01*
G02Y1480551I1664J1456D01*
G03X1701890Y1480683I-150J132D01*
G01Y1481305D01*
G02X1702093Y1481508I203J0D01*
G37*
G36*
G01X134456Y1485838D02*
X137276D01*
G02X137478Y1485635I-1J-203D01*
G01Y1485016D01*
G03X137528Y1484884I200J0D01*
G02Y1481968I-1661J-1458D01*
G03X137478Y1481836I150J-132D01*
G01Y1479898D01*
G03X137528Y1479766I200J0D01*
G02Y1476850I-1661J-1458D01*
G03X137478Y1476718I150J-132D01*
G01Y1476097D01*
G02X137276Y1475894I-202J-1D01*
G01X134456D01*
G02X134254Y1476097I1J203D01*
G01Y1476718D01*
G03X134204Y1476850I-200J0D01*
G02Y1479766I1661J1458D01*
G03X134254Y1479898I-150J132D01*
G01Y1481836D01*
G03X134204Y1481968I-200J0D01*
G02Y1484884I1661J1458D01*
G03X134254Y1485016I-150J132D01*
G01Y1485635D01*
G02X134456Y1485838I202J1D01*
G37*
G36*
G01X151779D02*
X154599D01*
G02X154802Y1485635I0J-203D01*
G01Y1485014D01*
G03X154852Y1484882I200J0D01*
G02Y1481970I-1664J-1456D01*
G03X154802Y1481838I150J-132D01*
G01Y1479896D01*
G03X154852Y1479764I200J0D01*
G02Y1476852I-1664J-1456D01*
G03X154802Y1476720I150J-132D01*
G01Y1476097D01*
G02X154599Y1475894I-203J0D01*
G01X151779D01*
G02X151576Y1476097I0J203D01*
G01Y1476720D01*
G03X151526Y1476852I-200J0D01*
G02Y1479764I1664J1456D01*
G03X151576Y1479896I-150J132D01*
G01Y1481838D01*
G03X151526Y1481970I-200J0D01*
G02Y1484882I1664J1456D01*
G03X151576Y1485014I-150J132D01*
G01Y1485635D01*
G02X151779Y1485838I203J0D01*
G37*
G36*
G01X169102D02*
X171922D01*
G02X172124Y1485635I-1J-203D01*
G01Y1485016D01*
G03X172174Y1484884I200J0D01*
G02Y1481968I-1661J-1458D01*
G03X172124Y1481836I150J-132D01*
G01Y1479898D01*
G03X172174Y1479766I200J0D01*
G02Y1476850I-1661J-1458D01*
G03X172124Y1476718I150J-132D01*
G01Y1476097D01*
G02X171922Y1475894I-202J-1D01*
G01X169102D01*
G02X168900Y1476097I1J203D01*
G01Y1476718D01*
G03X168850Y1476850I-200J0D01*
G02Y1479766I1661J1458D01*
G03X168900Y1479898I-150J132D01*
G01Y1481836D01*
G03X168850Y1481968I-200J0D01*
G02Y1484884I1661J1458D01*
G03X168900Y1485016I-150J132D01*
G01Y1485635D01*
G02X169102Y1485838I202J1D01*
G37*
G36*
G01X290361D02*
X293181D01*
G02X293384Y1485635I0J-203D01*
G01Y1485014D01*
G03X293434Y1484882I200J0D01*
G02Y1481970I-1664J-1456D01*
G03X293384Y1481838I150J-132D01*
G01Y1479896D01*
G03X293434Y1479764I200J0D01*
G02Y1476852I-1664J-1456D01*
G03X293384Y1476720I150J-132D01*
G01Y1476097D01*
G02X293181Y1475894I-203J0D01*
G01X290361D01*
G02X290158Y1476097I0J203D01*
G01Y1476720D01*
G03X290108Y1476852I-200J0D01*
G02Y1479764I1664J1456D01*
G03X290158Y1479896I-150J132D01*
G01Y1481838D01*
G03X290108Y1481970I-200J0D01*
G02Y1484882I1664J1456D01*
G03X290158Y1485014I-150J132D01*
G01Y1485635D01*
G02X290361Y1485838I203J0D01*
G37*
G36*
G01X463590D02*
X466410D01*
G02X466612Y1485635I-1J-203D01*
G01Y1485016D01*
G03X466662Y1484884I200J0D01*
G02Y1481968I-1661J-1458D01*
G03X466612Y1481836I150J-132D01*
G01Y1479898D01*
G03X466662Y1479766I200J0D01*
G02Y1476850I-1661J-1458D01*
G03X466612Y1476718I150J-132D01*
G01Y1476097D01*
G02X466410Y1475894I-202J-1D01*
G01X463590D01*
G02X463388Y1476097I1J203D01*
G01Y1476718D01*
G03X463338Y1476850I-200J0D01*
G02Y1479766I1661J1458D01*
G03X463388Y1479898I-150J132D01*
G01Y1481836D01*
G03X463338Y1481968I-200J0D01*
G02Y1484884I1661J1458D01*
G03X463388Y1485016I-150J132D01*
G01Y1485635D01*
G02X463590Y1485838I202J1D01*
G37*
G36*
G01X480913D02*
X483733D01*
G02X483936Y1485635I0J-203D01*
G01Y1485014D01*
G03X483986Y1484882I200J0D01*
G02Y1481970I-1664J-1456D01*
G03X483936Y1481838I150J-132D01*
G01Y1479896D01*
G03X483986Y1479764I200J0D01*
G02Y1476852I-1664J-1456D01*
G03X483936Y1476720I150J-132D01*
G01Y1476097D01*
G02X483733Y1475894I-203J0D01*
G01X480913D01*
G02X480710Y1476097I0J203D01*
G01Y1476720D01*
G03X480660Y1476852I-200J0D01*
G02Y1479764I1664J1456D01*
G03X480710Y1479896I-150J132D01*
G01Y1481838D01*
G03X480660Y1481970I-200J0D01*
G02Y1484882I1664J1456D01*
G03X480710Y1485014I-150J132D01*
G01Y1485635D01*
G02X480913Y1485838I203J0D01*
G37*
G36*
G01X498236D02*
X501056D01*
G02X501258Y1485635I-1J-203D01*
G01Y1485016D01*
G03X501308Y1484884I200J0D01*
G02Y1481968I-1661J-1458D01*
G03X501258Y1481836I150J-132D01*
G01Y1479898D01*
G03X501308Y1479766I200J0D01*
G02Y1476850I-1661J-1458D01*
G03X501258Y1476718I150J-132D01*
G01Y1476097D01*
G02X501056Y1475894I-202J-1D01*
G01X498236D01*
G02X498034Y1476097I1J203D01*
G01Y1476718D01*
G03X497984Y1476850I-200J0D01*
G02Y1479766I1661J1458D01*
G03X498034Y1479898I-150J132D01*
G01Y1481836D01*
G03X497984Y1481968I-200J0D01*
G02Y1484884I1661J1458D01*
G03X498034Y1485016I-150J132D01*
G01Y1485635D01*
G02X498236Y1485838I202J1D01*
G37*
G36*
G01X515559D02*
X518379D01*
G02X518582Y1485635I0J-203D01*
G01Y1485014D01*
G03X518632Y1484882I200J0D01*
G02Y1481970I-1664J-1456D01*
G03X518582Y1481838I150J-132D01*
G01Y1479896D01*
G03X518632Y1479764I200J0D01*
G02Y1476852I-1664J-1456D01*
G03X518582Y1476720I150J-132D01*
G01Y1476097D01*
G02X518379Y1475894I-203J0D01*
G01X515559D01*
G02X515356Y1476097I0J203D01*
G01Y1476720D01*
G03X515306Y1476852I-200J0D01*
G02Y1479764I1664J1456D01*
G03X515356Y1479896I-150J132D01*
G01Y1481838D01*
G03X515306Y1481970I-200J0D01*
G02Y1484882I1664J1456D01*
G03X515356Y1485014I-150J132D01*
G01Y1485635D01*
G02X515559Y1485838I203J0D01*
G37*
G36*
G01X654141D02*
X656961D01*
G02X657164Y1485635I0J-203D01*
G01Y1485014D01*
G03X657214Y1484882I200J0D01*
G02Y1481970I-1664J-1456D01*
G03X657164Y1481838I150J-132D01*
G01Y1479896D01*
G03X657214Y1479764I200J0D01*
G02Y1476852I-1664J-1456D01*
G03X657164Y1476720I150J-132D01*
G01Y1476097D01*
G02X656961Y1475894I-203J0D01*
G01X654141D01*
G02X653938Y1476097I0J203D01*
G01Y1476720D01*
G03X653888Y1476852I-200J0D01*
G02Y1479764I1664J1456D01*
G03X653938Y1479896I-150J132D01*
G01Y1481838D01*
G03X653888Y1481970I-200J0D01*
G02Y1484882I1664J1456D01*
G03X653938Y1485014I-150J132D01*
G01Y1485635D01*
G02X654141Y1485838I203J0D01*
G37*
G36*
G01X671464D02*
X674284D01*
G02X674486Y1485635I-1J-203D01*
G01Y1485016D01*
G03X674536Y1484884I200J0D01*
G02Y1481968I-1661J-1458D01*
G03X674486Y1481836I150J-132D01*
G01Y1479898D01*
G03X674536Y1479766I200J0D01*
G02Y1476850I-1661J-1458D01*
G03X674486Y1476718I150J-132D01*
G01Y1476097D01*
G02X674284Y1475894I-202J-1D01*
G01X671464D01*
G02X671262Y1476097I1J203D01*
G01Y1476718D01*
G03X671212Y1476850I-200J0D01*
G02Y1479766I1661J1458D01*
G03X671262Y1479898I-150J132D01*
G01Y1481836D01*
G03X671212Y1481968I-200J0D01*
G02Y1484884I1661J1458D01*
G03X671262Y1485016I-150J132D01*
G01Y1485635D01*
G02X671464Y1485838I202J1D01*
G37*
G36*
G01X688787D02*
X691607D01*
G02X691810Y1485635I0J-203D01*
G01Y1485014D01*
G03X691860Y1484882I200J0D01*
G02Y1481970I-1664J-1456D01*
G03X691810Y1481838I150J-132D01*
G01Y1479896D01*
G03X691860Y1479764I200J0D01*
G02Y1476852I-1664J-1456D01*
G03X691810Y1476720I150J-132D01*
G01Y1476097D01*
G02X691607Y1475894I-203J0D01*
G01X688787D01*
G02X688584Y1476097I0J203D01*
G01Y1476720D01*
G03X688534Y1476852I-200J0D01*
G02Y1479764I1664J1456D01*
G03X688584Y1479896I-150J132D01*
G01Y1481838D01*
G03X688534Y1481970I-200J0D01*
G02Y1484882I1664J1456D01*
G03X688584Y1485014I-150J132D01*
G01Y1485635D01*
G02X688787Y1485838I203J0D01*
G37*
G36*
G01X1173747D02*
X1176567D01*
G02X1176770Y1485635I0J-203D01*
G01Y1485014D01*
G03X1176820Y1484882I200J0D01*
G02Y1481970I-1664J-1456D01*
G03X1176770Y1481838I150J-132D01*
G01Y1479896D01*
G03X1176820Y1479764I200J0D01*
G02Y1476852I-1664J-1456D01*
G03X1176770Y1476720I150J-132D01*
G01Y1476097D01*
G02X1176567Y1475894I-203J0D01*
G01X1173747D01*
G02X1173544Y1476097I0J203D01*
G01Y1476720D01*
G03X1173494Y1476852I-200J0D01*
G02Y1479764I1664J1456D01*
G03X1173544Y1479896I-150J132D01*
G01Y1481838D01*
G03X1173494Y1481970I-200J0D01*
G02Y1484882I1664J1456D01*
G03X1173544Y1485014I-150J132D01*
G01Y1485635D01*
G02X1173747Y1485838I203J0D01*
G37*
G36*
G01X1191070D02*
X1193890D01*
G02X1194092Y1485635I-1J-203D01*
G01Y1485016D01*
G03X1194142Y1484884I200J0D01*
G02Y1481968I-1661J-1458D01*
G03X1194092Y1481836I150J-132D01*
G01Y1479898D01*
G03X1194142Y1479766I200J0D01*
G02Y1476850I-1661J-1458D01*
G03X1194092Y1476718I150J-132D01*
G01Y1476097D01*
G02X1193890Y1475894I-202J-1D01*
G01X1191070D01*
G02X1190868Y1476097I1J203D01*
G01Y1476718D01*
G03X1190818Y1476850I-200J0D01*
G02Y1479766I1661J1458D01*
G03X1190868Y1479898I-150J132D01*
G01Y1481836D01*
G03X1190818Y1481968I-200J0D01*
G02Y1484884I1661J1458D01*
G03X1190868Y1485016I-150J132D01*
G01Y1485635D01*
G02X1191070Y1485838I202J1D01*
G37*
G36*
G01X1312330D02*
X1315150D01*
G02X1315352Y1485635I-1J-203D01*
G01Y1485016D01*
G03X1315402Y1484884I200J0D01*
G02Y1481968I-1661J-1458D01*
G03X1315352Y1481836I150J-132D01*
G01Y1479898D01*
G03X1315402Y1479766I200J0D01*
G02Y1476850I-1661J-1458D01*
G03X1315352Y1476718I150J-132D01*
G01Y1476097D01*
G02X1315150Y1475894I-202J-1D01*
G01X1312330D01*
G02X1312128Y1476097I1J203D01*
G01Y1476718D01*
G03X1312078Y1476850I-200J0D01*
G02Y1479766I1661J1458D01*
G03X1312128Y1479898I-150J132D01*
G01Y1481836D01*
G03X1312078Y1481968I-200J0D01*
G02Y1484884I1661J1458D01*
G03X1312128Y1485016I-150J132D01*
G01Y1485635D01*
G02X1312330Y1485838I202J1D01*
G37*
G36*
G01X1329653D02*
X1332473D01*
G02X1332676Y1485635I0J-203D01*
G01Y1485014D01*
G03X1332726Y1484882I200J0D01*
G02Y1481970I-1664J-1456D01*
G03X1332676Y1481838I150J-132D01*
G01Y1479896D01*
G03X1332726Y1479764I200J0D01*
G02Y1476852I-1664J-1456D01*
G03X1332676Y1476720I150J-132D01*
G01Y1476097D01*
G02X1332473Y1475894I-203J0D01*
G01X1329653D01*
G02X1329450Y1476097I0J203D01*
G01Y1476720D01*
G03X1329400Y1476852I-200J0D01*
G02Y1479764I1664J1456D01*
G03X1329450Y1479896I-150J132D01*
G01Y1481838D01*
G03X1329400Y1481970I-200J0D01*
G02Y1484882I1664J1456D01*
G03X1329450Y1485014I-150J132D01*
G01Y1485635D01*
G02X1329653Y1485838I203J0D01*
G37*
G36*
G01X1346976D02*
X1349796D01*
G02X1349998Y1485635I-1J-203D01*
G01Y1485016D01*
G03X1350048Y1484884I200J0D01*
G02Y1481968I-1661J-1458D01*
G03X1349998Y1481836I150J-132D01*
G01Y1479898D01*
G03X1350048Y1479766I200J0D01*
G02Y1476850I-1661J-1458D01*
G03X1349998Y1476718I150J-132D01*
G01Y1476097D01*
G02X1349796Y1475894I-202J-1D01*
G01X1346976D01*
G02X1346774Y1476097I1J203D01*
G01Y1476718D01*
G03X1346724Y1476850I-200J0D01*
G02Y1479766I1661J1458D01*
G03X1346774Y1479898I-150J132D01*
G01Y1481836D01*
G03X1346724Y1481968I-200J0D01*
G02Y1484884I1661J1458D01*
G03X1346774Y1485016I-150J132D01*
G01Y1485635D01*
G02X1346976Y1485838I202J1D01*
G37*
G36*
G01X1364299D02*
X1367119D01*
G02X1367322Y1485635I0J-203D01*
G01Y1485014D01*
G03X1367372Y1484882I200J0D01*
G02Y1481970I-1664J-1456D01*
G03X1367322Y1481838I150J-132D01*
G01Y1479896D01*
G03X1367372Y1479764I200J0D01*
G02Y1476852I-1664J-1456D01*
G03X1367322Y1476720I150J-132D01*
G01Y1476097D01*
G02X1367119Y1475894I-203J0D01*
G01X1364299D01*
G02X1364096Y1476097I0J203D01*
G01Y1476720D01*
G03X1364046Y1476852I-200J0D01*
G02Y1479764I1664J1456D01*
G03X1364096Y1479896I-150J132D01*
G01Y1481838D01*
G03X1364046Y1481970I-200J0D01*
G02Y1484882I1664J1456D01*
G03X1364096Y1485014I-150J132D01*
G01Y1485635D01*
G02X1364299Y1485838I203J0D01*
G37*
G36*
G01X1485558D02*
X1488378D01*
G02X1488580Y1485635I-1J-203D01*
G01Y1485016D01*
G03X1488630Y1484884I200J0D01*
G02Y1481968I-1661J-1458D01*
G03X1488580Y1481836I150J-132D01*
G01Y1479898D01*
G03X1488630Y1479766I200J0D01*
G02Y1476850I-1661J-1458D01*
G03X1488580Y1476718I150J-132D01*
G01Y1476097D01*
G02X1488378Y1475894I-202J-1D01*
G01X1485558D01*
G02X1485356Y1476097I1J203D01*
G01Y1476718D01*
G03X1485306Y1476850I-200J0D01*
G02Y1479766I1661J1458D01*
G03X1485356Y1479898I-150J132D01*
G01Y1481836D01*
G03X1485306Y1481968I-200J0D01*
G02Y1484884I1661J1458D01*
G03X1485356Y1485016I-150J132D01*
G01Y1485635D01*
G02X1485558Y1485838I202J1D01*
G37*
G36*
G01X1502881D02*
X1505701D01*
G02X1505904Y1485635I0J-203D01*
G01Y1485014D01*
G03X1505954Y1484882I200J0D01*
G02Y1481970I-1664J-1456D01*
G03X1505904Y1481838I150J-132D01*
G01Y1479896D01*
G03X1505954Y1479764I200J0D01*
G02Y1476852I-1664J-1456D01*
G03X1505904Y1476720I150J-132D01*
G01Y1476097D01*
G02X1505701Y1475894I-203J0D01*
G01X1502881D01*
G02X1502678Y1476097I0J203D01*
G01Y1476720D01*
G03X1502628Y1476852I-200J0D01*
G02Y1479764I1664J1456D01*
G03X1502678Y1479896I-150J132D01*
G01Y1481838D01*
G03X1502628Y1481970I-200J0D01*
G02Y1484882I1664J1456D01*
G03X1502678Y1485014I-150J132D01*
G01Y1485635D01*
G02X1502881Y1485838I203J0D01*
G37*
G36*
G01X1520204D02*
X1523024D01*
G02X1523226Y1485635I-1J-203D01*
G01Y1485016D01*
G03X1523276Y1484884I200J0D01*
G02Y1481968I-1661J-1458D01*
G03X1523226Y1481836I150J-132D01*
G01Y1479898D01*
G03X1523276Y1479766I200J0D01*
G02Y1476850I-1661J-1458D01*
G03X1523226Y1476718I150J-132D01*
G01Y1476097D01*
G02X1523024Y1475894I-202J-1D01*
G01X1520204D01*
G02X1520002Y1476097I1J203D01*
G01Y1476718D01*
G03X1519952Y1476850I-200J0D01*
G02Y1479766I1661J1458D01*
G03X1520002Y1479898I-150J132D01*
G01Y1481836D01*
G03X1519952Y1481968I-200J0D01*
G02Y1484884I1661J1458D01*
G03X1520002Y1485016I-150J132D01*
G01Y1485635D01*
G02X1520204Y1485838I202J1D01*
G37*
G36*
G01X1537527D02*
X1540347D01*
G02X1540550Y1485635I0J-203D01*
G01Y1485014D01*
G03X1540600Y1484882I200J0D01*
G02Y1481970I-1664J-1456D01*
G03X1540550Y1481838I150J-132D01*
G01Y1479896D01*
G03X1540600Y1479764I200J0D01*
G02Y1476852I-1664J-1456D01*
G03X1540550Y1476720I150J-132D01*
G01Y1476097D01*
G02X1540347Y1475894I-203J0D01*
G01X1537527D01*
G02X1537324Y1476097I0J203D01*
G01Y1476720D01*
G03X1537274Y1476852I-200J0D01*
G02Y1479764I1664J1456D01*
G03X1537324Y1479896I-150J132D01*
G01Y1481838D01*
G03X1537274Y1481970I-200J0D01*
G02Y1484882I1664J1456D01*
G03X1537324Y1485014I-150J132D01*
G01Y1485635D01*
G02X1537527Y1485838I203J0D01*
G37*
G36*
G01X1693432D02*
X1696252D01*
G02X1696454Y1485635I-1J-203D01*
G01Y1485016D01*
G03X1696504Y1484884I200J0D01*
G02Y1481968I-1661J-1458D01*
G03X1696454Y1481836I150J-132D01*
G01Y1479898D01*
G03X1696504Y1479766I200J0D01*
G02Y1476850I-1661J-1458D01*
G03X1696454Y1476718I150J-132D01*
G01Y1476097D01*
G02X1696252Y1475894I-202J-1D01*
G01X1693432D01*
G02X1693230Y1476097I1J203D01*
G01Y1476718D01*
G03X1693180Y1476850I-200J0D01*
G02Y1479766I1661J1458D01*
G03X1693230Y1479898I-150J132D01*
G01Y1481836D01*
G03X1693180Y1481968I-200J0D01*
G02Y1484884I1661J1458D01*
G03X1693230Y1485016I-150J132D01*
G01Y1485635D01*
G02X1693432Y1485838I202J1D01*
G37*
G36*
G01X1710755D02*
X1713575D01*
G02X1713778Y1485635I0J-203D01*
G01Y1485014D01*
G03X1713828Y1484882I200J0D01*
G02Y1481970I-1664J-1456D01*
G03X1713778Y1481838I150J-132D01*
G01Y1479896D01*
G03X1713828Y1479764I200J0D01*
G02Y1476852I-1664J-1456D01*
G03X1713778Y1476720I150J-132D01*
G01Y1476097D01*
G02X1713575Y1475894I-203J0D01*
G01X1710755D01*
G02X1710552Y1476097I0J203D01*
G01Y1476720D01*
G03X1710502Y1476852I-200J0D01*
G02Y1479764I1664J1456D01*
G03X1710552Y1479896I-150J132D01*
G01Y1481838D01*
G03X1710502Y1481970I-200J0D01*
G02Y1484882I1664J1456D01*
G03X1710552Y1485014I-150J132D01*
G01Y1485635D01*
G02X1710755Y1485838I203J0D01*
G37*
G36*
G01X186425D02*
X189245D01*
G02X189448Y1485636I1J-202D01*
G01Y1485014D01*
G03X189498Y1484882I200J0D01*
G02Y1481970I-1664J-1456D01*
G03X189448Y1481838I150J-132D01*
G01Y1479896D01*
G03X189498Y1479764I200J0D01*
G02Y1476852I-1664J-1456D01*
G03X189448Y1476720I150J-132D01*
G01Y1476098D01*
G02X189245Y1475896I-203J1D01*
G01X186425D01*
G02X186222Y1476098I-1J202D01*
G01Y1476720D01*
G03X186172Y1476852I-200J0D01*
G02Y1479764I1664J1456D01*
G03X186222Y1479896I-150J132D01*
G01Y1481838D01*
G03X186172Y1481970I-200J0D01*
G02Y1484882I1664J1456D01*
G03X186222Y1485014I-150J132D01*
G01Y1485636D01*
G02X186425Y1485838I203J-1D01*
G37*
G36*
G01X125795Y1496862D02*
X128615D01*
G02X128818Y1496659I0J-203D01*
G01Y1496037D01*
G03X128868Y1495905I200J0D01*
G02Y1492993I-1664J-1456D01*
G03X128818Y1492861I150J-132D01*
G01Y1490919D01*
G03X128868Y1490787I200J0D01*
G02Y1487875I-1664J-1456D01*
G03X128818Y1487743I150J-132D01*
G01Y1487121D01*
G02X128615Y1486918I-203J0D01*
G01X125795D01*
G02X125592Y1487121I0J203D01*
G01Y1487743D01*
G03X125542Y1487875I-200J0D01*
G02Y1490787I1664J1456D01*
G03X125592Y1490919I-150J132D01*
G01Y1492861D01*
G03X125542Y1492993I-200J0D01*
G02Y1495905I1664J1456D01*
G03X125592Y1496037I-150J132D01*
G01Y1496659D01*
G02X125795Y1496862I203J0D01*
G37*
G36*
G01X143118D02*
X145938D01*
G02X146140Y1496659I-1J-203D01*
G01Y1496039D01*
G03X146190Y1495907I200J0D01*
G02Y1492991I-1661J-1458D01*
G03X146140Y1492859I150J-132D01*
G01Y1490921D01*
G03X146190Y1490789I200J0D01*
G02Y1487873I-1661J-1458D01*
G03X146140Y1487741I150J-132D01*
G01Y1487121D01*
G02X145938Y1486918I-202J-1D01*
G01X143118D01*
G02X142916Y1487121I1J203D01*
G01Y1487741D01*
G03X142866Y1487873I-200J0D01*
G02Y1490789I1661J1458D01*
G03X142916Y1490921I-150J132D01*
G01Y1492859D01*
G03X142866Y1492991I-200J0D01*
G02Y1495907I1661J1458D01*
G03X142916Y1496039I-150J132D01*
G01Y1496659D01*
G02X143118Y1496862I202J1D01*
G37*
G36*
G01X160440D02*
X163260D01*
G02X163462Y1496659I-1J-203D01*
G01Y1496039D01*
G03X163512Y1495907I200J0D01*
G02Y1492991I-1661J-1458D01*
G03X163462Y1492859I150J-132D01*
G01Y1490921D01*
G03X163512Y1490789I200J0D01*
G02Y1487873I-1661J-1458D01*
G03X163462Y1487741I150J-132D01*
G01Y1487121D01*
G02X163260Y1486918I-202J-1D01*
G01X160440D01*
G02X160238Y1487121I1J203D01*
G01Y1487741D01*
G03X160188Y1487873I-200J0D01*
G02Y1490789I1661J1458D01*
G03X160238Y1490921I-150J132D01*
G01Y1492859D01*
G03X160188Y1492991I-200J0D01*
G02Y1495907I1661J1458D01*
G03X160238Y1496039I-150J132D01*
G01Y1496659D01*
G02X160440Y1496862I202J1D01*
G37*
G36*
G01X281700D02*
X284520D01*
G02X284722Y1496659I-1J-203D01*
G01Y1496039D01*
G03X284772Y1495907I200J0D01*
G02Y1492991I-1661J-1458D01*
G03X284722Y1492859I150J-132D01*
G01Y1490921D01*
G03X284772Y1490789I200J0D01*
G02Y1487873I-1661J-1458D01*
G03X284722Y1487741I150J-132D01*
G01Y1487121D01*
G02X284520Y1486918I-202J-1D01*
G01X281700D01*
G02X281498Y1487121I1J203D01*
G01Y1487741D01*
G03X281448Y1487873I-200J0D01*
G02Y1490789I1661J1458D01*
G03X281498Y1490921I-150J132D01*
G01Y1492859D01*
G03X281448Y1492991I-200J0D01*
G02Y1495907I1661J1458D01*
G03X281498Y1496039I-150J132D01*
G01Y1496659D01*
G02X281700Y1496862I202J1D01*
G37*
G36*
G01X299023D02*
X301843D01*
G02X302046Y1496659I0J-203D01*
G01Y1496037D01*
G03X302096Y1495905I200J0D01*
G02Y1492993I-1664J-1456D01*
G03X302046Y1492861I150J-132D01*
G01Y1490919D01*
G03X302096Y1490787I200J0D01*
G02Y1487875I-1664J-1456D01*
G03X302046Y1487743I150J-132D01*
G01Y1487121D01*
G02X301843Y1486918I-203J0D01*
G01X299023D01*
G02X298820Y1487121I0J203D01*
G01Y1487743D01*
G03X298770Y1487875I-200J0D01*
G02Y1490787I1664J1456D01*
G03X298820Y1490919I-150J132D01*
G01Y1492861D01*
G03X298770Y1492993I-200J0D01*
G02Y1495905I1664J1456D01*
G03X298820Y1496037I-150J132D01*
G01Y1496659D01*
G02X299023Y1496862I203J0D01*
G37*
G36*
G01X454929D02*
X457749D01*
G02X457952Y1496659I0J-203D01*
G01Y1496037D01*
G03X458002Y1495905I200J0D01*
G02Y1492993I-1664J-1456D01*
G03X457952Y1492861I150J-132D01*
G01Y1490919D01*
G03X458002Y1490787I200J0D01*
G02Y1487875I-1664J-1456D01*
G03X457952Y1487743I150J-132D01*
G01Y1487121D01*
G02X457749Y1486918I-203J0D01*
G01X454929D01*
G02X454726Y1487121I0J203D01*
G01Y1487743D01*
G03X454676Y1487875I-200J0D01*
G02Y1490787I1664J1456D01*
G03X454726Y1490919I-150J132D01*
G01Y1492861D01*
G03X454676Y1492993I-200J0D01*
G02Y1495905I1664J1456D01*
G03X454726Y1496037I-150J132D01*
G01Y1496659D01*
G02X454929Y1496862I203J0D01*
G37*
G36*
G01X472252D02*
X475072D01*
G02X475274Y1496659I-1J-203D01*
G01Y1496039D01*
G03X475324Y1495907I200J0D01*
G02Y1492991I-1661J-1458D01*
G03X475274Y1492859I150J-132D01*
G01Y1490921D01*
G03X475324Y1490789I200J0D01*
G02Y1487873I-1661J-1458D01*
G03X475274Y1487741I150J-132D01*
G01Y1487121D01*
G02X475072Y1486918I-202J-1D01*
G01X472252D01*
G02X472050Y1487121I1J203D01*
G01Y1487741D01*
G03X472000Y1487873I-200J0D01*
G02Y1490789I1661J1458D01*
G03X472050Y1490921I-150J132D01*
G01Y1492859D01*
G03X472000Y1492991I-200J0D01*
G02Y1495907I1661J1458D01*
G03X472050Y1496039I-150J132D01*
G01Y1496659D01*
G02X472252Y1496862I202J1D01*
G37*
G36*
G01X489575D02*
X492395D01*
G02X492598Y1496659I0J-203D01*
G01Y1496037D01*
G03X492648Y1495905I200J0D01*
G02Y1492993I-1664J-1456D01*
G03X492598Y1492861I150J-132D01*
G01Y1490919D01*
G03X492648Y1490787I200J0D01*
G02Y1487875I-1664J-1456D01*
G03X492598Y1487743I150J-132D01*
G01Y1487121D01*
G02X492395Y1486918I-203J0D01*
G01X489575D01*
G02X489372Y1487121I0J203D01*
G01Y1487743D01*
G03X489322Y1487875I-200J0D01*
G02Y1490787I1664J1456D01*
G03X489372Y1490919I-150J132D01*
G01Y1492861D01*
G03X489322Y1492993I-200J0D01*
G02Y1495905I1664J1456D01*
G03X489372Y1496037I-150J132D01*
G01Y1496659D01*
G02X489575Y1496862I203J0D01*
G37*
G36*
G01X506897D02*
X509717D01*
G02X509920Y1496659I0J-203D01*
G01Y1496037D01*
G03X509970Y1495905I200J0D01*
G02Y1492993I-1664J-1456D01*
G03X509920Y1492861I150J-132D01*
G01Y1490919D01*
G03X509970Y1490787I200J0D01*
G02Y1487875I-1664J-1456D01*
G03X509920Y1487743I150J-132D01*
G01Y1487121D01*
G02X509717Y1486918I-203J0D01*
G01X506897D01*
G02X506694Y1487121I0J203D01*
G01Y1487743D01*
G03X506644Y1487875I-200J0D01*
G02Y1490787I1664J1456D01*
G03X506694Y1490919I-150J132D01*
G01Y1492861D01*
G03X506644Y1492993I-200J0D01*
G02Y1495905I1664J1456D01*
G03X506694Y1496037I-150J132D01*
G01Y1496659D01*
G02X506897Y1496862I203J0D01*
G37*
G36*
G01X645480D02*
X648300D01*
G02X648502Y1496659I-1J-203D01*
G01Y1496039D01*
G03X648552Y1495907I200J0D01*
G02Y1492991I-1661J-1458D01*
G03X648502Y1492859I150J-132D01*
G01Y1490921D01*
G03X648552Y1490789I200J0D01*
G02Y1487873I-1661J-1458D01*
G03X648502Y1487741I150J-132D01*
G01Y1487121D01*
G02X648300Y1486918I-202J-1D01*
G01X645480D01*
G02X645278Y1487121I1J203D01*
G01Y1487741D01*
G03X645228Y1487873I-200J0D01*
G02Y1490789I1661J1458D01*
G03X645278Y1490921I-150J132D01*
G01Y1492859D01*
G03X645228Y1492991I-200J0D01*
G02Y1495907I1661J1458D01*
G03X645278Y1496039I-150J132D01*
G01Y1496659D01*
G02X645480Y1496862I202J1D01*
G37*
G36*
G01X662803D02*
X665623D01*
G02X665826Y1496659I0J-203D01*
G01Y1496037D01*
G03X665876Y1495905I200J0D01*
G02Y1492993I-1664J-1456D01*
G03X665826Y1492861I150J-132D01*
G01Y1490919D01*
G03X665876Y1490787I200J0D01*
G02Y1487875I-1664J-1456D01*
G03X665826Y1487743I150J-132D01*
G01Y1487121D01*
G02X665623Y1486918I-203J0D01*
G01X662803D01*
G02X662600Y1487121I0J203D01*
G01Y1487743D01*
G03X662550Y1487875I-200J0D01*
G02Y1490787I1664J1456D01*
G03X662600Y1490919I-150J132D01*
G01Y1492861D01*
G03X662550Y1492993I-200J0D01*
G02Y1495905I1664J1456D01*
G03X662600Y1496037I-150J132D01*
G01Y1496659D01*
G02X662803Y1496862I203J0D01*
G37*
G36*
G01X680125D02*
X682945D01*
G02X683148Y1496659I0J-203D01*
G01Y1496037D01*
G03X683198Y1495905I200J0D01*
G02Y1492993I-1664J-1456D01*
G03X683148Y1492861I150J-132D01*
G01Y1490919D01*
G03X683198Y1490787I200J0D01*
G02Y1487875I-1664J-1456D01*
G03X683148Y1487743I150J-132D01*
G01Y1487121D01*
G02X682945Y1486918I-203J0D01*
G01X680125D01*
G02X679922Y1487121I0J203D01*
G01Y1487743D01*
G03X679872Y1487875I-200J0D01*
G02Y1490787I1664J1456D01*
G03X679922Y1490919I-150J132D01*
G01Y1492861D01*
G03X679872Y1492993I-200J0D01*
G02Y1495905I1664J1456D01*
G03X679922Y1496037I-150J132D01*
G01Y1496659D01*
G02X680125Y1496862I203J0D01*
G37*
G36*
G01X1165086D02*
X1167906D01*
G02X1168108Y1496659I-1J-203D01*
G01Y1496039D01*
G03X1168158Y1495907I200J0D01*
G02Y1492991I-1661J-1458D01*
G03X1168108Y1492859I150J-132D01*
G01Y1490921D01*
G03X1168158Y1490789I200J0D01*
G02Y1487873I-1661J-1458D01*
G03X1168108Y1487741I150J-132D01*
G01Y1487121D01*
G02X1167906Y1486918I-202J-1D01*
G01X1165086D01*
G02X1164884Y1487121I1J203D01*
G01Y1487741D01*
G03X1164834Y1487873I-200J0D01*
G02Y1490789I1661J1458D01*
G03X1164884Y1490921I-150J132D01*
G01Y1492859D01*
G03X1164834Y1492991I-200J0D01*
G02Y1495907I1661J1458D01*
G03X1164884Y1496039I-150J132D01*
G01Y1496659D01*
G02X1165086Y1496862I202J1D01*
G37*
G36*
G01X1182408D02*
X1185228D01*
G02X1185430Y1496659I-1J-203D01*
G01Y1496039D01*
G03X1185480Y1495907I200J0D01*
G02Y1492991I-1661J-1458D01*
G03X1185430Y1492859I150J-132D01*
G01Y1490921D01*
G03X1185480Y1490789I200J0D01*
G02Y1487873I-1661J-1458D01*
G03X1185430Y1487741I150J-132D01*
G01Y1487121D01*
G02X1185228Y1486918I-202J-1D01*
G01X1182408D01*
G02X1182206Y1487121I1J203D01*
G01Y1487741D01*
G03X1182156Y1487873I-200J0D01*
G02Y1490789I1661J1458D01*
G03X1182206Y1490921I-150J132D01*
G01Y1492859D01*
G03X1182156Y1492991I-200J0D01*
G02Y1495907I1661J1458D01*
G03X1182206Y1496039I-150J132D01*
G01Y1496659D01*
G02X1182408Y1496862I202J1D01*
G37*
G36*
G01X1303669D02*
X1306489D01*
G02X1306692Y1496659I0J-203D01*
G01Y1496037D01*
G03X1306742Y1495905I200J0D01*
G02Y1492993I-1664J-1456D01*
G03X1306692Y1492861I150J-132D01*
G01Y1490919D01*
G03X1306742Y1490787I200J0D01*
G02Y1487875I-1664J-1456D01*
G03X1306692Y1487743I150J-132D01*
G01Y1487121D01*
G02X1306489Y1486918I-203J0D01*
G01X1303669D01*
G02X1303466Y1487121I0J203D01*
G01Y1487743D01*
G03X1303416Y1487875I-200J0D01*
G02Y1490787I1664J1456D01*
G03X1303466Y1490919I-150J132D01*
G01Y1492861D01*
G03X1303416Y1492993I-200J0D01*
G02Y1495905I1664J1456D01*
G03X1303466Y1496037I-150J132D01*
G01Y1496659D01*
G02X1303669Y1496862I203J0D01*
G37*
G36*
G01X1320992D02*
X1323812D01*
G02X1324014Y1496659I-1J-203D01*
G01Y1496039D01*
G03X1324064Y1495907I200J0D01*
G02Y1492991I-1661J-1458D01*
G03X1324014Y1492859I150J-132D01*
G01Y1490921D01*
G03X1324064Y1490789I200J0D01*
G02Y1487873I-1661J-1458D01*
G03X1324014Y1487741I150J-132D01*
G01Y1487121D01*
G02X1323812Y1486918I-202J-1D01*
G01X1320992D01*
G02X1320790Y1487121I1J203D01*
G01Y1487741D01*
G03X1320740Y1487873I-200J0D01*
G02Y1490789I1661J1458D01*
G03X1320790Y1490921I-150J132D01*
G01Y1492859D01*
G03X1320740Y1492991I-200J0D01*
G02Y1495907I1661J1458D01*
G03X1320790Y1496039I-150J132D01*
G01Y1496659D01*
G02X1320992Y1496862I202J1D01*
G37*
G36*
G01X1338315D02*
X1341135D01*
G02X1341338Y1496659I0J-203D01*
G01Y1496037D01*
G03X1341388Y1495905I200J0D01*
G02Y1492993I-1664J-1456D01*
G03X1341338Y1492861I150J-132D01*
G01Y1490919D01*
G03X1341388Y1490787I200J0D01*
G02Y1487875I-1664J-1456D01*
G03X1341338Y1487743I150J-132D01*
G01Y1487121D01*
G02X1341135Y1486918I-203J0D01*
G01X1338315D01*
G02X1338112Y1487121I0J203D01*
G01Y1487743D01*
G03X1338062Y1487875I-200J0D01*
G02Y1490787I1664J1456D01*
G03X1338112Y1490919I-150J132D01*
G01Y1492861D01*
G03X1338062Y1492993I-200J0D01*
G02Y1495905I1664J1456D01*
G03X1338112Y1496037I-150J132D01*
G01Y1496659D01*
G02X1338315Y1496862I203J0D01*
G37*
G36*
G01X1355637D02*
X1358457D01*
G02X1358660Y1496659I0J-203D01*
G01Y1496037D01*
G03X1358710Y1495905I200J0D01*
G02Y1492993I-1664J-1456D01*
G03X1358660Y1492861I150J-132D01*
G01Y1490919D01*
G03X1358710Y1490787I200J0D01*
G02Y1487875I-1664J-1456D01*
G03X1358660Y1487743I150J-132D01*
G01Y1487121D01*
G02X1358457Y1486918I-203J0D01*
G01X1355637D01*
G02X1355434Y1487121I0J203D01*
G01Y1487743D01*
G03X1355384Y1487875I-200J0D01*
G02Y1490787I1664J1456D01*
G03X1355434Y1490919I-150J132D01*
G01Y1492861D01*
G03X1355384Y1492993I-200J0D01*
G02Y1495905I1664J1456D01*
G03X1355434Y1496037I-150J132D01*
G01Y1496659D01*
G02X1355637Y1496862I203J0D01*
G37*
G36*
G01X1476897D02*
X1479717D01*
G02X1479920Y1496659I0J-203D01*
G01Y1496037D01*
G03X1479970Y1495905I200J0D01*
G02Y1492993I-1664J-1456D01*
G03X1479920Y1492861I150J-132D01*
G01Y1490919D01*
G03X1479970Y1490787I200J0D01*
G02Y1487875I-1664J-1456D01*
G03X1479920Y1487743I150J-132D01*
G01Y1487121D01*
G02X1479717Y1486918I-203J0D01*
G01X1476897D01*
G02X1476694Y1487121I0J203D01*
G01Y1487743D01*
G03X1476644Y1487875I-200J0D01*
G02Y1490787I1664J1456D01*
G03X1476694Y1490919I-150J132D01*
G01Y1492861D01*
G03X1476644Y1492993I-200J0D01*
G02Y1495905I1664J1456D01*
G03X1476694Y1496037I-150J132D01*
G01Y1496659D01*
G02X1476897Y1496862I203J0D01*
G37*
G36*
G01X1494220D02*
X1497040D01*
G02X1497242Y1496659I-1J-203D01*
G01Y1496039D01*
G03X1497292Y1495907I200J0D01*
G02Y1492991I-1661J-1458D01*
G03X1497242Y1492859I150J-132D01*
G01Y1490921D01*
G03X1497292Y1490789I200J0D01*
G02Y1487873I-1661J-1458D01*
G03X1497242Y1487741I150J-132D01*
G01Y1487121D01*
G02X1497040Y1486918I-202J-1D01*
G01X1494220D01*
G02X1494018Y1487121I1J203D01*
G01Y1487741D01*
G03X1493968Y1487873I-200J0D01*
G02Y1490789I1661J1458D01*
G03X1494018Y1490921I-150J132D01*
G01Y1492859D01*
G03X1493968Y1492991I-200J0D01*
G02Y1495907I1661J1458D01*
G03X1494018Y1496039I-150J132D01*
G01Y1496659D01*
G02X1494220Y1496862I202J1D01*
G37*
G36*
G01X1511543D02*
X1514363D01*
G02X1514566Y1496659I0J-203D01*
G01Y1496037D01*
G03X1514616Y1495905I200J0D01*
G02Y1492993I-1664J-1456D01*
G03X1514566Y1492861I150J-132D01*
G01Y1490919D01*
G03X1514616Y1490787I200J0D01*
G02Y1487875I-1664J-1456D01*
G03X1514566Y1487743I150J-132D01*
G01Y1487121D01*
G02X1514363Y1486918I-203J0D01*
G01X1511543D01*
G02X1511340Y1487121I0J203D01*
G01Y1487743D01*
G03X1511290Y1487875I-200J0D01*
G02Y1490787I1664J1456D01*
G03X1511340Y1490919I-150J132D01*
G01Y1492861D01*
G03X1511290Y1492993I-200J0D01*
G02Y1495905I1664J1456D01*
G03X1511340Y1496037I-150J132D01*
G01Y1496659D01*
G02X1511543Y1496862I203J0D01*
G37*
G36*
G01X1528865D02*
X1531685D01*
G02X1531888Y1496659I0J-203D01*
G01Y1496037D01*
G03X1531938Y1495905I200J0D01*
G02Y1492993I-1664J-1456D01*
G03X1531888Y1492861I150J-132D01*
G01Y1490919D01*
G03X1531938Y1490787I200J0D01*
G02Y1487875I-1664J-1456D01*
G03X1531888Y1487743I150J-132D01*
G01Y1487121D01*
G02X1531685Y1486918I-203J0D01*
G01X1528865D01*
G02X1528662Y1487121I0J203D01*
G01Y1487743D01*
G03X1528612Y1487875I-200J0D01*
G02Y1490787I1664J1456D01*
G03X1528662Y1490919I-150J132D01*
G01Y1492861D01*
G03X1528612Y1492993I-200J0D01*
G02Y1495905I1664J1456D01*
G03X1528662Y1496037I-150J132D01*
G01Y1496659D01*
G02X1528865Y1496862I203J0D01*
G37*
G36*
G01X1684771D02*
X1687591D01*
G02X1687794Y1496659I0J-203D01*
G01Y1496037D01*
G03X1687844Y1495905I200J0D01*
G02Y1492993I-1664J-1456D01*
G03X1687794Y1492861I150J-132D01*
G01Y1490919D01*
G03X1687844Y1490787I200J0D01*
G02Y1487875I-1664J-1456D01*
G03X1687794Y1487743I150J-132D01*
G01Y1487121D01*
G02X1687591Y1486918I-203J0D01*
G01X1684771D01*
G02X1684568Y1487121I0J203D01*
G01Y1487743D01*
G03X1684518Y1487875I-200J0D01*
G02Y1490787I1664J1456D01*
G03X1684568Y1490919I-150J132D01*
G01Y1492861D01*
G03X1684518Y1492993I-200J0D01*
G02Y1495905I1664J1456D01*
G03X1684568Y1496037I-150J132D01*
G01Y1496659D01*
G02X1684771Y1496862I203J0D01*
G37*
G36*
G01X1702093D02*
X1704913D01*
G02X1705116Y1496659I0J-203D01*
G01Y1496037D01*
G03X1705166Y1495905I200J0D01*
G02Y1492993I-1664J-1456D01*
G03X1705116Y1492861I150J-132D01*
G01Y1490919D01*
G03X1705166Y1490787I200J0D01*
G02Y1487875I-1664J-1456D01*
G03X1705116Y1487743I150J-132D01*
G01Y1487121D01*
G02X1704913Y1486918I-203J0D01*
G01X1702093D01*
G02X1701890Y1487121I0J203D01*
G01Y1487743D01*
G03X1701840Y1487875I-200J0D01*
G02Y1490787I1664J1456D01*
G03X1701890Y1490919I-150J132D01*
G01Y1492861D01*
G03X1701840Y1492993I-200J0D01*
G02Y1495905I1664J1456D01*
G03X1701890Y1496037I-150J132D01*
G01Y1496659D01*
G02X1702093Y1496862I203J0D01*
G37*
G36*
G01X134456Y1501192D02*
X137276D01*
G02X137478Y1500989I-1J-203D01*
G01Y1500370D01*
G03X137528Y1500238I200J0D01*
G02Y1497322I-1661J-1458D01*
G03X137478Y1497190I150J-132D01*
G01Y1495252D01*
G03X137528Y1495120I200J0D01*
G02Y1492204I-1661J-1458D01*
G03X137478Y1492072I150J-132D01*
G01Y1491451D01*
G02X137276Y1491248I-202J-1D01*
G01X134456D01*
G02X134254Y1491451I1J203D01*
G01Y1492072D01*
G03X134204Y1492204I-200J0D01*
G02Y1495120I1661J1458D01*
G03X134254Y1495252I-150J132D01*
G01Y1497190D01*
G03X134204Y1497322I-200J0D01*
G02Y1500238I1661J1458D01*
G03X134254Y1500370I-150J132D01*
G01Y1500989D01*
G02X134456Y1501192I202J1D01*
G37*
G36*
G01X151779D02*
X154599D01*
G02X154802Y1500989I0J-203D01*
G01Y1500368D01*
G03X154852Y1500236I200J0D01*
G02Y1497324I-1664J-1456D01*
G03X154802Y1497192I150J-132D01*
G01Y1495250D01*
G03X154852Y1495118I200J0D01*
G02Y1492206I-1664J-1456D01*
G03X154802Y1492074I150J-132D01*
G01Y1491451D01*
G02X154599Y1491248I-203J0D01*
G01X151779D01*
G02X151576Y1491451I0J203D01*
G01Y1492074D01*
G03X151526Y1492206I-200J0D01*
G02Y1495118I1664J1456D01*
G03X151576Y1495250I-150J132D01*
G01Y1497192D01*
G03X151526Y1497324I-200J0D01*
G02Y1500236I1664J1456D01*
G03X151576Y1500368I-150J132D01*
G01Y1500989D01*
G02X151779Y1501192I203J0D01*
G37*
G36*
G01X169102D02*
X171922D01*
G02X172124Y1500989I-1J-203D01*
G01Y1500370D01*
G03X172174Y1500238I200J0D01*
G02Y1497322I-1661J-1458D01*
G03X172124Y1497190I150J-132D01*
G01Y1495252D01*
G03X172174Y1495120I200J0D01*
G02Y1492204I-1661J-1458D01*
G03X172124Y1492072I150J-132D01*
G01Y1491451D01*
G02X171922Y1491248I-202J-1D01*
G01X169102D01*
G02X168900Y1491451I1J203D01*
G01Y1492072D01*
G03X168850Y1492204I-200J0D01*
G02Y1495120I1661J1458D01*
G03X168900Y1495252I-150J132D01*
G01Y1497190D01*
G03X168850Y1497322I-200J0D01*
G02Y1500238I1661J1458D01*
G03X168900Y1500370I-150J132D01*
G01Y1500989D01*
G02X169102Y1501192I202J1D01*
G37*
G36*
G01X290361D02*
X293181D01*
G02X293384Y1500989I0J-203D01*
G01Y1500368D01*
G03X293434Y1500236I200J0D01*
G02Y1497324I-1664J-1456D01*
G03X293384Y1497192I150J-132D01*
G01Y1495250D01*
G03X293434Y1495118I200J0D01*
G02Y1492206I-1664J-1456D01*
G03X293384Y1492074I150J-132D01*
G01Y1491451D01*
G02X293181Y1491248I-203J0D01*
G01X290361D01*
G02X290158Y1491451I0J203D01*
G01Y1492074D01*
G03X290108Y1492206I-200J0D01*
G02Y1495118I1664J1456D01*
G03X290158Y1495250I-150J132D01*
G01Y1497192D01*
G03X290108Y1497324I-200J0D01*
G02Y1500236I1664J1456D01*
G03X290158Y1500368I-150J132D01*
G01Y1500989D01*
G02X290361Y1501192I203J0D01*
G37*
G36*
G01X463590D02*
X466410D01*
G02X466612Y1500989I-1J-203D01*
G01Y1500370D01*
G03X466662Y1500238I200J0D01*
G02Y1497322I-1661J-1458D01*
G03X466612Y1497190I150J-132D01*
G01Y1495252D01*
G03X466662Y1495120I200J0D01*
G02Y1492204I-1661J-1458D01*
G03X466612Y1492072I150J-132D01*
G01Y1491451D01*
G02X466410Y1491248I-202J-1D01*
G01X463590D01*
G02X463388Y1491451I1J203D01*
G01Y1492072D01*
G03X463338Y1492204I-200J0D01*
G02Y1495120I1661J1458D01*
G03X463388Y1495252I-150J132D01*
G01Y1497190D01*
G03X463338Y1497322I-200J0D01*
G02Y1500238I1661J1458D01*
G03X463388Y1500370I-150J132D01*
G01Y1500989D01*
G02X463590Y1501192I202J1D01*
G37*
G36*
G01X480913D02*
X483733D01*
G02X483936Y1500989I0J-203D01*
G01Y1500368D01*
G03X483986Y1500236I200J0D01*
G02Y1497324I-1664J-1456D01*
G03X483936Y1497192I150J-132D01*
G01Y1495250D01*
G03X483986Y1495118I200J0D01*
G02Y1492206I-1664J-1456D01*
G03X483936Y1492074I150J-132D01*
G01Y1491451D01*
G02X483733Y1491248I-203J0D01*
G01X480913D01*
G02X480710Y1491451I0J203D01*
G01Y1492074D01*
G03X480660Y1492206I-200J0D01*
G02Y1495118I1664J1456D01*
G03X480710Y1495250I-150J132D01*
G01Y1497192D01*
G03X480660Y1497324I-200J0D01*
G02Y1500236I1664J1456D01*
G03X480710Y1500368I-150J132D01*
G01Y1500989D01*
G02X480913Y1501192I203J0D01*
G37*
G36*
G01X498236D02*
X501056D01*
G02X501258Y1500989I-1J-203D01*
G01Y1500370D01*
G03X501308Y1500238I200J0D01*
G02Y1497322I-1661J-1458D01*
G03X501258Y1497190I150J-132D01*
G01Y1495252D01*
G03X501308Y1495120I200J0D01*
G02Y1492204I-1661J-1458D01*
G03X501258Y1492072I150J-132D01*
G01Y1491451D01*
G02X501056Y1491248I-202J-1D01*
G01X498236D01*
G02X498034Y1491451I1J203D01*
G01Y1492072D01*
G03X497984Y1492204I-200J0D01*
G02Y1495120I1661J1458D01*
G03X498034Y1495252I-150J132D01*
G01Y1497190D01*
G03X497984Y1497322I-200J0D01*
G02Y1500238I1661J1458D01*
G03X498034Y1500370I-150J132D01*
G01Y1500989D01*
G02X498236Y1501192I202J1D01*
G37*
G36*
G01X515559D02*
X518379D01*
G02X518582Y1500989I0J-203D01*
G01Y1500368D01*
G03X518632Y1500236I200J0D01*
G02Y1497324I-1664J-1456D01*
G03X518582Y1497192I150J-132D01*
G01Y1495250D01*
G03X518632Y1495118I200J0D01*
G02Y1492206I-1664J-1456D01*
G03X518582Y1492074I150J-132D01*
G01Y1491451D01*
G02X518379Y1491248I-203J0D01*
G01X515559D01*
G02X515356Y1491451I0J203D01*
G01Y1492074D01*
G03X515306Y1492206I-200J0D01*
G02Y1495118I1664J1456D01*
G03X515356Y1495250I-150J132D01*
G01Y1497192D01*
G03X515306Y1497324I-200J0D01*
G02Y1500236I1664J1456D01*
G03X515356Y1500368I-150J132D01*
G01Y1500989D01*
G02X515559Y1501192I203J0D01*
G37*
G36*
G01X654141D02*
X656961D01*
G02X657164Y1500989I0J-203D01*
G01Y1500368D01*
G03X657214Y1500236I200J0D01*
G02Y1497324I-1664J-1456D01*
G03X657164Y1497192I150J-132D01*
G01Y1495250D01*
G03X657214Y1495118I200J0D01*
G02Y1492206I-1664J-1456D01*
G03X657164Y1492074I150J-132D01*
G01Y1491451D01*
G02X656961Y1491248I-203J0D01*
G01X654141D01*
G02X653938Y1491451I0J203D01*
G01Y1492074D01*
G03X653888Y1492206I-200J0D01*
G02Y1495118I1664J1456D01*
G03X653938Y1495250I-150J132D01*
G01Y1497192D01*
G03X653888Y1497324I-200J0D01*
G02Y1500236I1664J1456D01*
G03X653938Y1500368I-150J132D01*
G01Y1500989D01*
G02X654141Y1501192I203J0D01*
G37*
G36*
G01X671464D02*
X674284D01*
G02X674486Y1500989I-1J-203D01*
G01Y1500370D01*
G03X674536Y1500238I200J0D01*
G02Y1497322I-1661J-1458D01*
G03X674486Y1497190I150J-132D01*
G01Y1495252D01*
G03X674536Y1495120I200J0D01*
G02Y1492204I-1661J-1458D01*
G03X674486Y1492072I150J-132D01*
G01Y1491451D01*
G02X674284Y1491248I-202J-1D01*
G01X671464D01*
G02X671262Y1491451I1J203D01*
G01Y1492072D01*
G03X671212Y1492204I-200J0D01*
G02Y1495120I1661J1458D01*
G03X671262Y1495252I-150J132D01*
G01Y1497190D01*
G03X671212Y1497322I-200J0D01*
G02Y1500238I1661J1458D01*
G03X671262Y1500370I-150J132D01*
G01Y1500989D01*
G02X671464Y1501192I202J1D01*
G37*
G36*
G01X688787D02*
X691607D01*
G02X691810Y1500989I0J-203D01*
G01Y1500368D01*
G03X691860Y1500236I200J0D01*
G02Y1497324I-1664J-1456D01*
G03X691810Y1497192I150J-132D01*
G01Y1495250D01*
G03X691860Y1495118I200J0D01*
G02Y1492206I-1664J-1456D01*
G03X691810Y1492074I150J-132D01*
G01Y1491451D01*
G02X691607Y1491248I-203J0D01*
G01X688787D01*
G02X688584Y1491451I0J203D01*
G01Y1492074D01*
G03X688534Y1492206I-200J0D01*
G02Y1495118I1664J1456D01*
G03X688584Y1495250I-150J132D01*
G01Y1497192D01*
G03X688534Y1497324I-200J0D01*
G02Y1500236I1664J1456D01*
G03X688584Y1500368I-150J132D01*
G01Y1500989D01*
G02X688787Y1501192I203J0D01*
G37*
G36*
G01X1173747D02*
X1176567D01*
G02X1176770Y1500989I0J-203D01*
G01Y1500368D01*
G03X1176820Y1500236I200J0D01*
G02Y1497324I-1664J-1456D01*
G03X1176770Y1497192I150J-132D01*
G01Y1495250D01*
G03X1176820Y1495118I200J0D01*
G02Y1492206I-1664J-1456D01*
G03X1176770Y1492074I150J-132D01*
G01Y1491451D01*
G02X1176567Y1491248I-203J0D01*
G01X1173747D01*
G02X1173544Y1491451I0J203D01*
G01Y1492074D01*
G03X1173494Y1492206I-200J0D01*
G02Y1495118I1664J1456D01*
G03X1173544Y1495250I-150J132D01*
G01Y1497192D01*
G03X1173494Y1497324I-200J0D01*
G02Y1500236I1664J1456D01*
G03X1173544Y1500368I-150J132D01*
G01Y1500989D01*
G02X1173747Y1501192I203J0D01*
G37*
G36*
G01X1191070D02*
X1193890D01*
G02X1194092Y1500989I-1J-203D01*
G01Y1500370D01*
G03X1194142Y1500238I200J0D01*
G02Y1497322I-1661J-1458D01*
G03X1194092Y1497190I150J-132D01*
G01Y1495252D01*
G03X1194142Y1495120I200J0D01*
G02Y1492204I-1661J-1458D01*
G03X1194092Y1492072I150J-132D01*
G01Y1491451D01*
G02X1193890Y1491248I-202J-1D01*
G01X1191070D01*
G02X1190868Y1491451I1J203D01*
G01Y1492072D01*
G03X1190818Y1492204I-200J0D01*
G02Y1495120I1661J1458D01*
G03X1190868Y1495252I-150J132D01*
G01Y1497190D01*
G03X1190818Y1497322I-200J0D01*
G02Y1500238I1661J1458D01*
G03X1190868Y1500370I-150J132D01*
G01Y1500989D01*
G02X1191070Y1501192I202J1D01*
G37*
G36*
G01X1312330D02*
X1315150D01*
G02X1315352Y1500989I-1J-203D01*
G01Y1500370D01*
G03X1315402Y1500238I200J0D01*
G02Y1497322I-1661J-1458D01*
G03X1315352Y1497190I150J-132D01*
G01Y1495252D01*
G03X1315402Y1495120I200J0D01*
G02Y1492204I-1661J-1458D01*
G03X1315352Y1492072I150J-132D01*
G01Y1491451D01*
G02X1315150Y1491248I-202J-1D01*
G01X1312330D01*
G02X1312128Y1491451I1J203D01*
G01Y1492072D01*
G03X1312078Y1492204I-200J0D01*
G02Y1495120I1661J1458D01*
G03X1312128Y1495252I-150J132D01*
G01Y1497190D01*
G03X1312078Y1497322I-200J0D01*
G02Y1500238I1661J1458D01*
G03X1312128Y1500370I-150J132D01*
G01Y1500989D01*
G02X1312330Y1501192I202J1D01*
G37*
G36*
G01X1329653D02*
X1332473D01*
G02X1332676Y1500989I0J-203D01*
G01Y1500368D01*
G03X1332726Y1500236I200J0D01*
G02Y1497324I-1664J-1456D01*
G03X1332676Y1497192I150J-132D01*
G01Y1495250D01*
G03X1332726Y1495118I200J0D01*
G02Y1492206I-1664J-1456D01*
G03X1332676Y1492074I150J-132D01*
G01Y1491451D01*
G02X1332473Y1491248I-203J0D01*
G01X1329653D01*
G02X1329450Y1491451I0J203D01*
G01Y1492074D01*
G03X1329400Y1492206I-200J0D01*
G02Y1495118I1664J1456D01*
G03X1329450Y1495250I-150J132D01*
G01Y1497192D01*
G03X1329400Y1497324I-200J0D01*
G02Y1500236I1664J1456D01*
G03X1329450Y1500368I-150J132D01*
G01Y1500989D01*
G02X1329653Y1501192I203J0D01*
G37*
G36*
G01X1346976D02*
X1349796D01*
G02X1349998Y1500989I-1J-203D01*
G01Y1500370D01*
G03X1350048Y1500238I200J0D01*
G02Y1497322I-1661J-1458D01*
G03X1349998Y1497190I150J-132D01*
G01Y1495252D01*
G03X1350048Y1495120I200J0D01*
G02Y1492204I-1661J-1458D01*
G03X1349998Y1492072I150J-132D01*
G01Y1491451D01*
G02X1349796Y1491248I-202J-1D01*
G01X1346976D01*
G02X1346774Y1491451I1J203D01*
G01Y1492072D01*
G03X1346724Y1492204I-200J0D01*
G02Y1495120I1661J1458D01*
G03X1346774Y1495252I-150J132D01*
G01Y1497190D01*
G03X1346724Y1497322I-200J0D01*
G02Y1500238I1661J1458D01*
G03X1346774Y1500370I-150J132D01*
G01Y1500989D01*
G02X1346976Y1501192I202J1D01*
G37*
G36*
G01X1364299D02*
X1367119D01*
G02X1367322Y1500989I0J-203D01*
G01Y1500368D01*
G03X1367372Y1500236I200J0D01*
G02Y1497324I-1664J-1456D01*
G03X1367322Y1497192I150J-132D01*
G01Y1495250D01*
G03X1367372Y1495118I200J0D01*
G02Y1492206I-1664J-1456D01*
G03X1367322Y1492074I150J-132D01*
G01Y1491451D01*
G02X1367119Y1491248I-203J0D01*
G01X1364299D01*
G02X1364096Y1491451I0J203D01*
G01Y1492074D01*
G03X1364046Y1492206I-200J0D01*
G02Y1495118I1664J1456D01*
G03X1364096Y1495250I-150J132D01*
G01Y1497192D01*
G03X1364046Y1497324I-200J0D01*
G02Y1500236I1664J1456D01*
G03X1364096Y1500368I-150J132D01*
G01Y1500989D01*
G02X1364299Y1501192I203J0D01*
G37*
G36*
G01X1485558D02*
X1488378D01*
G02X1488580Y1500989I-1J-203D01*
G01Y1500370D01*
G03X1488630Y1500238I200J0D01*
G02Y1497322I-1661J-1458D01*
G03X1488580Y1497190I150J-132D01*
G01Y1495252D01*
G03X1488630Y1495120I200J0D01*
G02Y1492204I-1661J-1458D01*
G03X1488580Y1492072I150J-132D01*
G01Y1491451D01*
G02X1488378Y1491248I-202J-1D01*
G01X1485558D01*
G02X1485356Y1491451I1J203D01*
G01Y1492072D01*
G03X1485306Y1492204I-200J0D01*
G02Y1495120I1661J1458D01*
G03X1485356Y1495252I-150J132D01*
G01Y1497190D01*
G03X1485306Y1497322I-200J0D01*
G02Y1500238I1661J1458D01*
G03X1485356Y1500370I-150J132D01*
G01Y1500989D01*
G02X1485558Y1501192I202J1D01*
G37*
G36*
G01X1502881D02*
X1505701D01*
G02X1505904Y1500989I0J-203D01*
G01Y1500368D01*
G03X1505954Y1500236I200J0D01*
G02Y1497324I-1664J-1456D01*
G03X1505904Y1497192I150J-132D01*
G01Y1495250D01*
G03X1505954Y1495118I200J0D01*
G02Y1492206I-1664J-1456D01*
G03X1505904Y1492074I150J-132D01*
G01Y1491451D01*
G02X1505701Y1491248I-203J0D01*
G01X1502881D01*
G02X1502678Y1491451I0J203D01*
G01Y1492074D01*
G03X1502628Y1492206I-200J0D01*
G02Y1495118I1664J1456D01*
G03X1502678Y1495250I-150J132D01*
G01Y1497192D01*
G03X1502628Y1497324I-200J0D01*
G02Y1500236I1664J1456D01*
G03X1502678Y1500368I-150J132D01*
G01Y1500989D01*
G02X1502881Y1501192I203J0D01*
G37*
G36*
G01X1520204D02*
X1523024D01*
G02X1523226Y1500989I-1J-203D01*
G01Y1500370D01*
G03X1523276Y1500238I200J0D01*
G02Y1497322I-1661J-1458D01*
G03X1523226Y1497190I150J-132D01*
G01Y1495252D01*
G03X1523276Y1495120I200J0D01*
G02Y1492204I-1661J-1458D01*
G03X1523226Y1492072I150J-132D01*
G01Y1491451D01*
G02X1523024Y1491248I-202J-1D01*
G01X1520204D01*
G02X1520002Y1491451I1J203D01*
G01Y1492072D01*
G03X1519952Y1492204I-200J0D01*
G02Y1495120I1661J1458D01*
G03X1520002Y1495252I-150J132D01*
G01Y1497190D01*
G03X1519952Y1497322I-200J0D01*
G02Y1500238I1661J1458D01*
G03X1520002Y1500370I-150J132D01*
G01Y1500989D01*
G02X1520204Y1501192I202J1D01*
G37*
G36*
G01X1537527D02*
X1540347D01*
G02X1540550Y1500989I0J-203D01*
G01Y1500368D01*
G03X1540600Y1500236I200J0D01*
G02Y1497324I-1664J-1456D01*
G03X1540550Y1497192I150J-132D01*
G01Y1495250D01*
G03X1540600Y1495118I200J0D01*
G02Y1492206I-1664J-1456D01*
G03X1540550Y1492074I150J-132D01*
G01Y1491451D01*
G02X1540347Y1491248I-203J0D01*
G01X1537527D01*
G02X1537324Y1491451I0J203D01*
G01Y1492074D01*
G03X1537274Y1492206I-200J0D01*
G02Y1495118I1664J1456D01*
G03X1537324Y1495250I-150J132D01*
G01Y1497192D01*
G03X1537274Y1497324I-200J0D01*
G02Y1500236I1664J1456D01*
G03X1537324Y1500368I-150J132D01*
G01Y1500989D01*
G02X1537527Y1501192I203J0D01*
G37*
G36*
G01X1693432D02*
X1696252D01*
G02X1696454Y1500989I-1J-203D01*
G01Y1500370D01*
G03X1696504Y1500238I200J0D01*
G02Y1497322I-1661J-1458D01*
G03X1696454Y1497190I150J-132D01*
G01Y1495252D01*
G03X1696504Y1495120I200J0D01*
G02Y1492204I-1661J-1458D01*
G03X1696454Y1492072I150J-132D01*
G01Y1491451D01*
G02X1696252Y1491248I-202J-1D01*
G01X1693432D01*
G02X1693230Y1491451I1J203D01*
G01Y1492072D01*
G03X1693180Y1492204I-200J0D01*
G02Y1495120I1661J1458D01*
G03X1693230Y1495252I-150J132D01*
G01Y1497190D01*
G03X1693180Y1497322I-200J0D01*
G02Y1500238I1661J1458D01*
G03X1693230Y1500370I-150J132D01*
G01Y1500989D01*
G02X1693432Y1501192I202J1D01*
G37*
G36*
G01X1710755D02*
X1713575D01*
G02X1713778Y1500989I0J-203D01*
G01Y1500368D01*
G03X1713828Y1500236I200J0D01*
G02Y1497324I-1664J-1456D01*
G03X1713778Y1497192I150J-132D01*
G01Y1495250D01*
G03X1713828Y1495118I200J0D01*
G02Y1492206I-1664J-1456D01*
G03X1713778Y1492074I150J-132D01*
G01Y1491451D01*
G02X1713575Y1491248I-203J0D01*
G01X1710755D01*
G02X1710552Y1491451I0J203D01*
G01Y1492074D01*
G03X1710502Y1492206I-200J0D01*
G02Y1495118I1664J1456D01*
G03X1710552Y1495250I-150J132D01*
G01Y1497192D01*
G03X1710502Y1497324I-200J0D01*
G02Y1500236I1664J1456D01*
G03X1710552Y1500368I-150J132D01*
G01Y1500989D01*
G02X1710755Y1501192I203J0D01*
G37*
G36*
G01X143118Y1512216D02*
X145938D01*
G02X146140Y1512014I0J-202D01*
G01Y1511394D01*
G03X146190Y1511262I200J0D01*
G02Y1508346I-1661J-1458D01*
G03X146140Y1508214I150J-132D01*
G01Y1506275D01*
G03X146190Y1506143I200J0D01*
G02Y1503227I-1661J-1458D01*
G03X146140Y1503095I150J-132D01*
G01Y1502476D01*
G02X145938Y1502274I-202J0D01*
G01X143118D01*
G02X142916Y1502476I0J202D01*
G01Y1503095D01*
G03X142866Y1503227I-200J0D01*
G02Y1506143I1661J1458D01*
G03X142916Y1506275I-150J132D01*
G01Y1508214D01*
G03X142866Y1508346I-200J0D01*
G02Y1511262I1661J1458D01*
G03X142916Y1511394I-150J132D01*
G01Y1512014D01*
G02X143118Y1512216I202J0D01*
G37*
G36*
G01X160440D02*
X163260D01*
G02X163462Y1512014I0J-202D01*
G01Y1511394D01*
G03X163512Y1511262I200J0D01*
G02Y1508346I-1661J-1458D01*
G03X163462Y1508214I150J-132D01*
G01Y1506275D01*
G03X163512Y1506143I200J0D01*
G02Y1503227I-1661J-1458D01*
G03X163462Y1503095I150J-132D01*
G01Y1502476D01*
G02X163260Y1502274I-202J0D01*
G01X160440D01*
G02X160238Y1502476I0J202D01*
G01Y1503095D01*
G03X160188Y1503227I-200J0D01*
G02Y1506143I1661J1458D01*
G03X160238Y1506275I-150J132D01*
G01Y1508214D01*
G03X160188Y1508346I-200J0D01*
G02Y1511262I1661J1458D01*
G03X160238Y1511394I-150J132D01*
G01Y1512014D01*
G02X160440Y1512216I202J0D01*
G37*
G36*
G01X281700D02*
X284520D01*
G02X284722Y1512014I0J-202D01*
G01Y1511394D01*
G03X284772Y1511262I200J0D01*
G02Y1508346I-1661J-1458D01*
G03X284722Y1508214I150J-132D01*
G01Y1506275D01*
G03X284772Y1506143I200J0D01*
G02Y1503227I-1661J-1458D01*
G03X284722Y1503095I150J-132D01*
G01Y1502476D01*
G02X284520Y1502274I-202J0D01*
G01X281700D01*
G02X281498Y1502476I0J202D01*
G01Y1503095D01*
G03X281448Y1503227I-200J0D01*
G02Y1506143I1661J1458D01*
G03X281498Y1506275I-150J132D01*
G01Y1508214D01*
G03X281448Y1508346I-200J0D01*
G02Y1511262I1661J1458D01*
G03X281498Y1511394I-150J132D01*
G01Y1512014D01*
G02X281700Y1512216I202J0D01*
G37*
G36*
G01X472252D02*
X475072D01*
G02X475274Y1512014I0J-202D01*
G01Y1511394D01*
G03X475324Y1511262I200J0D01*
G02Y1508346I-1661J-1458D01*
G03X475274Y1508214I150J-132D01*
G01Y1506275D01*
G03X475324Y1506143I200J0D01*
G02Y1503227I-1661J-1458D01*
G03X475274Y1503095I150J-132D01*
G01Y1502476D01*
G02X475072Y1502274I-202J0D01*
G01X472252D01*
G02X472050Y1502476I0J202D01*
G01Y1503095D01*
G03X472000Y1503227I-200J0D01*
G02Y1506143I1661J1458D01*
G03X472050Y1506275I-150J132D01*
G01Y1508214D01*
G03X472000Y1508346I-200J0D01*
G02Y1511262I1661J1458D01*
G03X472050Y1511394I-150J132D01*
G01Y1512014D01*
G02X472252Y1512216I202J0D01*
G37*
G36*
G01X645480D02*
X648300D01*
G02X648502Y1512014I0J-202D01*
G01Y1511394D01*
G03X648552Y1511262I200J0D01*
G02Y1508346I-1661J-1458D01*
G03X648502Y1508214I150J-132D01*
G01Y1506275D01*
G03X648552Y1506143I200J0D01*
G02Y1503227I-1661J-1458D01*
G03X648502Y1503095I150J-132D01*
G01Y1502476D01*
G02X648300Y1502274I-202J0D01*
G01X645480D01*
G02X645278Y1502476I0J202D01*
G01Y1503095D01*
G03X645228Y1503227I-200J0D01*
G02Y1506143I1661J1458D01*
G03X645278Y1506275I-150J132D01*
G01Y1508214D01*
G03X645228Y1508346I-200J0D01*
G02Y1511262I1661J1458D01*
G03X645278Y1511394I-150J132D01*
G01Y1512014D01*
G02X645480Y1512216I202J0D01*
G37*
G36*
G01X1165086D02*
X1167906D01*
G02X1168108Y1512014I0J-202D01*
G01Y1511394D01*
G03X1168158Y1511262I200J0D01*
G02Y1508346I-1661J-1458D01*
G03X1168108Y1508214I150J-132D01*
G01Y1506275D01*
G03X1168158Y1506143I200J0D01*
G02Y1503227I-1661J-1458D01*
G03X1168108Y1503095I150J-132D01*
G01Y1502476D01*
G02X1167906Y1502274I-202J0D01*
G01X1165086D01*
G02X1164884Y1502476I0J202D01*
G01Y1503095D01*
G03X1164834Y1503227I-200J0D01*
G02Y1506143I1661J1458D01*
G03X1164884Y1506275I-150J132D01*
G01Y1508214D01*
G03X1164834Y1508346I-200J0D01*
G02Y1511262I1661J1458D01*
G03X1164884Y1511394I-150J132D01*
G01Y1512014D01*
G02X1165086Y1512216I202J0D01*
G37*
G36*
G01X1182408D02*
X1185228D01*
G02X1185430Y1512014I0J-202D01*
G01Y1511394D01*
G03X1185480Y1511262I200J0D01*
G02Y1508346I-1661J-1458D01*
G03X1185430Y1508214I150J-132D01*
G01Y1506275D01*
G03X1185480Y1506143I200J0D01*
G02Y1503227I-1661J-1458D01*
G03X1185430Y1503095I150J-132D01*
G01Y1502476D01*
G02X1185228Y1502274I-202J0D01*
G01X1182408D01*
G02X1182206Y1502476I0J202D01*
G01Y1503095D01*
G03X1182156Y1503227I-200J0D01*
G02Y1506143I1661J1458D01*
G03X1182206Y1506275I-150J132D01*
G01Y1508214D01*
G03X1182156Y1508346I-200J0D01*
G02Y1511262I1661J1458D01*
G03X1182206Y1511394I-150J132D01*
G01Y1512014D01*
G02X1182408Y1512216I202J0D01*
G37*
G36*
G01X1320992D02*
X1323812D01*
G02X1324014Y1512014I0J-202D01*
G01Y1511394D01*
G03X1324064Y1511262I200J0D01*
G02Y1508346I-1661J-1458D01*
G03X1324014Y1508214I150J-132D01*
G01Y1506275D01*
G03X1324064Y1506143I200J0D01*
G02Y1503227I-1661J-1458D01*
G03X1324014Y1503095I150J-132D01*
G01Y1502476D01*
G02X1323812Y1502274I-202J0D01*
G01X1320992D01*
G02X1320790Y1502476I0J202D01*
G01Y1503095D01*
G03X1320740Y1503227I-200J0D01*
G02Y1506143I1661J1458D01*
G03X1320790Y1506275I-150J132D01*
G01Y1508214D01*
G03X1320740Y1508346I-200J0D01*
G02Y1511262I1661J1458D01*
G03X1320790Y1511394I-150J132D01*
G01Y1512014D01*
G02X1320992Y1512216I202J0D01*
G37*
G36*
G01X1494220D02*
X1497040D01*
G02X1497242Y1512014I0J-202D01*
G01Y1511394D01*
G03X1497292Y1511262I200J0D01*
G02Y1508346I-1661J-1458D01*
G03X1497242Y1508214I150J-132D01*
G01Y1506275D01*
G03X1497292Y1506143I200J0D01*
G02Y1503227I-1661J-1458D01*
G03X1497242Y1503095I150J-132D01*
G01Y1502476D01*
G02X1497040Y1502274I-202J0D01*
G01X1494220D01*
G02X1494018Y1502476I0J202D01*
G01Y1503095D01*
G03X1493968Y1503227I-200J0D01*
G02Y1506143I1661J1458D01*
G03X1494018Y1506275I-150J132D01*
G01Y1508214D01*
G03X1493968Y1508346I-200J0D01*
G02Y1511262I1661J1458D01*
G03X1494018Y1511394I-150J132D01*
G01Y1512014D01*
G02X1494220Y1512216I202J0D01*
G37*
G36*
G01X125795D02*
X128615D01*
G02X128818Y1512014I1J-202D01*
G01Y1511392D01*
G03X128868Y1511260I200J0D01*
G02Y1508348I-1664J-1456D01*
G03X128818Y1508216I150J-132D01*
G01Y1506273D01*
G03X128868Y1506141I200J0D01*
G02Y1503229I-1664J-1456D01*
G03X128818Y1503097I150J-132D01*
G01Y1502476D01*
G02X128615Y1502274I-203J1D01*
G01X125795D01*
G02X125592Y1502476I-1J202D01*
G01Y1503097D01*
G03X125542Y1503229I-200J0D01*
G02Y1506141I1664J1456D01*
G03X125592Y1506273I-150J132D01*
G01Y1508216D01*
G03X125542Y1508348I-200J0D01*
G02Y1511260I1664J1456D01*
G03X125592Y1511392I-150J132D01*
G01Y1512014D01*
G02X125795Y1512216I203J-1D01*
G37*
G36*
G01X299023D02*
X301843D01*
G02X302046Y1512014I1J-202D01*
G01Y1511392D01*
G03X302096Y1511260I200J0D01*
G02Y1508348I-1664J-1456D01*
G03X302046Y1508216I150J-132D01*
G01Y1506273D01*
G03X302096Y1506141I200J0D01*
G02Y1503229I-1664J-1456D01*
G03X302046Y1503097I150J-132D01*
G01Y1502476D01*
G02X301843Y1502274I-203J1D01*
G01X299023D01*
G02X298820Y1502476I-1J202D01*
G01Y1503097D01*
G03X298770Y1503229I-200J0D01*
G02Y1506141I1664J1456D01*
G03X298820Y1506273I-150J132D01*
G01Y1508216D01*
G03X298770Y1508348I-200J0D01*
G02Y1511260I1664J1456D01*
G03X298820Y1511392I-150J132D01*
G01Y1512014D01*
G02X299023Y1512216I203J-1D01*
G37*
G36*
G01X454929D02*
X457749D01*
G02X457952Y1512014I1J-202D01*
G01Y1511392D01*
G03X458002Y1511260I200J0D01*
G02Y1508348I-1664J-1456D01*
G03X457952Y1508216I150J-132D01*
G01Y1506273D01*
G03X458002Y1506141I200J0D01*
G02Y1503229I-1664J-1456D01*
G03X457952Y1503097I150J-132D01*
G01Y1502476D01*
G02X457749Y1502274I-203J1D01*
G01X454929D01*
G02X454726Y1502476I-1J202D01*
G01Y1503097D01*
G03X454676Y1503229I-200J0D01*
G02Y1506141I1664J1456D01*
G03X454726Y1506273I-150J132D01*
G01Y1508216D01*
G03X454676Y1508348I-200J0D01*
G02Y1511260I1664J1456D01*
G03X454726Y1511392I-150J132D01*
G01Y1512014D01*
G02X454929Y1512216I203J-1D01*
G37*
G36*
G01X489575D02*
X492395D01*
G02X492598Y1512014I1J-202D01*
G01Y1511392D01*
G03X492648Y1511260I200J0D01*
G02Y1508348I-1664J-1456D01*
G03X492598Y1508216I150J-132D01*
G01Y1506273D01*
G03X492648Y1506141I200J0D01*
G02Y1503229I-1664J-1456D01*
G03X492598Y1503097I150J-132D01*
G01Y1502476D01*
G02X492395Y1502274I-203J1D01*
G01X489575D01*
G02X489372Y1502476I-1J202D01*
G01Y1503097D01*
G03X489322Y1503229I-200J0D01*
G02Y1506141I1664J1456D01*
G03X489372Y1506273I-150J132D01*
G01Y1508216D01*
G03X489322Y1508348I-200J0D01*
G02Y1511260I1664J1456D01*
G03X489372Y1511392I-150J132D01*
G01Y1512014D01*
G02X489575Y1512216I203J-1D01*
G37*
G36*
G01X506897D02*
X509717D01*
G02X509920Y1512014I1J-202D01*
G01Y1511392D01*
G03X509970Y1511260I200J0D01*
G02Y1508348I-1664J-1456D01*
G03X509920Y1508216I150J-132D01*
G01Y1506273D01*
G03X509970Y1506141I200J0D01*
G02Y1503229I-1664J-1456D01*
G03X509920Y1503097I150J-132D01*
G01Y1502476D01*
G02X509717Y1502274I-203J1D01*
G01X506897D01*
G02X506694Y1502476I-1J202D01*
G01Y1503097D01*
G03X506644Y1503229I-200J0D01*
G02Y1506141I1664J1456D01*
G03X506694Y1506273I-150J132D01*
G01Y1508216D01*
G03X506644Y1508348I-200J0D01*
G02Y1511260I1664J1456D01*
G03X506694Y1511392I-150J132D01*
G01Y1512014D01*
G02X506897Y1512216I203J-1D01*
G37*
G36*
G01X662803D02*
X665623D01*
G02X665826Y1512014I1J-202D01*
G01Y1511392D01*
G03X665876Y1511260I200J0D01*
G02Y1508348I-1664J-1456D01*
G03X665826Y1508216I150J-132D01*
G01Y1506273D01*
G03X665876Y1506141I200J0D01*
G02Y1503229I-1664J-1456D01*
G03X665826Y1503097I150J-132D01*
G01Y1502476D01*
G02X665623Y1502274I-203J1D01*
G01X662803D01*
G02X662600Y1502476I-1J202D01*
G01Y1503097D01*
G03X662550Y1503229I-200J0D01*
G02Y1506141I1664J1456D01*
G03X662600Y1506273I-150J132D01*
G01Y1508216D01*
G03X662550Y1508348I-200J0D01*
G02Y1511260I1664J1456D01*
G03X662600Y1511392I-150J132D01*
G01Y1512014D01*
G02X662803Y1512216I203J-1D01*
G37*
G36*
G01X680125D02*
X682945D01*
G02X683148Y1512014I1J-202D01*
G01Y1511392D01*
G03X683198Y1511260I200J0D01*
G02Y1508348I-1664J-1456D01*
G03X683148Y1508216I150J-132D01*
G01Y1506273D01*
G03X683198Y1506141I200J0D01*
G02Y1503229I-1664J-1456D01*
G03X683148Y1503097I150J-132D01*
G01Y1502476D01*
G02X682945Y1502274I-203J1D01*
G01X680125D01*
G02X679922Y1502476I-1J202D01*
G01Y1503097D01*
G03X679872Y1503229I-200J0D01*
G02Y1506141I1664J1456D01*
G03X679922Y1506273I-150J132D01*
G01Y1508216D01*
G03X679872Y1508348I-200J0D01*
G02Y1511260I1664J1456D01*
G03X679922Y1511392I-150J132D01*
G01Y1512014D01*
G02X680125Y1512216I203J-1D01*
G37*
G36*
G01X1303669D02*
X1306489D01*
G02X1306692Y1512014I1J-202D01*
G01Y1511392D01*
G03X1306742Y1511260I200J0D01*
G02Y1508348I-1664J-1456D01*
G03X1306692Y1508216I150J-132D01*
G01Y1506273D01*
G03X1306742Y1506141I200J0D01*
G02Y1503229I-1664J-1456D01*
G03X1306692Y1503097I150J-132D01*
G01Y1502476D01*
G02X1306489Y1502274I-203J1D01*
G01X1303669D01*
G02X1303466Y1502476I-1J202D01*
G01Y1503097D01*
G03X1303416Y1503229I-200J0D01*
G02Y1506141I1664J1456D01*
G03X1303466Y1506273I-150J132D01*
G01Y1508216D01*
G03X1303416Y1508348I-200J0D01*
G02Y1511260I1664J1456D01*
G03X1303466Y1511392I-150J132D01*
G01Y1512014D01*
G02X1303669Y1512216I203J-1D01*
G37*
G36*
G01X1338315D02*
X1341135D01*
G02X1341338Y1512014I1J-202D01*
G01Y1511392D01*
G03X1341388Y1511260I200J0D01*
G02Y1508348I-1664J-1456D01*
G03X1341338Y1508216I150J-132D01*
G01Y1506273D01*
G03X1341388Y1506141I200J0D01*
G02Y1503229I-1664J-1456D01*
G03X1341338Y1503097I150J-132D01*
G01Y1502476D01*
G02X1341135Y1502274I-203J1D01*
G01X1338315D01*
G02X1338112Y1502476I-1J202D01*
G01Y1503097D01*
G03X1338062Y1503229I-200J0D01*
G02Y1506141I1664J1456D01*
G03X1338112Y1506273I-150J132D01*
G01Y1508216D01*
G03X1338062Y1508348I-200J0D01*
G02Y1511260I1664J1456D01*
G03X1338112Y1511392I-150J132D01*
G01Y1512014D01*
G02X1338315Y1512216I203J-1D01*
G37*
G36*
G01X1355637D02*
X1358457D01*
G02X1358660Y1512014I1J-202D01*
G01Y1511392D01*
G03X1358710Y1511260I200J0D01*
G02Y1508348I-1664J-1456D01*
G03X1358660Y1508216I150J-132D01*
G01Y1506273D01*
G03X1358710Y1506141I200J0D01*
G02Y1503229I-1664J-1456D01*
G03X1358660Y1503097I150J-132D01*
G01Y1502476D01*
G02X1358457Y1502274I-203J1D01*
G01X1355637D01*
G02X1355434Y1502476I-1J202D01*
G01Y1503097D01*
G03X1355384Y1503229I-200J0D01*
G02Y1506141I1664J1456D01*
G03X1355434Y1506273I-150J132D01*
G01Y1508216D01*
G03X1355384Y1508348I-200J0D01*
G02Y1511260I1664J1456D01*
G03X1355434Y1511392I-150J132D01*
G01Y1512014D01*
G02X1355637Y1512216I203J-1D01*
G37*
G36*
G01X1476897D02*
X1479717D01*
G02X1479920Y1512014I1J-202D01*
G01Y1511392D01*
G03X1479970Y1511260I200J0D01*
G02Y1508348I-1664J-1456D01*
G03X1479920Y1508216I150J-132D01*
G01Y1506273D01*
G03X1479970Y1506141I200J0D01*
G02Y1503229I-1664J-1456D01*
G03X1479920Y1503097I150J-132D01*
G01Y1502476D01*
G02X1479717Y1502274I-203J1D01*
G01X1476897D01*
G02X1476694Y1502476I-1J202D01*
G01Y1503097D01*
G03X1476644Y1503229I-200J0D01*
G02Y1506141I1664J1456D01*
G03X1476694Y1506273I-150J132D01*
G01Y1508216D01*
G03X1476644Y1508348I-200J0D01*
G02Y1511260I1664J1456D01*
G03X1476694Y1511392I-150J132D01*
G01Y1512014D01*
G02X1476897Y1512216I203J-1D01*
G37*
G36*
G01X1511543D02*
X1514363D01*
G02X1514566Y1512014I1J-202D01*
G01Y1511392D01*
G03X1514616Y1511260I200J0D01*
G02Y1508348I-1664J-1456D01*
G03X1514566Y1508216I150J-132D01*
G01Y1506273D01*
G03X1514616Y1506141I200J0D01*
G02Y1503229I-1664J-1456D01*
G03X1514566Y1503097I150J-132D01*
G01Y1502476D01*
G02X1514363Y1502274I-203J1D01*
G01X1511543D01*
G02X1511340Y1502476I-1J202D01*
G01Y1503097D01*
G03X1511290Y1503229I-200J0D01*
G02Y1506141I1664J1456D01*
G03X1511340Y1506273I-150J132D01*
G01Y1508216D01*
G03X1511290Y1508348I-200J0D01*
G02Y1511260I1664J1456D01*
G03X1511340Y1511392I-150J132D01*
G01Y1512014D01*
G02X1511543Y1512216I203J-1D01*
G37*
G36*
G01X1528865D02*
X1531685D01*
G02X1531888Y1512014I1J-202D01*
G01Y1511392D01*
G03X1531938Y1511260I200J0D01*
G02Y1508348I-1664J-1456D01*
G03X1531888Y1508216I150J-132D01*
G01Y1506273D01*
G03X1531938Y1506141I200J0D01*
G02Y1503229I-1664J-1456D01*
G03X1531888Y1503097I150J-132D01*
G01Y1502476D01*
G02X1531685Y1502274I-203J1D01*
G01X1528865D01*
G02X1528662Y1502476I-1J202D01*
G01Y1503097D01*
G03X1528612Y1503229I-200J0D01*
G02Y1506141I1664J1456D01*
G03X1528662Y1506273I-150J132D01*
G01Y1508216D01*
G03X1528612Y1508348I-200J0D01*
G02Y1511260I1664J1456D01*
G03X1528662Y1511392I-150J132D01*
G01Y1512014D01*
G02X1528865Y1512216I203J-1D01*
G37*
G36*
G01X1684771D02*
X1687591D01*
G02X1687794Y1512014I1J-202D01*
G01Y1511392D01*
G03X1687844Y1511260I200J0D01*
G02Y1508348I-1664J-1456D01*
G03X1687794Y1508216I150J-132D01*
G01Y1506273D01*
G03X1687844Y1506141I200J0D01*
G02Y1503229I-1664J-1456D01*
G03X1687794Y1503097I150J-132D01*
G01Y1502476D01*
G02X1687591Y1502274I-203J1D01*
G01X1684771D01*
G02X1684568Y1502476I-1J202D01*
G01Y1503097D01*
G03X1684518Y1503229I-200J0D01*
G02Y1506141I1664J1456D01*
G03X1684568Y1506273I-150J132D01*
G01Y1508216D01*
G03X1684518Y1508348I-200J0D01*
G02Y1511260I1664J1456D01*
G03X1684568Y1511392I-150J132D01*
G01Y1512014D01*
G02X1684771Y1512216I203J-1D01*
G37*
G36*
G01X1702093D02*
X1704913D01*
G02X1705116Y1512014I1J-202D01*
G01Y1511392D01*
G03X1705166Y1511260I200J0D01*
G02Y1508348I-1664J-1456D01*
G03X1705116Y1508216I150J-132D01*
G01Y1506273D01*
G03X1705166Y1506141I200J0D01*
G02Y1503229I-1664J-1456D01*
G03X1705116Y1503097I150J-132D01*
G01Y1502476D01*
G02X1704913Y1502274I-203J1D01*
G01X1702093D01*
G02X1701890Y1502476I-1J202D01*
G01Y1503097D01*
G03X1701840Y1503229I-200J0D01*
G02Y1506141I1664J1456D01*
G03X1701890Y1506273I-150J132D01*
G01Y1508216D01*
G03X1701840Y1508348I-200J0D01*
G02Y1511260I1664J1456D01*
G03X1701890Y1511392I-150J132D01*
G01Y1512014D01*
G02X1702093Y1512216I203J-1D01*
G37*
G36*
G01X134456Y1516546D02*
X137276D01*
G02X137478Y1516344I0J-202D01*
G01Y1515724D01*
G03X137528Y1515592I200J0D01*
G02Y1512676I-1661J-1458D01*
G03X137478Y1512544I150J-132D01*
G01Y1510606D01*
G03X137528Y1510474I200J0D01*
G02Y1507558I-1661J-1458D01*
G03X137478Y1507426I150J-132D01*
G01Y1506806D01*
G02X137276Y1506604I-202J0D01*
G01X134456D01*
G02X134254Y1506806I0J202D01*
G01Y1507426D01*
G03X134204Y1507558I-200J0D01*
G02Y1510474I1661J1458D01*
G03X134254Y1510606I-150J132D01*
G01Y1512544D01*
G03X134204Y1512676I-200J0D01*
G02Y1515592I1661J1458D01*
G03X134254Y1515724I-150J132D01*
G01Y1516344D01*
G02X134456Y1516546I202J0D01*
G37*
G36*
G01X169102D02*
X171922D01*
G02X172124Y1516344I0J-202D01*
G01Y1515724D01*
G03X172174Y1515592I200J0D01*
G02Y1512676I-1661J-1458D01*
G03X172124Y1512544I150J-132D01*
G01Y1510606D01*
G03X172174Y1510474I200J0D01*
G02Y1507558I-1661J-1458D01*
G03X172124Y1507426I150J-132D01*
G01Y1506806D01*
G02X171922Y1506604I-202J0D01*
G01X169102D01*
G02X168900Y1506806I0J202D01*
G01Y1507426D01*
G03X168850Y1507558I-200J0D01*
G02Y1510474I1661J1458D01*
G03X168900Y1510606I-150J132D01*
G01Y1512544D01*
G03X168850Y1512676I-200J0D01*
G02Y1515592I1661J1458D01*
G03X168900Y1515724I-150J132D01*
G01Y1516344D01*
G02X169102Y1516546I202J0D01*
G37*
G36*
G01X463590D02*
X466410D01*
G02X466612Y1516344I0J-202D01*
G01Y1515724D01*
G03X466662Y1515592I200J0D01*
G02Y1512676I-1661J-1458D01*
G03X466612Y1512544I150J-132D01*
G01Y1510606D01*
G03X466662Y1510474I200J0D01*
G02Y1507558I-1661J-1458D01*
G03X466612Y1507426I150J-132D01*
G01Y1506806D01*
G02X466410Y1506604I-202J0D01*
G01X463590D01*
G02X463388Y1506806I0J202D01*
G01Y1507426D01*
G03X463338Y1507558I-200J0D01*
G02Y1510474I1661J1458D01*
G03X463388Y1510606I-150J132D01*
G01Y1512544D01*
G03X463338Y1512676I-200J0D01*
G02Y1515592I1661J1458D01*
G03X463388Y1515724I-150J132D01*
G01Y1516344D01*
G02X463590Y1516546I202J0D01*
G37*
G36*
G01X498236D02*
X501056D01*
G02X501258Y1516344I0J-202D01*
G01Y1515724D01*
G03X501308Y1515592I200J0D01*
G02Y1512676I-1661J-1458D01*
G03X501258Y1512544I150J-132D01*
G01Y1510606D01*
G03X501308Y1510474I200J0D01*
G02Y1507558I-1661J-1458D01*
G03X501258Y1507426I150J-132D01*
G01Y1506806D01*
G02X501056Y1506604I-202J0D01*
G01X498236D01*
G02X498034Y1506806I0J202D01*
G01Y1507426D01*
G03X497984Y1507558I-200J0D01*
G02Y1510474I1661J1458D01*
G03X498034Y1510606I-150J132D01*
G01Y1512544D01*
G03X497984Y1512676I-200J0D01*
G02Y1515592I1661J1458D01*
G03X498034Y1515724I-150J132D01*
G01Y1516344D01*
G02X498236Y1516546I202J0D01*
G37*
G36*
G01X671464D02*
X674284D01*
G02X674486Y1516344I0J-202D01*
G01Y1515724D01*
G03X674536Y1515592I200J0D01*
G02Y1512676I-1661J-1458D01*
G03X674486Y1512544I150J-132D01*
G01Y1510606D01*
G03X674536Y1510474I200J0D01*
G02Y1507558I-1661J-1458D01*
G03X674486Y1507426I150J-132D01*
G01Y1506806D01*
G02X674284Y1506604I-202J0D01*
G01X671464D01*
G02X671262Y1506806I0J202D01*
G01Y1507426D01*
G03X671212Y1507558I-200J0D01*
G02Y1510474I1661J1458D01*
G03X671262Y1510606I-150J132D01*
G01Y1512544D01*
G03X671212Y1512676I-200J0D01*
G02Y1515592I1661J1458D01*
G03X671262Y1515724I-150J132D01*
G01Y1516344D01*
G02X671464Y1516546I202J0D01*
G37*
G36*
G01X1191070D02*
X1193890D01*
G02X1194092Y1516344I0J-202D01*
G01Y1515724D01*
G03X1194142Y1515592I200J0D01*
G02Y1512676I-1661J-1458D01*
G03X1194092Y1512544I150J-132D01*
G01Y1510606D01*
G03X1194142Y1510474I200J0D01*
G02Y1507558I-1661J-1458D01*
G03X1194092Y1507426I150J-132D01*
G01Y1506806D01*
G02X1193890Y1506604I-202J0D01*
G01X1191070D01*
G02X1190868Y1506806I0J202D01*
G01Y1507426D01*
G03X1190818Y1507558I-200J0D01*
G02Y1510474I1661J1458D01*
G03X1190868Y1510606I-150J132D01*
G01Y1512544D01*
G03X1190818Y1512676I-200J0D01*
G02Y1515592I1661J1458D01*
G03X1190868Y1515724I-150J132D01*
G01Y1516344D01*
G02X1191070Y1516546I202J0D01*
G37*
G36*
G01X1312330D02*
X1315150D01*
G02X1315352Y1516344I0J-202D01*
G01Y1515724D01*
G03X1315402Y1515592I200J0D01*
G02Y1512676I-1661J-1458D01*
G03X1315352Y1512544I150J-132D01*
G01Y1510606D01*
G03X1315402Y1510474I200J0D01*
G02Y1507558I-1661J-1458D01*
G03X1315352Y1507426I150J-132D01*
G01Y1506806D01*
G02X1315150Y1506604I-202J0D01*
G01X1312330D01*
G02X1312128Y1506806I0J202D01*
G01Y1507426D01*
G03X1312078Y1507558I-200J0D01*
G02Y1510474I1661J1458D01*
G03X1312128Y1510606I-150J132D01*
G01Y1512544D01*
G03X1312078Y1512676I-200J0D01*
G02Y1515592I1661J1458D01*
G03X1312128Y1515724I-150J132D01*
G01Y1516344D01*
G02X1312330Y1516546I202J0D01*
G37*
G36*
G01X1346976D02*
X1349796D01*
G02X1349998Y1516344I0J-202D01*
G01Y1515724D01*
G03X1350048Y1515592I200J0D01*
G02Y1512676I-1661J-1458D01*
G03X1349998Y1512544I150J-132D01*
G01Y1510606D01*
G03X1350048Y1510474I200J0D01*
G02Y1507558I-1661J-1458D01*
G03X1349998Y1507426I150J-132D01*
G01Y1506806D01*
G02X1349796Y1506604I-202J0D01*
G01X1346976D01*
G02X1346774Y1506806I0J202D01*
G01Y1507426D01*
G03X1346724Y1507558I-200J0D01*
G02Y1510474I1661J1458D01*
G03X1346774Y1510606I-150J132D01*
G01Y1512544D01*
G03X1346724Y1512676I-200J0D01*
G02Y1515592I1661J1458D01*
G03X1346774Y1515724I-150J132D01*
G01Y1516344D01*
G02X1346976Y1516546I202J0D01*
G37*
G36*
G01X1485558D02*
X1488378D01*
G02X1488580Y1516344I0J-202D01*
G01Y1515724D01*
G03X1488630Y1515592I200J0D01*
G02Y1512676I-1661J-1458D01*
G03X1488580Y1512544I150J-132D01*
G01Y1510606D01*
G03X1488630Y1510474I200J0D01*
G02Y1507558I-1661J-1458D01*
G03X1488580Y1507426I150J-132D01*
G01Y1506806D01*
G02X1488378Y1506604I-202J0D01*
G01X1485558D01*
G02X1485356Y1506806I0J202D01*
G01Y1507426D01*
G03X1485306Y1507558I-200J0D01*
G02Y1510474I1661J1458D01*
G03X1485356Y1510606I-150J132D01*
G01Y1512544D01*
G03X1485306Y1512676I-200J0D01*
G02Y1515592I1661J1458D01*
G03X1485356Y1515724I-150J132D01*
G01Y1516344D01*
G02X1485558Y1516546I202J0D01*
G37*
G36*
G01X1520204D02*
X1523024D01*
G02X1523226Y1516344I0J-202D01*
G01Y1515724D01*
G03X1523276Y1515592I200J0D01*
G02Y1512676I-1661J-1458D01*
G03X1523226Y1512544I150J-132D01*
G01Y1510606D01*
G03X1523276Y1510474I200J0D01*
G02Y1507558I-1661J-1458D01*
G03X1523226Y1507426I150J-132D01*
G01Y1506806D01*
G02X1523024Y1506604I-202J0D01*
G01X1520204D01*
G02X1520002Y1506806I0J202D01*
G01Y1507426D01*
G03X1519952Y1507558I-200J0D01*
G02Y1510474I1661J1458D01*
G03X1520002Y1510606I-150J132D01*
G01Y1512544D01*
G03X1519952Y1512676I-200J0D01*
G02Y1515592I1661J1458D01*
G03X1520002Y1515724I-150J132D01*
G01Y1516344D01*
G02X1520204Y1516546I202J0D01*
G37*
G36*
G01X1693432D02*
X1696252D01*
G02X1696454Y1516344I0J-202D01*
G01Y1515724D01*
G03X1696504Y1515592I200J0D01*
G02Y1512676I-1661J-1458D01*
G03X1696454Y1512544I150J-132D01*
G01Y1510606D01*
G03X1696504Y1510474I200J0D01*
G02Y1507558I-1661J-1458D01*
G03X1696454Y1507426I150J-132D01*
G01Y1506806D01*
G02X1696252Y1506604I-202J0D01*
G01X1693432D01*
G02X1693230Y1506806I0J202D01*
G01Y1507426D01*
G03X1693180Y1507558I-200J0D01*
G02Y1510474I1661J1458D01*
G03X1693230Y1510606I-150J132D01*
G01Y1512544D01*
G03X1693180Y1512676I-200J0D01*
G02Y1515592I1661J1458D01*
G03X1693230Y1515724I-150J132D01*
G01Y1516344D01*
G02X1693432Y1516546I202J0D01*
G37*
G36*
G01X151779D02*
X154599D01*
G02X154802Y1516344I1J-202D01*
G01Y1515722D01*
G03X154852Y1515590I200J0D01*
G02Y1512678I-1664J-1456D01*
G03X154802Y1512546I150J-132D01*
G01Y1510604D01*
G03X154852Y1510472I200J0D01*
G02Y1507560I-1664J-1456D01*
G03X154802Y1507428I150J-132D01*
G01Y1506806D01*
G02X154599Y1506604I-203J1D01*
G01X151779D01*
G02X151576Y1506806I-1J202D01*
G01Y1507428D01*
G03X151526Y1507560I-200J0D01*
G02Y1510472I1664J1456D01*
G03X151576Y1510604I-150J132D01*
G01Y1512546D01*
G03X151526Y1512678I-200J0D01*
G02Y1515590I1664J1456D01*
G03X151576Y1515722I-150J132D01*
G01Y1516344D01*
G02X151779Y1516546I203J-1D01*
G37*
G36*
G01X290361D02*
X293181D01*
G02X293384Y1516344I1J-202D01*
G01Y1515722D01*
G03X293434Y1515590I200J0D01*
G02Y1512678I-1664J-1456D01*
G03X293384Y1512546I150J-132D01*
G01Y1510604D01*
G03X293434Y1510472I200J0D01*
G02Y1507560I-1664J-1456D01*
G03X293384Y1507428I150J-132D01*
G01Y1506806D01*
G02X293181Y1506604I-203J1D01*
G01X290361D01*
G02X290158Y1506806I-1J202D01*
G01Y1507428D01*
G03X290108Y1507560I-200J0D01*
G02Y1510472I1664J1456D01*
G03X290158Y1510604I-150J132D01*
G01Y1512546D01*
G03X290108Y1512678I-200J0D01*
G02Y1515590I1664J1456D01*
G03X290158Y1515722I-150J132D01*
G01Y1516344D01*
G02X290361Y1516546I203J-1D01*
G37*
G36*
G01X480913D02*
X483733D01*
G02X483936Y1516344I1J-202D01*
G01Y1515722D01*
G03X483986Y1515590I200J0D01*
G02Y1512678I-1664J-1456D01*
G03X483936Y1512546I150J-132D01*
G01Y1510604D01*
G03X483986Y1510472I200J0D01*
G02Y1507560I-1664J-1456D01*
G03X483936Y1507428I150J-132D01*
G01Y1506806D01*
G02X483733Y1506604I-203J1D01*
G01X480913D01*
G02X480710Y1506806I-1J202D01*
G01Y1507428D01*
G03X480660Y1507560I-200J0D01*
G02Y1510472I1664J1456D01*
G03X480710Y1510604I-150J132D01*
G01Y1512546D01*
G03X480660Y1512678I-200J0D01*
G02Y1515590I1664J1456D01*
G03X480710Y1515722I-150J132D01*
G01Y1516344D01*
G02X480913Y1516546I203J-1D01*
G37*
G36*
G01X515559D02*
X518379D01*
G02X518582Y1516344I1J-202D01*
G01Y1515722D01*
G03X518632Y1515590I200J0D01*
G02Y1512678I-1664J-1456D01*
G03X518582Y1512546I150J-132D01*
G01Y1510604D01*
G03X518632Y1510472I200J0D01*
G02Y1507560I-1664J-1456D01*
G03X518582Y1507428I150J-132D01*
G01Y1506806D01*
G02X518379Y1506604I-203J1D01*
G01X515559D01*
G02X515356Y1506806I-1J202D01*
G01Y1507428D01*
G03X515306Y1507560I-200J0D01*
G02Y1510472I1664J1456D01*
G03X515356Y1510604I-150J132D01*
G01Y1512546D01*
G03X515306Y1512678I-200J0D01*
G02Y1515590I1664J1456D01*
G03X515356Y1515722I-150J132D01*
G01Y1516344D01*
G02X515559Y1516546I203J-1D01*
G37*
G36*
G01X654141D02*
X656961D01*
G02X657164Y1516344I1J-202D01*
G01Y1515722D01*
G03X657214Y1515590I200J0D01*
G02Y1512678I-1664J-1456D01*
G03X657164Y1512546I150J-132D01*
G01Y1510604D01*
G03X657214Y1510472I200J0D01*
G02Y1507560I-1664J-1456D01*
G03X657164Y1507428I150J-132D01*
G01Y1506806D01*
G02X656961Y1506604I-203J1D01*
G01X654141D01*
G02X653938Y1506806I-1J202D01*
G01Y1507428D01*
G03X653888Y1507560I-200J0D01*
G02Y1510472I1664J1456D01*
G03X653938Y1510604I-150J132D01*
G01Y1512546D01*
G03X653888Y1512678I-200J0D01*
G02Y1515590I1664J1456D01*
G03X653938Y1515722I-150J132D01*
G01Y1516344D01*
G02X654141Y1516546I203J-1D01*
G37*
G36*
G01X688787D02*
X691607D01*
G02X691810Y1516344I1J-202D01*
G01Y1515722D01*
G03X691860Y1515590I200J0D01*
G02Y1512678I-1664J-1456D01*
G03X691810Y1512546I150J-132D01*
G01Y1510604D01*
G03X691860Y1510472I200J0D01*
G02Y1507560I-1664J-1456D01*
G03X691810Y1507428I150J-132D01*
G01Y1506806D01*
G02X691607Y1506604I-203J1D01*
G01X688787D01*
G02X688584Y1506806I-1J202D01*
G01Y1507428D01*
G03X688534Y1507560I-200J0D01*
G02Y1510472I1664J1456D01*
G03X688584Y1510604I-150J132D01*
G01Y1512546D01*
G03X688534Y1512678I-200J0D01*
G02Y1515590I1664J1456D01*
G03X688584Y1515722I-150J132D01*
G01Y1516344D01*
G02X688787Y1516546I203J-1D01*
G37*
G36*
G01X1173747D02*
X1176567D01*
G02X1176770Y1516344I1J-202D01*
G01Y1515722D01*
G03X1176820Y1515590I200J0D01*
G02Y1512678I-1664J-1456D01*
G03X1176770Y1512546I150J-132D01*
G01Y1510604D01*
G03X1176820Y1510472I200J0D01*
G02Y1507560I-1664J-1456D01*
G03X1176770Y1507428I150J-132D01*
G01Y1506806D01*
G02X1176567Y1506604I-203J1D01*
G01X1173747D01*
G02X1173544Y1506806I-1J202D01*
G01Y1507428D01*
G03X1173494Y1507560I-200J0D01*
G02Y1510472I1664J1456D01*
G03X1173544Y1510604I-150J132D01*
G01Y1512546D01*
G03X1173494Y1512678I-200J0D01*
G02Y1515590I1664J1456D01*
G03X1173544Y1515722I-150J132D01*
G01Y1516344D01*
G02X1173747Y1516546I203J-1D01*
G37*
G36*
G01X1329653D02*
X1332473D01*
G02X1332676Y1516344I1J-202D01*
G01Y1515722D01*
G03X1332726Y1515590I200J0D01*
G02Y1512678I-1664J-1456D01*
G03X1332676Y1512546I150J-132D01*
G01Y1510604D01*
G03X1332726Y1510472I200J0D01*
G02Y1507560I-1664J-1456D01*
G03X1332676Y1507428I150J-132D01*
G01Y1506806D01*
G02X1332473Y1506604I-203J1D01*
G01X1329653D01*
G02X1329450Y1506806I-1J202D01*
G01Y1507428D01*
G03X1329400Y1507560I-200J0D01*
G02Y1510472I1664J1456D01*
G03X1329450Y1510604I-150J132D01*
G01Y1512546D01*
G03X1329400Y1512678I-200J0D01*
G02Y1515590I1664J1456D01*
G03X1329450Y1515722I-150J132D01*
G01Y1516344D01*
G02X1329653Y1516546I203J-1D01*
G37*
G36*
G01X1364299D02*
X1367119D01*
G02X1367322Y1516344I1J-202D01*
G01Y1515722D01*
G03X1367372Y1515590I200J0D01*
G02Y1512678I-1664J-1456D01*
G03X1367322Y1512546I150J-132D01*
G01Y1510604D01*
G03X1367372Y1510472I200J0D01*
G02Y1507560I-1664J-1456D01*
G03X1367322Y1507428I150J-132D01*
G01Y1506806D01*
G02X1367119Y1506604I-203J1D01*
G01X1364299D01*
G02X1364096Y1506806I-1J202D01*
G01Y1507428D01*
G03X1364046Y1507560I-200J0D01*
G02Y1510472I1664J1456D01*
G03X1364096Y1510604I-150J132D01*
G01Y1512546D01*
G03X1364046Y1512678I-200J0D01*
G02Y1515590I1664J1456D01*
G03X1364096Y1515722I-150J132D01*
G01Y1516344D01*
G02X1364299Y1516546I203J-1D01*
G37*
G36*
G01X1502881D02*
X1505701D01*
G02X1505904Y1516344I1J-202D01*
G01Y1515722D01*
G03X1505954Y1515590I200J0D01*
G02Y1512678I-1664J-1456D01*
G03X1505904Y1512546I150J-132D01*
G01Y1510604D01*
G03X1505954Y1510472I200J0D01*
G02Y1507560I-1664J-1456D01*
G03X1505904Y1507428I150J-132D01*
G01Y1506806D01*
G02X1505701Y1506604I-203J1D01*
G01X1502881D01*
G02X1502678Y1506806I-1J202D01*
G01Y1507428D01*
G03X1502628Y1507560I-200J0D01*
G02Y1510472I1664J1456D01*
G03X1502678Y1510604I-150J132D01*
G01Y1512546D01*
G03X1502628Y1512678I-200J0D01*
G02Y1515590I1664J1456D01*
G03X1502678Y1515722I-150J132D01*
G01Y1516344D01*
G02X1502881Y1516546I203J-1D01*
G37*
G36*
G01X1537527D02*
X1540347D01*
G02X1540550Y1516344I1J-202D01*
G01Y1515722D01*
G03X1540600Y1515590I200J0D01*
G02Y1512678I-1664J-1456D01*
G03X1540550Y1512546I150J-132D01*
G01Y1510604D01*
G03X1540600Y1510472I200J0D01*
G02Y1507560I-1664J-1456D01*
G03X1540550Y1507428I150J-132D01*
G01Y1506806D01*
G02X1540347Y1506604I-203J1D01*
G01X1537527D01*
G02X1537324Y1506806I-1J202D01*
G01Y1507428D01*
G03X1537274Y1507560I-200J0D01*
G02Y1510472I1664J1456D01*
G03X1537324Y1510604I-150J132D01*
G01Y1512546D01*
G03X1537274Y1512678I-200J0D01*
G02Y1515590I1664J1456D01*
G03X1537324Y1515722I-150J132D01*
G01Y1516344D01*
G02X1537527Y1516546I203J-1D01*
G37*
G36*
G01X1710755D02*
X1713575D01*
G02X1713778Y1516344I1J-202D01*
G01Y1515722D01*
G03X1713828Y1515590I200J0D01*
G02Y1512678I-1664J-1456D01*
G03X1713778Y1512546I150J-132D01*
G01Y1510604D01*
G03X1713828Y1510472I200J0D01*
G02Y1507560I-1664J-1456D01*
G03X1713778Y1507428I150J-132D01*
G01Y1506806D01*
G02X1713575Y1506604I-203J1D01*
G01X1710755D01*
G02X1710552Y1506806I-1J202D01*
G01Y1507428D01*
G03X1710502Y1507560I-200J0D01*
G02Y1510472I1664J1456D01*
G03X1710552Y1510604I-150J132D01*
G01Y1512546D01*
G03X1710502Y1512678I-200J0D01*
G02Y1515590I1664J1456D01*
G03X1710552Y1515722I-150J132D01*
G01Y1516344D01*
G02X1710755Y1516546I203J-1D01*
G37*
G36*
G01X108472Y1568516D02*
X111292D01*
G02X111494Y1568313I-1J-203D01*
G01Y1567693D01*
G03X111544Y1567561I200J0D01*
G02Y1564645I-1661J-1458D01*
G03X111494Y1564513I150J-132D01*
G01Y1562575D01*
G03X111544Y1562443I200J0D01*
G02Y1559527I-1661J-1458D01*
G03X111494Y1559395I150J-132D01*
G01Y1558775D01*
G02X111292Y1558572I-202J-1D01*
G01X108472D01*
G02X108270Y1558775I1J203D01*
G01Y1559395D01*
G03X108220Y1559527I-200J0D01*
G02Y1562443I1661J1458D01*
G03X108270Y1562575I-150J132D01*
G01Y1564513D01*
G03X108220Y1564645I-200J0D01*
G02Y1567561I1661J1458D01*
G03X108270Y1567693I-150J132D01*
G01Y1568313D01*
G02X108472Y1568516I202J1D01*
G37*
G36*
G01X125795D02*
X128615D01*
G02X128818Y1568313I0J-203D01*
G01Y1567691D01*
G03X128868Y1567559I200J0D01*
G02Y1564647I-1664J-1456D01*
G03X128818Y1564515I150J-132D01*
G01Y1562573D01*
G03X128868Y1562441I200J0D01*
G02Y1559529I-1664J-1456D01*
G03X128818Y1559397I150J-132D01*
G01Y1558775D01*
G02X128615Y1558572I-203J0D01*
G01X125795D01*
G02X125592Y1558775I0J203D01*
G01Y1559397D01*
G03X125542Y1559529I-200J0D01*
G02Y1562441I1664J1456D01*
G03X125592Y1562573I-150J132D01*
G01Y1564515D01*
G03X125542Y1564647I-200J0D01*
G02Y1567559I1664J1456D01*
G03X125592Y1567691I-150J132D01*
G01Y1568313D01*
G02X125795Y1568516I203J0D01*
G37*
G36*
G01X143118D02*
X145938D01*
G02X146140Y1568313I-1J-203D01*
G01Y1567693D01*
G03X146190Y1567561I200J0D01*
G02Y1564645I-1661J-1458D01*
G03X146140Y1564513I150J-132D01*
G01Y1562575D01*
G03X146190Y1562443I200J0D01*
G02Y1559527I-1661J-1458D01*
G03X146140Y1559395I150J-132D01*
G01Y1558775D01*
G02X145938Y1558572I-202J-1D01*
G01X143118D01*
G02X142916Y1558775I1J203D01*
G01Y1559395D01*
G03X142866Y1559527I-200J0D01*
G02Y1562443I1661J1458D01*
G03X142916Y1562575I-150J132D01*
G01Y1564513D01*
G03X142866Y1564645I-200J0D01*
G02Y1567561I1661J1458D01*
G03X142916Y1567693I-150J132D01*
G01Y1568313D01*
G02X143118Y1568516I202J1D01*
G37*
G36*
G01X160440D02*
X163260D01*
G02X163462Y1568313I-1J-203D01*
G01Y1567693D01*
G03X163512Y1567561I200J0D01*
G02Y1564645I-1661J-1458D01*
G03X163462Y1564513I150J-132D01*
G01Y1562575D01*
G03X163512Y1562443I200J0D01*
G02Y1559527I-1661J-1458D01*
G03X163462Y1559395I150J-132D01*
G01Y1558775D01*
G02X163260Y1558572I-202J-1D01*
G01X160440D01*
G02X160238Y1558775I1J203D01*
G01Y1559395D01*
G03X160188Y1559527I-200J0D01*
G02Y1562443I1661J1458D01*
G03X160238Y1562575I-150J132D01*
G01Y1564513D01*
G03X160188Y1564645I-200J0D01*
G02Y1567561I1661J1458D01*
G03X160238Y1567693I-150J132D01*
G01Y1568313D01*
G02X160440Y1568516I202J1D01*
G37*
G36*
G01X281700D02*
X284520D01*
G02X284722Y1568313I-1J-203D01*
G01Y1567693D01*
G03X284772Y1567561I200J0D01*
G02Y1564645I-1661J-1458D01*
G03X284722Y1564513I150J-132D01*
G01Y1562575D01*
G03X284772Y1562443I200J0D01*
G02Y1559527I-1661J-1458D01*
G03X284722Y1559395I150J-132D01*
G01Y1558775D01*
G02X284520Y1558572I-202J-1D01*
G01X281700D01*
G02X281498Y1558775I1J203D01*
G01Y1559395D01*
G03X281448Y1559527I-200J0D01*
G02Y1562443I1661J1458D01*
G03X281498Y1562575I-150J132D01*
G01Y1564513D01*
G03X281448Y1564645I-200J0D01*
G02Y1567561I1661J1458D01*
G03X281498Y1567693I-150J132D01*
G01Y1568313D01*
G02X281700Y1568516I202J1D01*
G37*
G36*
G01X299023D02*
X301843D01*
G02X302046Y1568313I0J-203D01*
G01Y1567691D01*
G03X302096Y1567559I200J0D01*
G02Y1564647I-1664J-1456D01*
G03X302046Y1564515I150J-132D01*
G01Y1562573D01*
G03X302096Y1562441I200J0D01*
G02Y1559529I-1664J-1456D01*
G03X302046Y1559397I150J-132D01*
G01Y1558775D01*
G02X301843Y1558572I-203J0D01*
G01X299023D01*
G02X298820Y1558775I0J203D01*
G01Y1559397D01*
G03X298770Y1559529I-200J0D01*
G02Y1562441I1664J1456D01*
G03X298820Y1562573I-150J132D01*
G01Y1564515D01*
G03X298770Y1564647I-200J0D01*
G02Y1567559I1664J1456D01*
G03X298820Y1567691I-150J132D01*
G01Y1568313D01*
G02X299023Y1568516I203J0D01*
G37*
G36*
G01X316346D02*
X319166D01*
G02X319368Y1568313I-1J-203D01*
G01Y1567693D01*
G03X319418Y1567561I200J0D01*
G02Y1564645I-1661J-1458D01*
G03X319368Y1564513I150J-132D01*
G01Y1562575D01*
G03X319418Y1562443I200J0D01*
G02Y1559527I-1661J-1458D01*
G03X319368Y1559395I150J-132D01*
G01Y1558775D01*
G02X319166Y1558572I-202J-1D01*
G01X316346D01*
G02X316144Y1558775I1J203D01*
G01Y1559395D01*
G03X316094Y1559527I-200J0D01*
G02Y1562443I1661J1458D01*
G03X316144Y1562575I-150J132D01*
G01Y1564513D01*
G03X316094Y1564645I-200J0D01*
G02Y1567561I1661J1458D01*
G03X316144Y1567693I-150J132D01*
G01Y1568313D01*
G02X316346Y1568516I202J1D01*
G37*
G36*
G01X333668D02*
X336488D01*
G02X336690Y1568313I-1J-203D01*
G01Y1567693D01*
G03X336740Y1567561I200J0D01*
G02Y1564645I-1661J-1458D01*
G03X336690Y1564513I150J-132D01*
G01Y1562575D01*
G03X336740Y1562443I200J0D01*
G02Y1559527I-1661J-1458D01*
G03X336690Y1559395I150J-132D01*
G01Y1558775D01*
G02X336488Y1558572I-202J-1D01*
G01X333668D01*
G02X333466Y1558775I1J203D01*
G01Y1559395D01*
G03X333416Y1559527I-200J0D01*
G02Y1562443I1661J1458D01*
G03X333466Y1562575I-150J132D01*
G01Y1564513D01*
G03X333416Y1564645I-200J0D01*
G02Y1567561I1661J1458D01*
G03X333466Y1567693I-150J132D01*
G01Y1568313D01*
G02X333668Y1568516I202J1D01*
G37*
G36*
G01X628157D02*
X630977D01*
G02X631180Y1568313I0J-203D01*
G01Y1567691D01*
G03X631230Y1567559I200J0D01*
G02Y1564647I-1664J-1456D01*
G03X631180Y1564515I150J-132D01*
G01Y1562573D01*
G03X631230Y1562441I200J0D01*
G02Y1559529I-1664J-1456D01*
G03X631180Y1559397I150J-132D01*
G01Y1558775D01*
G02X630977Y1558572I-203J0D01*
G01X628157D01*
G02X627954Y1558775I0J203D01*
G01Y1559397D01*
G03X627904Y1559529I-200J0D01*
G02Y1562441I1664J1456D01*
G03X627954Y1562573I-150J132D01*
G01Y1564515D01*
G03X627904Y1564647I-200J0D01*
G02Y1567559I1664J1456D01*
G03X627954Y1567691I-150J132D01*
G01Y1568313D01*
G02X628157Y1568516I203J0D01*
G37*
G36*
G01X645480D02*
X648300D01*
G02X648502Y1568313I-1J-203D01*
G01Y1567693D01*
G03X648552Y1567561I200J0D01*
G02Y1564645I-1661J-1458D01*
G03X648502Y1564513I150J-132D01*
G01Y1562575D01*
G03X648552Y1562443I200J0D01*
G02Y1559527I-1661J-1458D01*
G03X648502Y1559395I150J-132D01*
G01Y1558775D01*
G02X648300Y1558572I-202J-1D01*
G01X645480D01*
G02X645278Y1558775I1J203D01*
G01Y1559395D01*
G03X645228Y1559527I-200J0D01*
G02Y1562443I1661J1458D01*
G03X645278Y1562575I-150J132D01*
G01Y1564513D01*
G03X645228Y1564645I-200J0D01*
G02Y1567561I1661J1458D01*
G03X645278Y1567693I-150J132D01*
G01Y1568313D01*
G02X645480Y1568516I202J1D01*
G37*
G36*
G01X662803D02*
X665623D01*
G02X665826Y1568313I0J-203D01*
G01Y1567691D01*
G03X665876Y1567559I200J0D01*
G02Y1564647I-1664J-1456D01*
G03X665826Y1564515I150J-132D01*
G01Y1562573D01*
G03X665876Y1562441I200J0D01*
G02Y1559529I-1664J-1456D01*
G03X665826Y1559397I150J-132D01*
G01Y1558775D01*
G02X665623Y1558572I-203J0D01*
G01X662803D01*
G02X662600Y1558775I0J203D01*
G01Y1559397D01*
G03X662550Y1559529I-200J0D01*
G02Y1562441I1664J1456D01*
G03X662600Y1562573I-150J132D01*
G01Y1564515D01*
G03X662550Y1564647I-200J0D01*
G02Y1567559I1664J1456D01*
G03X662600Y1567691I-150J132D01*
G01Y1568313D01*
G02X662803Y1568516I203J0D01*
G37*
G36*
G01X680125D02*
X682945D01*
G02X683148Y1568313I0J-203D01*
G01Y1567691D01*
G03X683198Y1567559I200J0D01*
G02Y1564647I-1664J-1456D01*
G03X683148Y1564515I150J-132D01*
G01Y1562573D01*
G03X683198Y1562441I200J0D01*
G02Y1559529I-1664J-1456D01*
G03X683148Y1559397I150J-132D01*
G01Y1558775D01*
G02X682945Y1558572I-203J0D01*
G01X680125D01*
G02X679922Y1558775I0J203D01*
G01Y1559397D01*
G03X679872Y1559529I-200J0D01*
G02Y1562441I1664J1456D01*
G03X679922Y1562573I-150J132D01*
G01Y1564515D01*
G03X679872Y1564647I-200J0D01*
G02Y1567559I1664J1456D01*
G03X679922Y1567691I-150J132D01*
G01Y1568313D01*
G02X680125Y1568516I203J0D01*
G37*
G36*
G01X1130440D02*
X1133260D01*
G02X1133462Y1568313I-1J-203D01*
G01Y1567693D01*
G03X1133512Y1567561I200J0D01*
G02Y1564645I-1661J-1458D01*
G03X1133462Y1564513I150J-132D01*
G01Y1562575D01*
G03X1133512Y1562443I200J0D01*
G02Y1559527I-1661J-1458D01*
G03X1133462Y1559395I150J-132D01*
G01Y1558775D01*
G02X1133260Y1558572I-202J-1D01*
G01X1130440D01*
G02X1130238Y1558775I1J203D01*
G01Y1559395D01*
G03X1130188Y1559527I-200J0D01*
G02Y1562443I1661J1458D01*
G03X1130238Y1562575I-150J132D01*
G01Y1564513D01*
G03X1130188Y1564645I-200J0D01*
G02Y1567561I1661J1458D01*
G03X1130238Y1567693I-150J132D01*
G01Y1568313D01*
G02X1130440Y1568516I202J1D01*
G37*
G36*
G01X1147763D02*
X1150583D01*
G02X1150786Y1568313I0J-203D01*
G01Y1567691D01*
G03X1150836Y1567559I200J0D01*
G02Y1564647I-1664J-1456D01*
G03X1150786Y1564515I150J-132D01*
G01Y1562573D01*
G03X1150836Y1562441I200J0D01*
G02Y1559529I-1664J-1456D01*
G03X1150786Y1559397I150J-132D01*
G01Y1558775D01*
G02X1150583Y1558572I-203J0D01*
G01X1147763D01*
G02X1147560Y1558775I0J203D01*
G01Y1559397D01*
G03X1147510Y1559529I-200J0D01*
G02Y1562441I1664J1456D01*
G03X1147560Y1562573I-150J132D01*
G01Y1564515D01*
G03X1147510Y1564647I-200J0D01*
G02Y1567559I1664J1456D01*
G03X1147560Y1567691I-150J132D01*
G01Y1568313D01*
G02X1147763Y1568516I203J0D01*
G37*
G36*
G01X1165086D02*
X1167906D01*
G02X1168108Y1568313I-1J-203D01*
G01Y1567693D01*
G03X1168158Y1567561I200J0D01*
G02Y1564645I-1661J-1458D01*
G03X1168108Y1564513I150J-132D01*
G01Y1562575D01*
G03X1168158Y1562443I200J0D01*
G02Y1559527I-1661J-1458D01*
G03X1168108Y1559395I150J-132D01*
G01Y1558775D01*
G02X1167906Y1558572I-202J-1D01*
G01X1165086D01*
G02X1164884Y1558775I1J203D01*
G01Y1559395D01*
G03X1164834Y1559527I-200J0D01*
G02Y1562443I1661J1458D01*
G03X1164884Y1562575I-150J132D01*
G01Y1564513D01*
G03X1164834Y1564645I-200J0D01*
G02Y1567561I1661J1458D01*
G03X1164884Y1567693I-150J132D01*
G01Y1568313D01*
G02X1165086Y1568516I202J1D01*
G37*
G36*
G01X1182408D02*
X1185228D01*
G02X1185430Y1568313I-1J-203D01*
G01Y1567693D01*
G03X1185480Y1567561I200J0D01*
G02Y1564645I-1661J-1458D01*
G03X1185430Y1564513I150J-132D01*
G01Y1562575D01*
G03X1185480Y1562443I200J0D01*
G02Y1559527I-1661J-1458D01*
G03X1185430Y1559395I150J-132D01*
G01Y1558775D01*
G02X1185228Y1558572I-202J-1D01*
G01X1182408D01*
G02X1182206Y1558775I1J203D01*
G01Y1559395D01*
G03X1182156Y1559527I-200J0D01*
G02Y1562443I1661J1458D01*
G03X1182206Y1562575I-150J132D01*
G01Y1564513D01*
G03X1182156Y1564645I-200J0D01*
G02Y1567561I1661J1458D01*
G03X1182206Y1567693I-150J132D01*
G01Y1568313D01*
G02X1182408Y1568516I202J1D01*
G37*
G36*
G01X1303669D02*
X1306489D01*
G02X1306692Y1568313I0J-203D01*
G01Y1567691D01*
G03X1306742Y1567559I200J0D01*
G02Y1564647I-1664J-1456D01*
G03X1306692Y1564515I150J-132D01*
G01Y1562573D01*
G03X1306742Y1562441I200J0D01*
G02Y1559529I-1664J-1456D01*
G03X1306692Y1559397I150J-132D01*
G01Y1558775D01*
G02X1306489Y1558572I-203J0D01*
G01X1303669D01*
G02X1303466Y1558775I0J203D01*
G01Y1559397D01*
G03X1303416Y1559529I-200J0D01*
G02Y1562441I1664J1456D01*
G03X1303466Y1562573I-150J132D01*
G01Y1564515D01*
G03X1303416Y1564647I-200J0D01*
G02Y1567559I1664J1456D01*
G03X1303466Y1567691I-150J132D01*
G01Y1568313D01*
G02X1303669Y1568516I203J0D01*
G37*
G36*
G01X1320992D02*
X1323812D01*
G02X1324014Y1568313I-1J-203D01*
G01Y1567693D01*
G03X1324064Y1567561I200J0D01*
G02Y1564645I-1661J-1458D01*
G03X1324014Y1564513I150J-132D01*
G01Y1562575D01*
G03X1324064Y1562443I200J0D01*
G02Y1559527I-1661J-1458D01*
G03X1324014Y1559395I150J-132D01*
G01Y1558775D01*
G02X1323812Y1558572I-202J-1D01*
G01X1320992D01*
G02X1320790Y1558775I1J203D01*
G01Y1559395D01*
G03X1320740Y1559527I-200J0D01*
G02Y1562443I1661J1458D01*
G03X1320790Y1562575I-150J132D01*
G01Y1564513D01*
G03X1320740Y1564645I-200J0D01*
G02Y1567561I1661J1458D01*
G03X1320790Y1567693I-150J132D01*
G01Y1568313D01*
G02X1320992Y1568516I202J1D01*
G37*
G36*
G01X1338315D02*
X1341135D01*
G02X1341338Y1568313I0J-203D01*
G01Y1567691D01*
G03X1341388Y1567559I200J0D01*
G02Y1564647I-1664J-1456D01*
G03X1341338Y1564515I150J-132D01*
G01Y1562573D01*
G03X1341388Y1562441I200J0D01*
G02Y1559529I-1664J-1456D01*
G03X1341338Y1559397I150J-132D01*
G01Y1558775D01*
G02X1341135Y1558572I-203J0D01*
G01X1338315D01*
G02X1338112Y1558775I0J203D01*
G01Y1559397D01*
G03X1338062Y1559529I-200J0D01*
G02Y1562441I1664J1456D01*
G03X1338112Y1562573I-150J132D01*
G01Y1564515D01*
G03X1338062Y1564647I-200J0D01*
G02Y1567559I1664J1456D01*
G03X1338112Y1567691I-150J132D01*
G01Y1568313D01*
G02X1338315Y1568516I203J0D01*
G37*
G36*
G01X1355637D02*
X1358457D01*
G02X1358660Y1568313I0J-203D01*
G01Y1567691D01*
G03X1358710Y1567559I200J0D01*
G02Y1564647I-1664J-1456D01*
G03X1358660Y1564515I150J-132D01*
G01Y1562573D01*
G03X1358710Y1562441I200J0D01*
G02Y1559529I-1664J-1456D01*
G03X1358660Y1559397I150J-132D01*
G01Y1558775D01*
G02X1358457Y1558572I-203J0D01*
G01X1355637D01*
G02X1355434Y1558775I0J203D01*
G01Y1559397D01*
G03X1355384Y1559529I-200J0D01*
G02Y1562441I1664J1456D01*
G03X1355434Y1562573I-150J132D01*
G01Y1564515D01*
G03X1355384Y1564647I-200J0D01*
G02Y1567559I1664J1456D01*
G03X1355434Y1567691I-150J132D01*
G01Y1568313D01*
G02X1355637Y1568516I203J0D01*
G37*
G36*
G01X1476897D02*
X1479717D01*
G02X1479920Y1568313I0J-203D01*
G01Y1567691D01*
G03X1479970Y1567559I200J0D01*
G02Y1564647I-1664J-1456D01*
G03X1479920Y1564515I150J-132D01*
G01Y1562573D01*
G03X1479970Y1562441I200J0D01*
G02Y1559529I-1664J-1456D01*
G03X1479920Y1559397I150J-132D01*
G01Y1558775D01*
G02X1479717Y1558572I-203J0D01*
G01X1476897D01*
G02X1476694Y1558775I0J203D01*
G01Y1559397D01*
G03X1476644Y1559529I-200J0D01*
G02Y1562441I1664J1456D01*
G03X1476694Y1562573I-150J132D01*
G01Y1564515D01*
G03X1476644Y1564647I-200J0D01*
G02Y1567559I1664J1456D01*
G03X1476694Y1567691I-150J132D01*
G01Y1568313D01*
G02X1476897Y1568516I203J0D01*
G37*
G36*
G01X1650125D02*
X1652945D01*
G02X1653148Y1568313I0J-203D01*
G01Y1567691D01*
G03X1653198Y1567559I200J0D01*
G02Y1564647I-1664J-1456D01*
G03X1653148Y1564515I150J-132D01*
G01Y1562573D01*
G03X1653198Y1562441I200J0D01*
G02Y1559529I-1664J-1456D01*
G03X1653148Y1559397I150J-132D01*
G01Y1558775D01*
G02X1652945Y1558572I-203J0D01*
G01X1650125D01*
G02X1649922Y1558775I0J203D01*
G01Y1559397D01*
G03X1649872Y1559529I-200J0D01*
G02Y1562441I1664J1456D01*
G03X1649922Y1562573I-150J132D01*
G01Y1564515D01*
G03X1649872Y1564647I-200J0D01*
G02Y1567559I1664J1456D01*
G03X1649922Y1567691I-150J132D01*
G01Y1568313D01*
G02X1650125Y1568516I203J0D01*
G37*
G36*
G01X1667448D02*
X1670268D01*
G02X1670470Y1568313I-1J-203D01*
G01Y1567693D01*
G03X1670520Y1567561I200J0D01*
G02Y1564645I-1661J-1458D01*
G03X1670470Y1564513I150J-132D01*
G01Y1562575D01*
G03X1670520Y1562443I200J0D01*
G02Y1559527I-1661J-1458D01*
G03X1670470Y1559395I150J-132D01*
G01Y1558775D01*
G02X1670268Y1558572I-202J-1D01*
G01X1667448D01*
G02X1667246Y1558775I1J203D01*
G01Y1559395D01*
G03X1667196Y1559527I-200J0D01*
G02Y1562443I1661J1458D01*
G03X1667246Y1562575I-150J132D01*
G01Y1564513D01*
G03X1667196Y1564645I-200J0D01*
G02Y1567561I1661J1458D01*
G03X1667246Y1567693I-150J132D01*
G01Y1568313D01*
G02X1667448Y1568516I202J1D01*
G37*
G36*
G01X1684771D02*
X1687591D01*
G02X1687794Y1568313I0J-203D01*
G01Y1567691D01*
G03X1687844Y1567559I200J0D01*
G02Y1564647I-1664J-1456D01*
G03X1687794Y1564515I150J-132D01*
G01Y1562573D01*
G03X1687844Y1562441I200J0D01*
G02Y1559529I-1664J-1456D01*
G03X1687794Y1559397I150J-132D01*
G01Y1558775D01*
G02X1687591Y1558572I-203J0D01*
G01X1684771D01*
G02X1684568Y1558775I0J203D01*
G01Y1559397D01*
G03X1684518Y1559529I-200J0D01*
G02Y1562441I1664J1456D01*
G03X1684568Y1562573I-150J132D01*
G01Y1564515D01*
G03X1684518Y1564647I-200J0D01*
G02Y1567559I1664J1456D01*
G03X1684568Y1567691I-150J132D01*
G01Y1568313D01*
G02X1684771Y1568516I203J0D01*
G37*
G36*
G01X1702093D02*
X1704913D01*
G02X1705116Y1568313I0J-203D01*
G01Y1567691D01*
G03X1705166Y1567559I200J0D01*
G02Y1564647I-1664J-1456D01*
G03X1705116Y1564515I150J-132D01*
G01Y1562573D01*
G03X1705166Y1562441I200J0D01*
G02Y1559529I-1664J-1456D01*
G03X1705116Y1559397I150J-132D01*
G01Y1558775D01*
G02X1704913Y1558572I-203J0D01*
G01X1702093D01*
G02X1701890Y1558775I0J203D01*
G01Y1559397D01*
G03X1701840Y1559529I-200J0D01*
G02Y1562441I1664J1456D01*
G03X1701890Y1562573I-150J132D01*
G01Y1564515D01*
G03X1701840Y1564647I-200J0D01*
G02Y1567559I1664J1456D01*
G03X1701890Y1567691I-150J132D01*
G01Y1568313D01*
G02X1702093Y1568516I203J0D01*
G37*
G36*
G01X134456Y1572846D02*
X137276D01*
G02X137478Y1572644I0J-202D01*
G01Y1572024D01*
G03X137528Y1571892I200J0D01*
G02Y1568976I-1661J-1458D01*
G03X137478Y1568844I150J-132D01*
G01Y1566905D01*
G03X137528Y1566773I200J0D01*
G02Y1563857I-1661J-1458D01*
G03X137478Y1563725I150J-132D01*
G01Y1563106D01*
G02X137276Y1562904I-202J0D01*
G01X134456D01*
G02X134254Y1563106I0J202D01*
G01Y1563725D01*
G03X134204Y1563857I-200J0D01*
G02Y1566773I1661J1458D01*
G03X134254Y1566905I-150J132D01*
G01Y1568844D01*
G03X134204Y1568976I-200J0D01*
G02Y1571892I1661J1458D01*
G03X134254Y1572024I-150J132D01*
G01Y1572644D01*
G02X134456Y1572846I202J0D01*
G37*
G36*
G01X169102D02*
X171922D01*
G02X172124Y1572644I0J-202D01*
G01Y1572024D01*
G03X172174Y1571892I200J0D01*
G02Y1568976I-1661J-1458D01*
G03X172124Y1568844I150J-132D01*
G01Y1566905D01*
G03X172174Y1566773I200J0D01*
G02Y1563857I-1661J-1458D01*
G03X172124Y1563725I150J-132D01*
G01Y1563106D01*
G02X171922Y1562904I-202J0D01*
G01X169102D01*
G02X168900Y1563106I0J202D01*
G01Y1563725D01*
G03X168850Y1563857I-200J0D01*
G02Y1566773I1661J1458D01*
G03X168900Y1566905I-150J132D01*
G01Y1568844D01*
G03X168850Y1568976I-200J0D01*
G02Y1571892I1661J1458D01*
G03X168900Y1572024I-150J132D01*
G01Y1572644D01*
G02X169102Y1572846I202J0D01*
G37*
G36*
G01X307684D02*
X310504D01*
G02X310706Y1572644I0J-202D01*
G01Y1572024D01*
G03X310756Y1571892I200J0D01*
G02Y1568976I-1661J-1458D01*
G03X310706Y1568844I150J-132D01*
G01Y1566905D01*
G03X310756Y1566773I200J0D01*
G02Y1563857I-1661J-1458D01*
G03X310706Y1563725I150J-132D01*
G01Y1563106D01*
G02X310504Y1562904I-202J0D01*
G01X307684D01*
G02X307482Y1563106I0J202D01*
G01Y1563725D01*
G03X307432Y1563857I-200J0D01*
G02Y1566773I1661J1458D01*
G03X307482Y1566905I-150J132D01*
G01Y1568844D01*
G03X307432Y1568976I-200J0D01*
G02Y1571892I1661J1458D01*
G03X307482Y1572024I-150J132D01*
G01Y1572644D01*
G02X307684Y1572846I202J0D01*
G37*
G36*
G01X342330D02*
X345150D01*
G02X345352Y1572644I0J-202D01*
G01Y1572024D01*
G03X345402Y1571892I200J0D01*
G02Y1568976I-1661J-1458D01*
G03X345352Y1568844I150J-132D01*
G01Y1566905D01*
G03X345402Y1566773I200J0D01*
G02Y1563857I-1661J-1458D01*
G03X345352Y1563725I150J-132D01*
G01Y1563106D01*
G02X345150Y1562904I-202J0D01*
G01X342330D01*
G02X342128Y1563106I0J202D01*
G01Y1563725D01*
G03X342078Y1563857I-200J0D01*
G02Y1566773I1661J1458D01*
G03X342128Y1566905I-150J132D01*
G01Y1568844D01*
G03X342078Y1568976I-200J0D01*
G02Y1571892I1661J1458D01*
G03X342128Y1572024I-150J132D01*
G01Y1572644D01*
G02X342330Y1572846I202J0D01*
G37*
G36*
G01X636818D02*
X639638D01*
G02X639840Y1572644I0J-202D01*
G01Y1572024D01*
G03X639890Y1571892I200J0D01*
G02Y1568976I-1661J-1458D01*
G03X639840Y1568844I150J-132D01*
G01Y1566905D01*
G03X639890Y1566773I200J0D01*
G02Y1563857I-1661J-1458D01*
G03X639840Y1563725I150J-132D01*
G01Y1563106D01*
G02X639638Y1562904I-202J0D01*
G01X636818D01*
G02X636616Y1563106I0J202D01*
G01Y1563725D01*
G03X636566Y1563857I-200J0D01*
G02Y1566773I1661J1458D01*
G03X636616Y1566905I-150J132D01*
G01Y1568844D01*
G03X636566Y1568976I-200J0D01*
G02Y1571892I1661J1458D01*
G03X636616Y1572024I-150J132D01*
G01Y1572644D01*
G02X636818Y1572846I202J0D01*
G37*
G36*
G01X671464D02*
X674284D01*
G02X674486Y1572644I0J-202D01*
G01Y1572024D01*
G03X674536Y1571892I200J0D01*
G02Y1568976I-1661J-1458D01*
G03X674486Y1568844I150J-132D01*
G01Y1566905D01*
G03X674536Y1566773I200J0D01*
G02Y1563857I-1661J-1458D01*
G03X674486Y1563725I150J-132D01*
G01Y1563106D01*
G02X674284Y1562904I-202J0D01*
G01X671464D01*
G02X671262Y1563106I0J202D01*
G01Y1563725D01*
G03X671212Y1563857I-200J0D01*
G02Y1566773I1661J1458D01*
G03X671262Y1566905I-150J132D01*
G01Y1568844D01*
G03X671212Y1568976I-200J0D01*
G02Y1571892I1661J1458D01*
G03X671262Y1572024I-150J132D01*
G01Y1572644D01*
G02X671464Y1572846I202J0D01*
G37*
G36*
G01X1156424D02*
X1159244D01*
G02X1159446Y1572644I0J-202D01*
G01Y1572024D01*
G03X1159496Y1571892I200J0D01*
G02Y1568976I-1661J-1458D01*
G03X1159446Y1568844I150J-132D01*
G01Y1566905D01*
G03X1159496Y1566773I200J0D01*
G02Y1563857I-1661J-1458D01*
G03X1159446Y1563725I150J-132D01*
G01Y1563106D01*
G02X1159244Y1562904I-202J0D01*
G01X1156424D01*
G02X1156222Y1563106I0J202D01*
G01Y1563725D01*
G03X1156172Y1563857I-200J0D01*
G02Y1566773I1661J1458D01*
G03X1156222Y1566905I-150J132D01*
G01Y1568844D01*
G03X1156172Y1568976I-200J0D01*
G02Y1571892I1661J1458D01*
G03X1156222Y1572024I-150J132D01*
G01Y1572644D01*
G02X1156424Y1572846I202J0D01*
G37*
G36*
G01X1191070D02*
X1193890D01*
G02X1194092Y1572644I0J-202D01*
G01Y1572024D01*
G03X1194142Y1571892I200J0D01*
G02Y1568976I-1661J-1458D01*
G03X1194092Y1568844I150J-132D01*
G01Y1566905D01*
G03X1194142Y1566773I200J0D01*
G02Y1563857I-1661J-1458D01*
G03X1194092Y1563725I150J-132D01*
G01Y1563106D01*
G02X1193890Y1562904I-202J0D01*
G01X1191070D01*
G02X1190868Y1563106I0J202D01*
G01Y1563725D01*
G03X1190818Y1563857I-200J0D01*
G02Y1566773I1661J1458D01*
G03X1190868Y1566905I-150J132D01*
G01Y1568844D01*
G03X1190818Y1568976I-200J0D01*
G02Y1571892I1661J1458D01*
G03X1190868Y1572024I-150J132D01*
G01Y1572644D01*
G02X1191070Y1572846I202J0D01*
G37*
G36*
G01X1312330D02*
X1315150D01*
G02X1315352Y1572644I0J-202D01*
G01Y1572024D01*
G03X1315402Y1571892I200J0D01*
G02Y1568976I-1661J-1458D01*
G03X1315352Y1568844I150J-132D01*
G01Y1566905D01*
G03X1315402Y1566773I200J0D01*
G02Y1563857I-1661J-1458D01*
G03X1315352Y1563725I150J-132D01*
G01Y1563106D01*
G02X1315150Y1562904I-202J0D01*
G01X1312330D01*
G02X1312128Y1563106I0J202D01*
G01Y1563725D01*
G03X1312078Y1563857I-200J0D01*
G02Y1566773I1661J1458D01*
G03X1312128Y1566905I-150J132D01*
G01Y1568844D01*
G03X1312078Y1568976I-200J0D01*
G02Y1571892I1661J1458D01*
G03X1312128Y1572024I-150J132D01*
G01Y1572644D01*
G02X1312330Y1572846I202J0D01*
G37*
G36*
G01X1346976D02*
X1349796D01*
G02X1349998Y1572644I0J-202D01*
G01Y1572024D01*
G03X1350048Y1571892I200J0D01*
G02Y1568976I-1661J-1458D01*
G03X1349998Y1568844I150J-132D01*
G01Y1566905D01*
G03X1350048Y1566773I200J0D01*
G02Y1563857I-1661J-1458D01*
G03X1349998Y1563725I150J-132D01*
G01Y1563106D01*
G02X1349796Y1562904I-202J0D01*
G01X1346976D01*
G02X1346774Y1563106I0J202D01*
G01Y1563725D01*
G03X1346724Y1563857I-200J0D01*
G02Y1566773I1661J1458D01*
G03X1346774Y1566905I-150J132D01*
G01Y1568844D01*
G03X1346724Y1568976I-200J0D01*
G02Y1571892I1661J1458D01*
G03X1346774Y1572024I-150J132D01*
G01Y1572644D01*
G02X1346976Y1572846I202J0D01*
G37*
G36*
G01X1658786D02*
X1661606D01*
G02X1661808Y1572644I0J-202D01*
G01Y1572024D01*
G03X1661858Y1571892I200J0D01*
G02Y1568976I-1661J-1458D01*
G03X1661808Y1568844I150J-132D01*
G01Y1566905D01*
G03X1661858Y1566773I200J0D01*
G02Y1563857I-1661J-1458D01*
G03X1661808Y1563725I150J-132D01*
G01Y1563106D01*
G02X1661606Y1562904I-202J0D01*
G01X1658786D01*
G02X1658584Y1563106I0J202D01*
G01Y1563725D01*
G03X1658534Y1563857I-200J0D01*
G02Y1566773I1661J1458D01*
G03X1658584Y1566905I-150J132D01*
G01Y1568844D01*
G03X1658534Y1568976I-200J0D01*
G02Y1571892I1661J1458D01*
G03X1658584Y1572024I-150J132D01*
G01Y1572644D01*
G02X1658786Y1572846I202J0D01*
G37*
G36*
G01X1693432D02*
X1696252D01*
G02X1696454Y1572644I0J-202D01*
G01Y1572024D01*
G03X1696504Y1571892I200J0D01*
G02Y1568976I-1661J-1458D01*
G03X1696454Y1568844I150J-132D01*
G01Y1566905D01*
G03X1696504Y1566773I200J0D01*
G02Y1563857I-1661J-1458D01*
G03X1696454Y1563725I150J-132D01*
G01Y1563106D01*
G02X1696252Y1562904I-202J0D01*
G01X1693432D01*
G02X1693230Y1563106I0J202D01*
G01Y1563725D01*
G03X1693180Y1563857I-200J0D01*
G02Y1566773I1661J1458D01*
G03X1693230Y1566905I-150J132D01*
G01Y1568844D01*
G03X1693180Y1568976I-200J0D01*
G02Y1571892I1661J1458D01*
G03X1693230Y1572024I-150J132D01*
G01Y1572644D01*
G02X1693432Y1572846I202J0D01*
G37*
G36*
G01X117133D02*
X119953D01*
G02X120156Y1572644I1J-202D01*
G01Y1572022D01*
G03X120206Y1571890I200J0D01*
G02Y1568978I-1664J-1456D01*
G03X120156Y1568846I150J-132D01*
G01Y1566903D01*
G03X120206Y1566771I200J0D01*
G02Y1563859I-1664J-1456D01*
G03X120156Y1563727I150J-132D01*
G01Y1563106D01*
G02X119953Y1562904I-203J1D01*
G01X117133D01*
G02X116930Y1563106I-1J202D01*
G01Y1563727D01*
G03X116880Y1563859I-200J0D01*
G02Y1566771I1664J1456D01*
G03X116930Y1566903I-150J132D01*
G01Y1568846D01*
G03X116880Y1568978I-200J0D01*
G02Y1571890I1664J1456D01*
G03X116930Y1572022I-150J132D01*
G01Y1572644D01*
G02X117133Y1572846I203J-1D01*
G37*
G36*
G01X151779D02*
X154599D01*
G02X154802Y1572644I1J-202D01*
G01Y1572022D01*
G03X154852Y1571890I200J0D01*
G02Y1568978I-1664J-1456D01*
G03X154802Y1568846I150J-132D01*
G01Y1566903D01*
G03X154852Y1566771I200J0D01*
G02Y1563859I-1664J-1456D01*
G03X154802Y1563727I150J-132D01*
G01Y1563106D01*
G02X154599Y1562904I-203J1D01*
G01X151779D01*
G02X151576Y1563106I-1J202D01*
G01Y1563727D01*
G03X151526Y1563859I-200J0D01*
G02Y1566771I1664J1456D01*
G03X151576Y1566903I-150J132D01*
G01Y1568846D01*
G03X151526Y1568978I-200J0D01*
G02Y1571890I1664J1456D01*
G03X151576Y1572022I-150J132D01*
G01Y1572644D01*
G02X151779Y1572846I203J-1D01*
G37*
G36*
G01X290361D02*
X293181D01*
G02X293384Y1572644I1J-202D01*
G01Y1572022D01*
G03X293434Y1571890I200J0D01*
G02Y1568978I-1664J-1456D01*
G03X293384Y1568846I150J-132D01*
G01Y1566903D01*
G03X293434Y1566771I200J0D01*
G02Y1563859I-1664J-1456D01*
G03X293384Y1563727I150J-132D01*
G01Y1563106D01*
G02X293181Y1562904I-203J1D01*
G01X290361D01*
G02X290158Y1563106I-1J202D01*
G01Y1563727D01*
G03X290108Y1563859I-200J0D01*
G02Y1566771I1664J1456D01*
G03X290158Y1566903I-150J132D01*
G01Y1568846D01*
G03X290108Y1568978I-200J0D01*
G02Y1571890I1664J1456D01*
G03X290158Y1572022I-150J132D01*
G01Y1572644D01*
G02X290361Y1572846I203J-1D01*
G37*
G36*
G01X325007D02*
X327827D01*
G02X328030Y1572644I1J-202D01*
G01Y1572022D01*
G03X328080Y1571890I200J0D01*
G02Y1568978I-1664J-1456D01*
G03X328030Y1568846I150J-132D01*
G01Y1566903D01*
G03X328080Y1566771I200J0D01*
G02Y1563859I-1664J-1456D01*
G03X328030Y1563727I150J-132D01*
G01Y1563106D01*
G02X327827Y1562904I-203J1D01*
G01X325007D01*
G02X324804Y1563106I-1J202D01*
G01Y1563727D01*
G03X324754Y1563859I-200J0D01*
G02Y1566771I1664J1456D01*
G03X324804Y1566903I-150J132D01*
G01Y1568846D01*
G03X324754Y1568978I-200J0D01*
G02Y1571890I1664J1456D01*
G03X324804Y1572022I-150J132D01*
G01Y1572644D01*
G02X325007Y1572846I203J-1D01*
G37*
G36*
G01X515559D02*
X518379D01*
G02X518582Y1572644I1J-202D01*
G01Y1572022D01*
G03X518632Y1571890I200J0D01*
G02Y1568978I-1664J-1456D01*
G03X518582Y1568846I150J-132D01*
G01Y1566903D01*
G03X518632Y1566771I200J0D01*
G02Y1563859I-1664J-1456D01*
G03X518582Y1563727I150J-132D01*
G01Y1563106D01*
G02X518379Y1562904I-203J1D01*
G01X515559D01*
G02X515356Y1563106I-1J202D01*
G01Y1563727D01*
G03X515306Y1563859I-200J0D01*
G02Y1566771I1664J1456D01*
G03X515356Y1566903I-150J132D01*
G01Y1568846D01*
G03X515306Y1568978I-200J0D01*
G02Y1571890I1664J1456D01*
G03X515356Y1572022I-150J132D01*
G01Y1572644D01*
G02X515559Y1572846I203J-1D01*
G37*
G36*
G01X654141D02*
X656961D01*
G02X657164Y1572644I1J-202D01*
G01Y1572022D01*
G03X657214Y1571890I200J0D01*
G02Y1568978I-1664J-1456D01*
G03X657164Y1568846I150J-132D01*
G01Y1566903D01*
G03X657214Y1566771I200J0D01*
G02Y1563859I-1664J-1456D01*
G03X657164Y1563727I150J-132D01*
G01Y1563106D01*
G02X656961Y1562904I-203J1D01*
G01X654141D01*
G02X653938Y1563106I-1J202D01*
G01Y1563727D01*
G03X653888Y1563859I-200J0D01*
G02Y1566771I1664J1456D01*
G03X653938Y1566903I-150J132D01*
G01Y1568846D01*
G03X653888Y1568978I-200J0D01*
G02Y1571890I1664J1456D01*
G03X653938Y1572022I-150J132D01*
G01Y1572644D01*
G02X654141Y1572846I203J-1D01*
G37*
G36*
G01X688787D02*
X691607D01*
G02X691810Y1572644I1J-202D01*
G01Y1572022D01*
G03X691860Y1571890I200J0D01*
G02Y1568978I-1664J-1456D01*
G03X691810Y1568846I150J-132D01*
G01Y1566903D01*
G03X691860Y1566771I200J0D01*
G02Y1563859I-1664J-1456D01*
G03X691810Y1563727I150J-132D01*
G01Y1563106D01*
G02X691607Y1562904I-203J1D01*
G01X688787D01*
G02X688584Y1563106I-1J202D01*
G01Y1563727D01*
G03X688534Y1563859I-200J0D01*
G02Y1566771I1664J1456D01*
G03X688584Y1566903I-150J132D01*
G01Y1568846D01*
G03X688534Y1568978I-200J0D01*
G02Y1571890I1664J1456D01*
G03X688584Y1572022I-150J132D01*
G01Y1572644D01*
G02X688787Y1572846I203J-1D01*
G37*
G36*
G01X1139101D02*
X1141921D01*
G02X1142124Y1572644I1J-202D01*
G01Y1572022D01*
G03X1142174Y1571890I200J0D01*
G02Y1568978I-1664J-1456D01*
G03X1142124Y1568846I150J-132D01*
G01Y1566903D01*
G03X1142174Y1566771I200J0D01*
G02Y1563859I-1664J-1456D01*
G03X1142124Y1563727I150J-132D01*
G01Y1563106D01*
G02X1141921Y1562904I-203J1D01*
G01X1139101D01*
G02X1138898Y1563106I-1J202D01*
G01Y1563727D01*
G03X1138848Y1563859I-200J0D01*
G02Y1566771I1664J1456D01*
G03X1138898Y1566903I-150J132D01*
G01Y1568846D01*
G03X1138848Y1568978I-200J0D01*
G02Y1571890I1664J1456D01*
G03X1138898Y1572022I-150J132D01*
G01Y1572644D01*
G02X1139101Y1572846I203J-1D01*
G37*
G36*
G01X1173747D02*
X1176567D01*
G02X1176770Y1572644I1J-202D01*
G01Y1572022D01*
G03X1176820Y1571890I200J0D01*
G02Y1568978I-1664J-1456D01*
G03X1176770Y1568846I150J-132D01*
G01Y1566903D01*
G03X1176820Y1566771I200J0D01*
G02Y1563859I-1664J-1456D01*
G03X1176770Y1563727I150J-132D01*
G01Y1563106D01*
G02X1176567Y1562904I-203J1D01*
G01X1173747D01*
G02X1173544Y1563106I-1J202D01*
G01Y1563727D01*
G03X1173494Y1563859I-200J0D01*
G02Y1566771I1664J1456D01*
G03X1173544Y1566903I-150J132D01*
G01Y1568846D01*
G03X1173494Y1568978I-200J0D01*
G02Y1571890I1664J1456D01*
G03X1173544Y1572022I-150J132D01*
G01Y1572644D01*
G02X1173747Y1572846I203J-1D01*
G37*
G36*
G01X1329653D02*
X1332473D01*
G02X1332676Y1572644I1J-202D01*
G01Y1572022D01*
G03X1332726Y1571890I200J0D01*
G02Y1568978I-1664J-1456D01*
G03X1332676Y1568846I150J-132D01*
G01Y1566903D01*
G03X1332726Y1566771I200J0D01*
G02Y1563859I-1664J-1456D01*
G03X1332676Y1563727I150J-132D01*
G01Y1563106D01*
G02X1332473Y1562904I-203J1D01*
G01X1329653D01*
G02X1329450Y1563106I-1J202D01*
G01Y1563727D01*
G03X1329400Y1563859I-200J0D01*
G02Y1566771I1664J1456D01*
G03X1329450Y1566903I-150J132D01*
G01Y1568846D01*
G03X1329400Y1568978I-200J0D01*
G02Y1571890I1664J1456D01*
G03X1329450Y1572022I-150J132D01*
G01Y1572644D01*
G02X1329653Y1572846I203J-1D01*
G37*
G36*
G01X1364299D02*
X1367119D01*
G02X1367322Y1572644I1J-202D01*
G01Y1572022D01*
G03X1367372Y1571890I200J0D01*
G02Y1568978I-1664J-1456D01*
G03X1367322Y1568846I150J-132D01*
G01Y1566903D01*
G03X1367372Y1566771I200J0D01*
G02Y1563859I-1664J-1456D01*
G03X1367322Y1563727I150J-132D01*
G01Y1563106D01*
G02X1367119Y1562904I-203J1D01*
G01X1364299D01*
G02X1364096Y1563106I-1J202D01*
G01Y1563727D01*
G03X1364046Y1563859I-200J0D01*
G02Y1566771I1664J1456D01*
G03X1364096Y1566903I-150J132D01*
G01Y1568846D01*
G03X1364046Y1568978I-200J0D01*
G02Y1571890I1664J1456D01*
G03X1364096Y1572022I-150J132D01*
G01Y1572644D01*
G02X1364299Y1572846I203J-1D01*
G37*
G36*
G01X1676109D02*
X1678929D01*
G02X1679132Y1572644I1J-202D01*
G01Y1572022D01*
G03X1679182Y1571890I200J0D01*
G02Y1568978I-1664J-1456D01*
G03X1679132Y1568846I150J-132D01*
G01Y1566903D01*
G03X1679182Y1566771I200J0D01*
G02Y1563859I-1664J-1456D01*
G03X1679132Y1563727I150J-132D01*
G01Y1563106D01*
G02X1678929Y1562904I-203J1D01*
G01X1676109D01*
G02X1675906Y1563106I-1J202D01*
G01Y1563727D01*
G03X1675856Y1563859I-200J0D01*
G02Y1566771I1664J1456D01*
G03X1675906Y1566903I-150J132D01*
G01Y1568846D01*
G03X1675856Y1568978I-200J0D01*
G02Y1571890I1664J1456D01*
G03X1675906Y1572022I-150J132D01*
G01Y1572644D01*
G02X1676109Y1572846I203J-1D01*
G37*
G36*
G01X1710755D02*
X1713575D01*
G02X1713778Y1572644I1J-202D01*
G01Y1572022D01*
G03X1713828Y1571890I200J0D01*
G02Y1568978I-1664J-1456D01*
G03X1713778Y1568846I150J-132D01*
G01Y1566903D01*
G03X1713828Y1566771I200J0D01*
G02Y1563859I-1664J-1456D01*
G03X1713778Y1563727I150J-132D01*
G01Y1563106D01*
G02X1713575Y1562904I-203J1D01*
G01X1710755D01*
G02X1710552Y1563106I-1J202D01*
G01Y1563727D01*
G03X1710502Y1563859I-200J0D01*
G02Y1566771I1664J1456D01*
G03X1710552Y1566903I-150J132D01*
G01Y1568846D01*
G03X1710502Y1568978I-200J0D01*
G02Y1571890I1664J1456D01*
G03X1710552Y1572022I-150J132D01*
G01Y1572644D01*
G02X1710755Y1572846I203J-1D01*
G37*
G36*
G01X108472Y1583870D02*
X111292D01*
G02X111494Y1583667I-1J-203D01*
G01Y1583047D01*
G03X111544Y1582915I200J0D01*
G02Y1579999I-1661J-1458D01*
G03X111494Y1579867I150J-132D01*
G01Y1577929D01*
G03X111544Y1577797I200J0D01*
G02Y1574881I-1661J-1458D01*
G03X111494Y1574749I150J-132D01*
G01Y1574129D01*
G02X111292Y1573926I-202J-1D01*
G01X108472D01*
G02X108270Y1574129I1J203D01*
G01Y1574749D01*
G03X108220Y1574881I-200J0D01*
G02Y1577797I1661J1458D01*
G03X108270Y1577929I-150J132D01*
G01Y1579867D01*
G03X108220Y1579999I-200J0D01*
G02Y1582915I1661J1458D01*
G03X108270Y1583047I-150J132D01*
G01Y1583667D01*
G02X108472Y1583870I202J1D01*
G37*
G36*
G01X125795D02*
X128615D01*
G02X128818Y1583667I0J-203D01*
G01Y1583045D01*
G03X128868Y1582913I200J0D01*
G02Y1580001I-1664J-1456D01*
G03X128818Y1579869I150J-132D01*
G01Y1577927D01*
G03X128868Y1577795I200J0D01*
G02Y1574883I-1664J-1456D01*
G03X128818Y1574751I150J-132D01*
G01Y1574129D01*
G02X128615Y1573926I-203J0D01*
G01X125795D01*
G02X125592Y1574129I0J203D01*
G01Y1574751D01*
G03X125542Y1574883I-200J0D01*
G02Y1577795I1664J1456D01*
G03X125592Y1577927I-150J132D01*
G01Y1579869D01*
G03X125542Y1580001I-200J0D01*
G02Y1582913I1664J1456D01*
G03X125592Y1583045I-150J132D01*
G01Y1583667D01*
G02X125795Y1583870I203J0D01*
G37*
G36*
G01X143118D02*
X145938D01*
G02X146140Y1583667I-1J-203D01*
G01Y1583047D01*
G03X146190Y1582915I200J0D01*
G02Y1579999I-1661J-1458D01*
G03X146140Y1579867I150J-132D01*
G01Y1577929D01*
G03X146190Y1577797I200J0D01*
G02Y1574881I-1661J-1458D01*
G03X146140Y1574749I150J-132D01*
G01Y1574129D01*
G02X145938Y1573926I-202J-1D01*
G01X143118D01*
G02X142916Y1574129I1J203D01*
G01Y1574749D01*
G03X142866Y1574881I-200J0D01*
G02Y1577797I1661J1458D01*
G03X142916Y1577929I-150J132D01*
G01Y1579867D01*
G03X142866Y1579999I-200J0D01*
G02Y1582915I1661J1458D01*
G03X142916Y1583047I-150J132D01*
G01Y1583667D01*
G02X143118Y1583870I202J1D01*
G37*
G36*
G01X160440D02*
X163260D01*
G02X163462Y1583667I-1J-203D01*
G01Y1583047D01*
G03X163512Y1582915I200J0D01*
G02Y1579999I-1661J-1458D01*
G03X163462Y1579867I150J-132D01*
G01Y1577929D01*
G03X163512Y1577797I200J0D01*
G02Y1574881I-1661J-1458D01*
G03X163462Y1574749I150J-132D01*
G01Y1574129D01*
G02X163260Y1573926I-202J-1D01*
G01X160440D01*
G02X160238Y1574129I1J203D01*
G01Y1574749D01*
G03X160188Y1574881I-200J0D01*
G02Y1577797I1661J1458D01*
G03X160238Y1577929I-150J132D01*
G01Y1579867D01*
G03X160188Y1579999I-200J0D01*
G02Y1582915I1661J1458D01*
G03X160238Y1583047I-150J132D01*
G01Y1583667D01*
G02X160440Y1583870I202J1D01*
G37*
G36*
G01X281700D02*
X284520D01*
G02X284722Y1583667I-1J-203D01*
G01Y1583047D01*
G03X284772Y1582915I200J0D01*
G02Y1579999I-1661J-1458D01*
G03X284722Y1579867I150J-132D01*
G01Y1577929D01*
G03X284772Y1577797I200J0D01*
G02Y1574881I-1661J-1458D01*
G03X284722Y1574749I150J-132D01*
G01Y1574129D01*
G02X284520Y1573926I-202J-1D01*
G01X281700D01*
G02X281498Y1574129I1J203D01*
G01Y1574749D01*
G03X281448Y1574881I-200J0D01*
G02Y1577797I1661J1458D01*
G03X281498Y1577929I-150J132D01*
G01Y1579867D01*
G03X281448Y1579999I-200J0D01*
G02Y1582915I1661J1458D01*
G03X281498Y1583047I-150J132D01*
G01Y1583667D01*
G02X281700Y1583870I202J1D01*
G37*
G36*
G01X299023D02*
X301843D01*
G02X302046Y1583667I0J-203D01*
G01Y1583045D01*
G03X302096Y1582913I200J0D01*
G02Y1580001I-1664J-1456D01*
G03X302046Y1579869I150J-132D01*
G01Y1577927D01*
G03X302096Y1577795I200J0D01*
G02Y1574883I-1664J-1456D01*
G03X302046Y1574751I150J-132D01*
G01Y1574129D01*
G02X301843Y1573926I-203J0D01*
G01X299023D01*
G02X298820Y1574129I0J203D01*
G01Y1574751D01*
G03X298770Y1574883I-200J0D01*
G02Y1577795I1664J1456D01*
G03X298820Y1577927I-150J132D01*
G01Y1579869D01*
G03X298770Y1580001I-200J0D01*
G02Y1582913I1664J1456D01*
G03X298820Y1583045I-150J132D01*
G01Y1583667D01*
G02X299023Y1583870I203J0D01*
G37*
G36*
G01X316346D02*
X319166D01*
G02X319368Y1583667I-1J-203D01*
G01Y1583047D01*
G03X319418Y1582915I200J0D01*
G02Y1579999I-1661J-1458D01*
G03X319368Y1579867I150J-132D01*
G01Y1577929D01*
G03X319418Y1577797I200J0D01*
G02Y1574881I-1661J-1458D01*
G03X319368Y1574749I150J-132D01*
G01Y1574129D01*
G02X319166Y1573926I-202J-1D01*
G01X316346D01*
G02X316144Y1574129I1J203D01*
G01Y1574749D01*
G03X316094Y1574881I-200J0D01*
G02Y1577797I1661J1458D01*
G03X316144Y1577929I-150J132D01*
G01Y1579867D01*
G03X316094Y1579999I-200J0D01*
G02Y1582915I1661J1458D01*
G03X316144Y1583047I-150J132D01*
G01Y1583667D01*
G02X316346Y1583870I202J1D01*
G37*
G36*
G01X333668D02*
X336488D01*
G02X336690Y1583667I-1J-203D01*
G01Y1583047D01*
G03X336740Y1582915I200J0D01*
G02Y1579999I-1661J-1458D01*
G03X336690Y1579867I150J-132D01*
G01Y1577929D01*
G03X336740Y1577797I200J0D01*
G02Y1574881I-1661J-1458D01*
G03X336690Y1574749I150J-132D01*
G01Y1574129D01*
G02X336488Y1573926I-202J-1D01*
G01X333668D01*
G02X333466Y1574129I1J203D01*
G01Y1574749D01*
G03X333416Y1574881I-200J0D01*
G02Y1577797I1661J1458D01*
G03X333466Y1577929I-150J132D01*
G01Y1579867D01*
G03X333416Y1579999I-200J0D01*
G02Y1582915I1661J1458D01*
G03X333466Y1583047I-150J132D01*
G01Y1583667D01*
G02X333668Y1583870I202J1D01*
G37*
G36*
G01X628157D02*
X630977D01*
G02X631180Y1583667I0J-203D01*
G01Y1583045D01*
G03X631230Y1582913I200J0D01*
G02Y1580001I-1664J-1456D01*
G03X631180Y1579869I150J-132D01*
G01Y1577927D01*
G03X631230Y1577795I200J0D01*
G02Y1574883I-1664J-1456D01*
G03X631180Y1574751I150J-132D01*
G01Y1574129D01*
G02X630977Y1573926I-203J0D01*
G01X628157D01*
G02X627954Y1574129I0J203D01*
G01Y1574751D01*
G03X627904Y1574883I-200J0D01*
G02Y1577795I1664J1456D01*
G03X627954Y1577927I-150J132D01*
G01Y1579869D01*
G03X627904Y1580001I-200J0D01*
G02Y1582913I1664J1456D01*
G03X627954Y1583045I-150J132D01*
G01Y1583667D01*
G02X628157Y1583870I203J0D01*
G37*
G36*
G01X645480D02*
X648300D01*
G02X648502Y1583667I-1J-203D01*
G01Y1583047D01*
G03X648552Y1582915I200J0D01*
G02Y1579999I-1661J-1458D01*
G03X648502Y1579867I150J-132D01*
G01Y1577929D01*
G03X648552Y1577797I200J0D01*
G02Y1574881I-1661J-1458D01*
G03X648502Y1574749I150J-132D01*
G01Y1574129D01*
G02X648300Y1573926I-202J-1D01*
G01X645480D01*
G02X645278Y1574129I1J203D01*
G01Y1574749D01*
G03X645228Y1574881I-200J0D01*
G02Y1577797I1661J1458D01*
G03X645278Y1577929I-150J132D01*
G01Y1579867D01*
G03X645228Y1579999I-200J0D01*
G02Y1582915I1661J1458D01*
G03X645278Y1583047I-150J132D01*
G01Y1583667D01*
G02X645480Y1583870I202J1D01*
G37*
G36*
G01X662803D02*
X665623D01*
G02X665826Y1583667I0J-203D01*
G01Y1583045D01*
G03X665876Y1582913I200J0D01*
G02Y1580001I-1664J-1456D01*
G03X665826Y1579869I150J-132D01*
G01Y1577927D01*
G03X665876Y1577795I200J0D01*
G02Y1574883I-1664J-1456D01*
G03X665826Y1574751I150J-132D01*
G01Y1574129D01*
G02X665623Y1573926I-203J0D01*
G01X662803D01*
G02X662600Y1574129I0J203D01*
G01Y1574751D01*
G03X662550Y1574883I-200J0D01*
G02Y1577795I1664J1456D01*
G03X662600Y1577927I-150J132D01*
G01Y1579869D01*
G03X662550Y1580001I-200J0D01*
G02Y1582913I1664J1456D01*
G03X662600Y1583045I-150J132D01*
G01Y1583667D01*
G02X662803Y1583870I203J0D01*
G37*
G36*
G01X680125D02*
X682945D01*
G02X683148Y1583667I0J-203D01*
G01Y1583045D01*
G03X683198Y1582913I200J0D01*
G02Y1580001I-1664J-1456D01*
G03X683148Y1579869I150J-132D01*
G01Y1577927D01*
G03X683198Y1577795I200J0D01*
G02Y1574883I-1664J-1456D01*
G03X683148Y1574751I150J-132D01*
G01Y1574129D01*
G02X682945Y1573926I-203J0D01*
G01X680125D01*
G02X679922Y1574129I0J203D01*
G01Y1574751D01*
G03X679872Y1574883I-200J0D01*
G02Y1577795I1664J1456D01*
G03X679922Y1577927I-150J132D01*
G01Y1579869D01*
G03X679872Y1580001I-200J0D01*
G02Y1582913I1664J1456D01*
G03X679922Y1583045I-150J132D01*
G01Y1583667D01*
G02X680125Y1583870I203J0D01*
G37*
G36*
G01X1130440D02*
X1133260D01*
G02X1133462Y1583667I-1J-203D01*
G01Y1583047D01*
G03X1133512Y1582915I200J0D01*
G02Y1579999I-1661J-1458D01*
G03X1133462Y1579867I150J-132D01*
G01Y1577929D01*
G03X1133512Y1577797I200J0D01*
G02Y1574881I-1661J-1458D01*
G03X1133462Y1574749I150J-132D01*
G01Y1574129D01*
G02X1133260Y1573926I-202J-1D01*
G01X1130440D01*
G02X1130238Y1574129I1J203D01*
G01Y1574749D01*
G03X1130188Y1574881I-200J0D01*
G02Y1577797I1661J1458D01*
G03X1130238Y1577929I-150J132D01*
G01Y1579867D01*
G03X1130188Y1579999I-200J0D01*
G02Y1582915I1661J1458D01*
G03X1130238Y1583047I-150J132D01*
G01Y1583667D01*
G02X1130440Y1583870I202J1D01*
G37*
G36*
G01X1147763D02*
X1150583D01*
G02X1150786Y1583667I0J-203D01*
G01Y1583045D01*
G03X1150836Y1582913I200J0D01*
G02Y1580001I-1664J-1456D01*
G03X1150786Y1579869I150J-132D01*
G01Y1577927D01*
G03X1150836Y1577795I200J0D01*
G02Y1574883I-1664J-1456D01*
G03X1150786Y1574751I150J-132D01*
G01Y1574129D01*
G02X1150583Y1573926I-203J0D01*
G01X1147763D01*
G02X1147560Y1574129I0J203D01*
G01Y1574751D01*
G03X1147510Y1574883I-200J0D01*
G02Y1577795I1664J1456D01*
G03X1147560Y1577927I-150J132D01*
G01Y1579869D01*
G03X1147510Y1580001I-200J0D01*
G02Y1582913I1664J1456D01*
G03X1147560Y1583045I-150J132D01*
G01Y1583667D01*
G02X1147763Y1583870I203J0D01*
G37*
G36*
G01X1165086D02*
X1167906D01*
G02X1168108Y1583667I-1J-203D01*
G01Y1583047D01*
G03X1168158Y1582915I200J0D01*
G02Y1579999I-1661J-1458D01*
G03X1168108Y1579867I150J-132D01*
G01Y1577929D01*
G03X1168158Y1577797I200J0D01*
G02Y1574881I-1661J-1458D01*
G03X1168108Y1574749I150J-132D01*
G01Y1574129D01*
G02X1167906Y1573926I-202J-1D01*
G01X1165086D01*
G02X1164884Y1574129I1J203D01*
G01Y1574749D01*
G03X1164834Y1574881I-200J0D01*
G02Y1577797I1661J1458D01*
G03X1164884Y1577929I-150J132D01*
G01Y1579867D01*
G03X1164834Y1579999I-200J0D01*
G02Y1582915I1661J1458D01*
G03X1164884Y1583047I-150J132D01*
G01Y1583667D01*
G02X1165086Y1583870I202J1D01*
G37*
G36*
G01X1182408D02*
X1185228D01*
G02X1185430Y1583667I-1J-203D01*
G01Y1583047D01*
G03X1185480Y1582915I200J0D01*
G02Y1579999I-1661J-1458D01*
G03X1185430Y1579867I150J-132D01*
G01Y1577929D01*
G03X1185480Y1577797I200J0D01*
G02Y1574881I-1661J-1458D01*
G03X1185430Y1574749I150J-132D01*
G01Y1574129D01*
G02X1185228Y1573926I-202J-1D01*
G01X1182408D01*
G02X1182206Y1574129I1J203D01*
G01Y1574749D01*
G03X1182156Y1574881I-200J0D01*
G02Y1577797I1661J1458D01*
G03X1182206Y1577929I-150J132D01*
G01Y1579867D01*
G03X1182156Y1579999I-200J0D01*
G02Y1582915I1661J1458D01*
G03X1182206Y1583047I-150J132D01*
G01Y1583667D01*
G02X1182408Y1583870I202J1D01*
G37*
G36*
G01X1303669D02*
X1306489D01*
G02X1306692Y1583667I0J-203D01*
G01Y1583045D01*
G03X1306742Y1582913I200J0D01*
G02Y1580001I-1664J-1456D01*
G03X1306692Y1579869I150J-132D01*
G01Y1577927D01*
G03X1306742Y1577795I200J0D01*
G02Y1574883I-1664J-1456D01*
G03X1306692Y1574751I150J-132D01*
G01Y1574129D01*
G02X1306489Y1573926I-203J0D01*
G01X1303669D01*
G02X1303466Y1574129I0J203D01*
G01Y1574751D01*
G03X1303416Y1574883I-200J0D01*
G02Y1577795I1664J1456D01*
G03X1303466Y1577927I-150J132D01*
G01Y1579869D01*
G03X1303416Y1580001I-200J0D01*
G02Y1582913I1664J1456D01*
G03X1303466Y1583045I-150J132D01*
G01Y1583667D01*
G02X1303669Y1583870I203J0D01*
G37*
G36*
G01X1320992D02*
X1323812D01*
G02X1324014Y1583667I-1J-203D01*
G01Y1583047D01*
G03X1324064Y1582915I200J0D01*
G02Y1579999I-1661J-1458D01*
G03X1324014Y1579867I150J-132D01*
G01Y1577929D01*
G03X1324064Y1577797I200J0D01*
G02Y1574881I-1661J-1458D01*
G03X1324014Y1574749I150J-132D01*
G01Y1574129D01*
G02X1323812Y1573926I-202J-1D01*
G01X1320992D01*
G02X1320790Y1574129I1J203D01*
G01Y1574749D01*
G03X1320740Y1574881I-200J0D01*
G02Y1577797I1661J1458D01*
G03X1320790Y1577929I-150J132D01*
G01Y1579867D01*
G03X1320740Y1579999I-200J0D01*
G02Y1582915I1661J1458D01*
G03X1320790Y1583047I-150J132D01*
G01Y1583667D01*
G02X1320992Y1583870I202J1D01*
G37*
G36*
G01X1338315D02*
X1341135D01*
G02X1341338Y1583667I0J-203D01*
G01Y1583045D01*
G03X1341388Y1582913I200J0D01*
G02Y1580001I-1664J-1456D01*
G03X1341338Y1579869I150J-132D01*
G01Y1577927D01*
G03X1341388Y1577795I200J0D01*
G02Y1574883I-1664J-1456D01*
G03X1341338Y1574751I150J-132D01*
G01Y1574129D01*
G02X1341135Y1573926I-203J0D01*
G01X1338315D01*
G02X1338112Y1574129I0J203D01*
G01Y1574751D01*
G03X1338062Y1574883I-200J0D01*
G02Y1577795I1664J1456D01*
G03X1338112Y1577927I-150J132D01*
G01Y1579869D01*
G03X1338062Y1580001I-200J0D01*
G02Y1582913I1664J1456D01*
G03X1338112Y1583045I-150J132D01*
G01Y1583667D01*
G02X1338315Y1583870I203J0D01*
G37*
G36*
G01X1355637D02*
X1358457D01*
G02X1358660Y1583667I0J-203D01*
G01Y1583045D01*
G03X1358710Y1582913I200J0D01*
G02Y1580001I-1664J-1456D01*
G03X1358660Y1579869I150J-132D01*
G01Y1577927D01*
G03X1358710Y1577795I200J0D01*
G02Y1574883I-1664J-1456D01*
G03X1358660Y1574751I150J-132D01*
G01Y1574129D01*
G02X1358457Y1573926I-203J0D01*
G01X1355637D01*
G02X1355434Y1574129I0J203D01*
G01Y1574751D01*
G03X1355384Y1574883I-200J0D01*
G02Y1577795I1664J1456D01*
G03X1355434Y1577927I-150J132D01*
G01Y1579869D01*
G03X1355384Y1580001I-200J0D01*
G02Y1582913I1664J1456D01*
G03X1355434Y1583045I-150J132D01*
G01Y1583667D01*
G02X1355637Y1583870I203J0D01*
G37*
G36*
G01X1476897D02*
X1479717D01*
G02X1479920Y1583667I0J-203D01*
G01Y1583045D01*
G03X1479970Y1582913I200J0D01*
G02Y1580001I-1664J-1456D01*
G03X1479920Y1579869I150J-132D01*
G01Y1577927D01*
G03X1479970Y1577795I200J0D01*
G02Y1574883I-1664J-1456D01*
G03X1479920Y1574751I150J-132D01*
G01Y1574129D01*
G02X1479717Y1573926I-203J0D01*
G01X1476897D01*
G02X1476694Y1574129I0J203D01*
G01Y1574751D01*
G03X1476644Y1574883I-200J0D01*
G02Y1577795I1664J1456D01*
G03X1476694Y1577927I-150J132D01*
G01Y1579869D01*
G03X1476644Y1580001I-200J0D01*
G02Y1582913I1664J1456D01*
G03X1476694Y1583045I-150J132D01*
G01Y1583667D01*
G02X1476897Y1583870I203J0D01*
G37*
G36*
G01X1650125D02*
X1652945D01*
G02X1653148Y1583667I0J-203D01*
G01Y1583045D01*
G03X1653198Y1582913I200J0D01*
G02Y1580001I-1664J-1456D01*
G03X1653148Y1579869I150J-132D01*
G01Y1577927D01*
G03X1653198Y1577795I200J0D01*
G02Y1574883I-1664J-1456D01*
G03X1653148Y1574751I150J-132D01*
G01Y1574129D01*
G02X1652945Y1573926I-203J0D01*
G01X1650125D01*
G02X1649922Y1574129I0J203D01*
G01Y1574751D01*
G03X1649872Y1574883I-200J0D01*
G02Y1577795I1664J1456D01*
G03X1649922Y1577927I-150J132D01*
G01Y1579869D01*
G03X1649872Y1580001I-200J0D01*
G02Y1582913I1664J1456D01*
G03X1649922Y1583045I-150J132D01*
G01Y1583667D01*
G02X1650125Y1583870I203J0D01*
G37*
G36*
G01X1667448D02*
X1670268D01*
G02X1670470Y1583667I-1J-203D01*
G01Y1583047D01*
G03X1670520Y1582915I200J0D01*
G02Y1579999I-1661J-1458D01*
G03X1670470Y1579867I150J-132D01*
G01Y1577929D01*
G03X1670520Y1577797I200J0D01*
G02Y1574881I-1661J-1458D01*
G03X1670470Y1574749I150J-132D01*
G01Y1574129D01*
G02X1670268Y1573926I-202J-1D01*
G01X1667448D01*
G02X1667246Y1574129I1J203D01*
G01Y1574749D01*
G03X1667196Y1574881I-200J0D01*
G02Y1577797I1661J1458D01*
G03X1667246Y1577929I-150J132D01*
G01Y1579867D01*
G03X1667196Y1579999I-200J0D01*
G02Y1582915I1661J1458D01*
G03X1667246Y1583047I-150J132D01*
G01Y1583667D01*
G02X1667448Y1583870I202J1D01*
G37*
G36*
G01X1684771D02*
X1687591D01*
G02X1687794Y1583667I0J-203D01*
G01Y1583045D01*
G03X1687844Y1582913I200J0D01*
G02Y1580001I-1664J-1456D01*
G03X1687794Y1579869I150J-132D01*
G01Y1577927D01*
G03X1687844Y1577795I200J0D01*
G02Y1574883I-1664J-1456D01*
G03X1687794Y1574751I150J-132D01*
G01Y1574129D01*
G02X1687591Y1573926I-203J0D01*
G01X1684771D01*
G02X1684568Y1574129I0J203D01*
G01Y1574751D01*
G03X1684518Y1574883I-200J0D01*
G02Y1577795I1664J1456D01*
G03X1684568Y1577927I-150J132D01*
G01Y1579869D01*
G03X1684518Y1580001I-200J0D01*
G02Y1582913I1664J1456D01*
G03X1684568Y1583045I-150J132D01*
G01Y1583667D01*
G02X1684771Y1583870I203J0D01*
G37*
G36*
G01X1702093D02*
X1704913D01*
G02X1705116Y1583667I0J-203D01*
G01Y1583045D01*
G03X1705166Y1582913I200J0D01*
G02Y1580001I-1664J-1456D01*
G03X1705116Y1579869I150J-132D01*
G01Y1577927D01*
G03X1705166Y1577795I200J0D01*
G02Y1574883I-1664J-1456D01*
G03X1705116Y1574751I150J-132D01*
G01Y1574129D01*
G02X1704913Y1573926I-203J0D01*
G01X1702093D01*
G02X1701890Y1574129I0J203D01*
G01Y1574751D01*
G03X1701840Y1574883I-200J0D01*
G02Y1577795I1664J1456D01*
G03X1701890Y1577927I-150J132D01*
G01Y1579869D01*
G03X1701840Y1580001I-200J0D01*
G02Y1582913I1664J1456D01*
G03X1701890Y1583045I-150J132D01*
G01Y1583667D01*
G02X1702093Y1583870I203J0D01*
G37*
G36*
G01X134456Y1588200D02*
X137276D01*
G02X137478Y1587998I0J-202D01*
G01Y1587378D01*
G03X137528Y1587246I200J0D01*
G02Y1584330I-1661J-1458D01*
G03X137478Y1584198I150J-132D01*
G01Y1582260D01*
G03X137528Y1582128I200J0D01*
G02Y1579212I-1661J-1458D01*
G03X137478Y1579080I150J-132D01*
G01Y1578460D01*
G02X137276Y1578258I-202J0D01*
G01X134456D01*
G02X134254Y1578460I0J202D01*
G01Y1579080D01*
G03X134204Y1579212I-200J0D01*
G02Y1582128I1661J1458D01*
G03X134254Y1582260I-150J132D01*
G01Y1584198D01*
G03X134204Y1584330I-200J0D01*
G02Y1587246I1661J1458D01*
G03X134254Y1587378I-150J132D01*
G01Y1587998D01*
G02X134456Y1588200I202J0D01*
G37*
G36*
G01X169102D02*
X171922D01*
G02X172124Y1587998I0J-202D01*
G01Y1587378D01*
G03X172174Y1587246I200J0D01*
G02Y1584330I-1661J-1458D01*
G03X172124Y1584198I150J-132D01*
G01Y1582260D01*
G03X172174Y1582128I200J0D01*
G02Y1579212I-1661J-1458D01*
G03X172124Y1579080I150J-132D01*
G01Y1578460D01*
G02X171922Y1578258I-202J0D01*
G01X169102D01*
G02X168900Y1578460I0J202D01*
G01Y1579080D01*
G03X168850Y1579212I-200J0D01*
G02Y1582128I1661J1458D01*
G03X168900Y1582260I-150J132D01*
G01Y1584198D01*
G03X168850Y1584330I-200J0D01*
G02Y1587246I1661J1458D01*
G03X168900Y1587378I-150J132D01*
G01Y1587998D01*
G02X169102Y1588200I202J0D01*
G37*
G36*
G01X307684D02*
X310504D01*
G02X310706Y1587998I0J-202D01*
G01Y1587378D01*
G03X310756Y1587246I200J0D01*
G02Y1584330I-1661J-1458D01*
G03X310706Y1584198I150J-132D01*
G01Y1582260D01*
G03X310756Y1582128I200J0D01*
G02Y1579212I-1661J-1458D01*
G03X310706Y1579080I150J-132D01*
G01Y1578460D01*
G02X310504Y1578258I-202J0D01*
G01X307684D01*
G02X307482Y1578460I0J202D01*
G01Y1579080D01*
G03X307432Y1579212I-200J0D01*
G02Y1582128I1661J1458D01*
G03X307482Y1582260I-150J132D01*
G01Y1584198D01*
G03X307432Y1584330I-200J0D01*
G02Y1587246I1661J1458D01*
G03X307482Y1587378I-150J132D01*
G01Y1587998D01*
G02X307684Y1588200I202J0D01*
G37*
G36*
G01X342330D02*
X345150D01*
G02X345352Y1587998I0J-202D01*
G01Y1587378D01*
G03X345402Y1587246I200J0D01*
G02Y1584330I-1661J-1458D01*
G03X345352Y1584198I150J-132D01*
G01Y1582260D01*
G03X345402Y1582128I200J0D01*
G02Y1579212I-1661J-1458D01*
G03X345352Y1579080I150J-132D01*
G01Y1578460D01*
G02X345150Y1578258I-202J0D01*
G01X342330D01*
G02X342128Y1578460I0J202D01*
G01Y1579080D01*
G03X342078Y1579212I-200J0D01*
G02Y1582128I1661J1458D01*
G03X342128Y1582260I-150J132D01*
G01Y1584198D01*
G03X342078Y1584330I-200J0D01*
G02Y1587246I1661J1458D01*
G03X342128Y1587378I-150J132D01*
G01Y1587998D01*
G02X342330Y1588200I202J0D01*
G37*
G36*
G01X636818D02*
X639638D01*
G02X639840Y1587998I0J-202D01*
G01Y1587378D01*
G03X639890Y1587246I200J0D01*
G02Y1584330I-1661J-1458D01*
G03X639840Y1584198I150J-132D01*
G01Y1582260D01*
G03X639890Y1582128I200J0D01*
G02Y1579212I-1661J-1458D01*
G03X639840Y1579080I150J-132D01*
G01Y1578460D01*
G02X639638Y1578258I-202J0D01*
G01X636818D01*
G02X636616Y1578460I0J202D01*
G01Y1579080D01*
G03X636566Y1579212I-200J0D01*
G02Y1582128I1661J1458D01*
G03X636616Y1582260I-150J132D01*
G01Y1584198D01*
G03X636566Y1584330I-200J0D01*
G02Y1587246I1661J1458D01*
G03X636616Y1587378I-150J132D01*
G01Y1587998D01*
G02X636818Y1588200I202J0D01*
G37*
G36*
G01X671464D02*
X674284D01*
G02X674486Y1587998I0J-202D01*
G01Y1587378D01*
G03X674536Y1587246I200J0D01*
G02Y1584330I-1661J-1458D01*
G03X674486Y1584198I150J-132D01*
G01Y1582260D01*
G03X674536Y1582128I200J0D01*
G02Y1579212I-1661J-1458D01*
G03X674486Y1579080I150J-132D01*
G01Y1578460D01*
G02X674284Y1578258I-202J0D01*
G01X671464D01*
G02X671262Y1578460I0J202D01*
G01Y1579080D01*
G03X671212Y1579212I-200J0D01*
G02Y1582128I1661J1458D01*
G03X671262Y1582260I-150J132D01*
G01Y1584198D01*
G03X671212Y1584330I-200J0D01*
G02Y1587246I1661J1458D01*
G03X671262Y1587378I-150J132D01*
G01Y1587998D01*
G02X671464Y1588200I202J0D01*
G37*
G36*
G01X1156424D02*
X1159244D01*
G02X1159446Y1587998I0J-202D01*
G01Y1587378D01*
G03X1159496Y1587246I200J0D01*
G02Y1584330I-1661J-1458D01*
G03X1159446Y1584198I150J-132D01*
G01Y1582260D01*
G03X1159496Y1582128I200J0D01*
G02Y1579212I-1661J-1458D01*
G03X1159446Y1579080I150J-132D01*
G01Y1578460D01*
G02X1159244Y1578258I-202J0D01*
G01X1156424D01*
G02X1156222Y1578460I0J202D01*
G01Y1579080D01*
G03X1156172Y1579212I-200J0D01*
G02Y1582128I1661J1458D01*
G03X1156222Y1582260I-150J132D01*
G01Y1584198D01*
G03X1156172Y1584330I-200J0D01*
G02Y1587246I1661J1458D01*
G03X1156222Y1587378I-150J132D01*
G01Y1587998D01*
G02X1156424Y1588200I202J0D01*
G37*
G36*
G01X1191070D02*
X1193890D01*
G02X1194092Y1587998I0J-202D01*
G01Y1587378D01*
G03X1194142Y1587246I200J0D01*
G02Y1584330I-1661J-1458D01*
G03X1194092Y1584198I150J-132D01*
G01Y1582260D01*
G03X1194142Y1582128I200J0D01*
G02Y1579212I-1661J-1458D01*
G03X1194092Y1579080I150J-132D01*
G01Y1578460D01*
G02X1193890Y1578258I-202J0D01*
G01X1191070D01*
G02X1190868Y1578460I0J202D01*
G01Y1579080D01*
G03X1190818Y1579212I-200J0D01*
G02Y1582128I1661J1458D01*
G03X1190868Y1582260I-150J132D01*
G01Y1584198D01*
G03X1190818Y1584330I-200J0D01*
G02Y1587246I1661J1458D01*
G03X1190868Y1587378I-150J132D01*
G01Y1587998D01*
G02X1191070Y1588200I202J0D01*
G37*
G36*
G01X1312330D02*
X1315150D01*
G02X1315352Y1587998I0J-202D01*
G01Y1587378D01*
G03X1315402Y1587246I200J0D01*
G02Y1584330I-1661J-1458D01*
G03X1315352Y1584198I150J-132D01*
G01Y1582260D01*
G03X1315402Y1582128I200J0D01*
G02Y1579212I-1661J-1458D01*
G03X1315352Y1579080I150J-132D01*
G01Y1578460D01*
G02X1315150Y1578258I-202J0D01*
G01X1312330D01*
G02X1312128Y1578460I0J202D01*
G01Y1579080D01*
G03X1312078Y1579212I-200J0D01*
G02Y1582128I1661J1458D01*
G03X1312128Y1582260I-150J132D01*
G01Y1584198D01*
G03X1312078Y1584330I-200J0D01*
G02Y1587246I1661J1458D01*
G03X1312128Y1587378I-150J132D01*
G01Y1587998D01*
G02X1312330Y1588200I202J0D01*
G37*
G36*
G01X1346976D02*
X1349796D01*
G02X1349998Y1587998I0J-202D01*
G01Y1587378D01*
G03X1350048Y1587246I200J0D01*
G02Y1584330I-1661J-1458D01*
G03X1349998Y1584198I150J-132D01*
G01Y1582260D01*
G03X1350048Y1582128I200J0D01*
G02Y1579212I-1661J-1458D01*
G03X1349998Y1579080I150J-132D01*
G01Y1578460D01*
G02X1349796Y1578258I-202J0D01*
G01X1346976D01*
G02X1346774Y1578460I0J202D01*
G01Y1579080D01*
G03X1346724Y1579212I-200J0D01*
G02Y1582128I1661J1458D01*
G03X1346774Y1582260I-150J132D01*
G01Y1584198D01*
G03X1346724Y1584330I-200J0D01*
G02Y1587246I1661J1458D01*
G03X1346774Y1587378I-150J132D01*
G01Y1587998D01*
G02X1346976Y1588200I202J0D01*
G37*
G36*
G01X1658786D02*
X1661606D01*
G02X1661808Y1587998I0J-202D01*
G01Y1587378D01*
G03X1661858Y1587246I200J0D01*
G02Y1584330I-1661J-1458D01*
G03X1661808Y1584198I150J-132D01*
G01Y1582260D01*
G03X1661858Y1582128I200J0D01*
G02Y1579212I-1661J-1458D01*
G03X1661808Y1579080I150J-132D01*
G01Y1578460D01*
G02X1661606Y1578258I-202J0D01*
G01X1658786D01*
G02X1658584Y1578460I0J202D01*
G01Y1579080D01*
G03X1658534Y1579212I-200J0D01*
G02Y1582128I1661J1458D01*
G03X1658584Y1582260I-150J132D01*
G01Y1584198D01*
G03X1658534Y1584330I-200J0D01*
G02Y1587246I1661J1458D01*
G03X1658584Y1587378I-150J132D01*
G01Y1587998D01*
G02X1658786Y1588200I202J0D01*
G37*
G36*
G01X1693432D02*
X1696252D01*
G02X1696454Y1587998I0J-202D01*
G01Y1587378D01*
G03X1696504Y1587246I200J0D01*
G02Y1584330I-1661J-1458D01*
G03X1696454Y1584198I150J-132D01*
G01Y1582260D01*
G03X1696504Y1582128I200J0D01*
G02Y1579212I-1661J-1458D01*
G03X1696454Y1579080I150J-132D01*
G01Y1578460D01*
G02X1696252Y1578258I-202J0D01*
G01X1693432D01*
G02X1693230Y1578460I0J202D01*
G01Y1579080D01*
G03X1693180Y1579212I-200J0D01*
G02Y1582128I1661J1458D01*
G03X1693230Y1582260I-150J132D01*
G01Y1584198D01*
G03X1693180Y1584330I-200J0D01*
G02Y1587246I1661J1458D01*
G03X1693230Y1587378I-150J132D01*
G01Y1587998D01*
G02X1693432Y1588200I202J0D01*
G37*
G36*
G01X117133D02*
X119953D01*
G02X120156Y1587998I1J-202D01*
G01Y1587376D01*
G03X120206Y1587244I200J0D01*
G02Y1584332I-1664J-1456D01*
G03X120156Y1584200I150J-132D01*
G01Y1582258D01*
G03X120206Y1582126I200J0D01*
G02Y1579214I-1664J-1456D01*
G03X120156Y1579082I150J-132D01*
G01Y1578460D01*
G02X119953Y1578258I-203J1D01*
G01X117133D01*
G02X116930Y1578460I-1J202D01*
G01Y1579082D01*
G03X116880Y1579214I-200J0D01*
G02Y1582126I1664J1456D01*
G03X116930Y1582258I-150J132D01*
G01Y1584200D01*
G03X116880Y1584332I-200J0D01*
G02Y1587244I1664J1456D01*
G03X116930Y1587376I-150J132D01*
G01Y1587998D01*
G02X117133Y1588200I203J-1D01*
G37*
G36*
G01X151779D02*
X154599D01*
G02X154802Y1587998I1J-202D01*
G01Y1587376D01*
G03X154852Y1587244I200J0D01*
G02Y1584332I-1664J-1456D01*
G03X154802Y1584200I150J-132D01*
G01Y1582258D01*
G03X154852Y1582126I200J0D01*
G02Y1579214I-1664J-1456D01*
G03X154802Y1579082I150J-132D01*
G01Y1578460D01*
G02X154599Y1578258I-203J1D01*
G01X151779D01*
G02X151576Y1578460I-1J202D01*
G01Y1579082D01*
G03X151526Y1579214I-200J0D01*
G02Y1582126I1664J1456D01*
G03X151576Y1582258I-150J132D01*
G01Y1584200D01*
G03X151526Y1584332I-200J0D01*
G02Y1587244I1664J1456D01*
G03X151576Y1587376I-150J132D01*
G01Y1587998D01*
G02X151779Y1588200I203J-1D01*
G37*
G36*
G01X290361D02*
X293181D01*
G02X293384Y1587998I1J-202D01*
G01Y1587376D01*
G03X293434Y1587244I200J0D01*
G02Y1584332I-1664J-1456D01*
G03X293384Y1584200I150J-132D01*
G01Y1582258D01*
G03X293434Y1582126I200J0D01*
G02Y1579214I-1664J-1456D01*
G03X293384Y1579082I150J-132D01*
G01Y1578460D01*
G02X293181Y1578258I-203J1D01*
G01X290361D01*
G02X290158Y1578460I-1J202D01*
G01Y1579082D01*
G03X290108Y1579214I-200J0D01*
G02Y1582126I1664J1456D01*
G03X290158Y1582258I-150J132D01*
G01Y1584200D01*
G03X290108Y1584332I-200J0D01*
G02Y1587244I1664J1456D01*
G03X290158Y1587376I-150J132D01*
G01Y1587998D01*
G02X290361Y1588200I203J-1D01*
G37*
G36*
G01X325007D02*
X327827D01*
G02X328030Y1587998I1J-202D01*
G01Y1587376D01*
G03X328080Y1587244I200J0D01*
G02Y1584332I-1664J-1456D01*
G03X328030Y1584200I150J-132D01*
G01Y1582258D01*
G03X328080Y1582126I200J0D01*
G02Y1579214I-1664J-1456D01*
G03X328030Y1579082I150J-132D01*
G01Y1578460D01*
G02X327827Y1578258I-203J1D01*
G01X325007D01*
G02X324804Y1578460I-1J202D01*
G01Y1579082D01*
G03X324754Y1579214I-200J0D01*
G02Y1582126I1664J1456D01*
G03X324804Y1582258I-150J132D01*
G01Y1584200D01*
G03X324754Y1584332I-200J0D01*
G02Y1587244I1664J1456D01*
G03X324804Y1587376I-150J132D01*
G01Y1587998D01*
G02X325007Y1588200I203J-1D01*
G37*
G36*
G01X515559D02*
X518379D01*
G02X518582Y1587998I1J-202D01*
G01Y1587376D01*
G03X518632Y1587244I200J0D01*
G02Y1584332I-1664J-1456D01*
G03X518582Y1584200I150J-132D01*
G01Y1582258D01*
G03X518632Y1582126I200J0D01*
G02Y1579214I-1664J-1456D01*
G03X518582Y1579082I150J-132D01*
G01Y1578460D01*
G02X518379Y1578258I-203J1D01*
G01X515559D01*
G02X515356Y1578460I-1J202D01*
G01Y1579082D01*
G03X515306Y1579214I-200J0D01*
G02Y1582126I1664J1456D01*
G03X515356Y1582258I-150J132D01*
G01Y1584200D01*
G03X515306Y1584332I-200J0D01*
G02Y1587244I1664J1456D01*
G03X515356Y1587376I-150J132D01*
G01Y1587998D01*
G02X515559Y1588200I203J-1D01*
G37*
G36*
G01X654141D02*
X656961D01*
G02X657164Y1587998I1J-202D01*
G01Y1587376D01*
G03X657214Y1587244I200J0D01*
G02Y1584332I-1664J-1456D01*
G03X657164Y1584200I150J-132D01*
G01Y1582258D01*
G03X657214Y1582126I200J0D01*
G02Y1579214I-1664J-1456D01*
G03X657164Y1579082I150J-132D01*
G01Y1578460D01*
G02X656961Y1578258I-203J1D01*
G01X654141D01*
G02X653938Y1578460I-1J202D01*
G01Y1579082D01*
G03X653888Y1579214I-200J0D01*
G02Y1582126I1664J1456D01*
G03X653938Y1582258I-150J132D01*
G01Y1584200D01*
G03X653888Y1584332I-200J0D01*
G02Y1587244I1664J1456D01*
G03X653938Y1587376I-150J132D01*
G01Y1587998D01*
G02X654141Y1588200I203J-1D01*
G37*
G36*
G01X688787D02*
X691607D01*
G02X691810Y1587998I1J-202D01*
G01Y1587376D01*
G03X691860Y1587244I200J0D01*
G02Y1584332I-1664J-1456D01*
G03X691810Y1584200I150J-132D01*
G01Y1582258D01*
G03X691860Y1582126I200J0D01*
G02Y1579214I-1664J-1456D01*
G03X691810Y1579082I150J-132D01*
G01Y1578460D01*
G02X691607Y1578258I-203J1D01*
G01X688787D01*
G02X688584Y1578460I-1J202D01*
G01Y1579082D01*
G03X688534Y1579214I-200J0D01*
G02Y1582126I1664J1456D01*
G03X688584Y1582258I-150J132D01*
G01Y1584200D01*
G03X688534Y1584332I-200J0D01*
G02Y1587244I1664J1456D01*
G03X688584Y1587376I-150J132D01*
G01Y1587998D01*
G02X688787Y1588200I203J-1D01*
G37*
G36*
G01X1139101D02*
X1141921D01*
G02X1142124Y1587998I1J-202D01*
G01Y1587376D01*
G03X1142174Y1587244I200J0D01*
G02Y1584332I-1664J-1456D01*
G03X1142124Y1584200I150J-132D01*
G01Y1582258D01*
G03X1142174Y1582126I200J0D01*
G02Y1579214I-1664J-1456D01*
G03X1142124Y1579082I150J-132D01*
G01Y1578460D01*
G02X1141921Y1578258I-203J1D01*
G01X1139101D01*
G02X1138898Y1578460I-1J202D01*
G01Y1579082D01*
G03X1138848Y1579214I-200J0D01*
G02Y1582126I1664J1456D01*
G03X1138898Y1582258I-150J132D01*
G01Y1584200D01*
G03X1138848Y1584332I-200J0D01*
G02Y1587244I1664J1456D01*
G03X1138898Y1587376I-150J132D01*
G01Y1587998D01*
G02X1139101Y1588200I203J-1D01*
G37*
G36*
G01X1173747D02*
X1176567D01*
G02X1176770Y1587998I1J-202D01*
G01Y1587376D01*
G03X1176820Y1587244I200J0D01*
G02Y1584332I-1664J-1456D01*
G03X1176770Y1584200I150J-132D01*
G01Y1582258D01*
G03X1176820Y1582126I200J0D01*
G02Y1579214I-1664J-1456D01*
G03X1176770Y1579082I150J-132D01*
G01Y1578460D01*
G02X1176567Y1578258I-203J1D01*
G01X1173747D01*
G02X1173544Y1578460I-1J202D01*
G01Y1579082D01*
G03X1173494Y1579214I-200J0D01*
G02Y1582126I1664J1456D01*
G03X1173544Y1582258I-150J132D01*
G01Y1584200D01*
G03X1173494Y1584332I-200J0D01*
G02Y1587244I1664J1456D01*
G03X1173544Y1587376I-150J132D01*
G01Y1587998D01*
G02X1173747Y1588200I203J-1D01*
G37*
G36*
G01X1329653D02*
X1332473D01*
G02X1332676Y1587998I1J-202D01*
G01Y1587376D01*
G03X1332726Y1587244I200J0D01*
G02Y1584332I-1664J-1456D01*
G03X1332676Y1584200I150J-132D01*
G01Y1582258D01*
G03X1332726Y1582126I200J0D01*
G02Y1579214I-1664J-1456D01*
G03X1332676Y1579082I150J-132D01*
G01Y1578460D01*
G02X1332473Y1578258I-203J1D01*
G01X1329653D01*
G02X1329450Y1578460I-1J202D01*
G01Y1579082D01*
G03X1329400Y1579214I-200J0D01*
G02Y1582126I1664J1456D01*
G03X1329450Y1582258I-150J132D01*
G01Y1584200D01*
G03X1329400Y1584332I-200J0D01*
G02Y1587244I1664J1456D01*
G03X1329450Y1587376I-150J132D01*
G01Y1587998D01*
G02X1329653Y1588200I203J-1D01*
G37*
G36*
G01X1364299D02*
X1367119D01*
G02X1367322Y1587998I1J-202D01*
G01Y1587376D01*
G03X1367372Y1587244I200J0D01*
G02Y1584332I-1664J-1456D01*
G03X1367322Y1584200I150J-132D01*
G01Y1582258D01*
G03X1367372Y1582126I200J0D01*
G02Y1579214I-1664J-1456D01*
G03X1367322Y1579082I150J-132D01*
G01Y1578460D01*
G02X1367119Y1578258I-203J1D01*
G01X1364299D01*
G02X1364096Y1578460I-1J202D01*
G01Y1579082D01*
G03X1364046Y1579214I-200J0D01*
G02Y1582126I1664J1456D01*
G03X1364096Y1582258I-150J132D01*
G01Y1584200D01*
G03X1364046Y1584332I-200J0D01*
G02Y1587244I1664J1456D01*
G03X1364096Y1587376I-150J132D01*
G01Y1587998D01*
G02X1364299Y1588200I203J-1D01*
G37*
G36*
G01X1676109D02*
X1678929D01*
G02X1679132Y1587998I1J-202D01*
G01Y1587376D01*
G03X1679182Y1587244I200J0D01*
G02Y1584332I-1664J-1456D01*
G03X1679132Y1584200I150J-132D01*
G01Y1582258D01*
G03X1679182Y1582126I200J0D01*
G02Y1579214I-1664J-1456D01*
G03X1679132Y1579082I150J-132D01*
G01Y1578460D01*
G02X1678929Y1578258I-203J1D01*
G01X1676109D01*
G02X1675906Y1578460I-1J202D01*
G01Y1579082D01*
G03X1675856Y1579214I-200J0D01*
G02Y1582126I1664J1456D01*
G03X1675906Y1582258I-150J132D01*
G01Y1584200D01*
G03X1675856Y1584332I-200J0D01*
G02Y1587244I1664J1456D01*
G03X1675906Y1587376I-150J132D01*
G01Y1587998D01*
G02X1676109Y1588200I203J-1D01*
G37*
G36*
G01X1710755D02*
X1713575D01*
G02X1713778Y1587998I1J-202D01*
G01Y1587376D01*
G03X1713828Y1587244I200J0D01*
G02Y1584332I-1664J-1456D01*
G03X1713778Y1584200I150J-132D01*
G01Y1582258D01*
G03X1713828Y1582126I200J0D01*
G02Y1579214I-1664J-1456D01*
G03X1713778Y1579082I150J-132D01*
G01Y1578460D01*
G02X1713575Y1578258I-203J1D01*
G01X1710755D01*
G02X1710552Y1578460I-1J202D01*
G01Y1579082D01*
G03X1710502Y1579214I-200J0D01*
G02Y1582126I1664J1456D01*
G03X1710552Y1582258I-150J132D01*
G01Y1584200D01*
G03X1710502Y1584332I-200J0D01*
G02Y1587244I1664J1456D01*
G03X1710552Y1587376I-150J132D01*
G01Y1587998D01*
G02X1710755Y1588200I203J-1D01*
G37*
G36*
G01X108472Y1599224D02*
X111292D01*
G02X111494Y1599021I-1J-203D01*
G01Y1598401D01*
G03X111544Y1598269I200J0D01*
G02Y1595353I-1661J-1458D01*
G03X111494Y1595221I150J-132D01*
G01Y1593283D01*
G03X111544Y1593151I200J0D01*
G02Y1590235I-1661J-1458D01*
G03X111494Y1590103I150J-132D01*
G01Y1589483D01*
G02X111292Y1589280I-202J-1D01*
G01X108472D01*
G02X108270Y1589483I1J203D01*
G01Y1590103D01*
G03X108220Y1590235I-200J0D01*
G02Y1593151I1661J1458D01*
G03X108270Y1593283I-150J132D01*
G01Y1595221D01*
G03X108220Y1595353I-200J0D01*
G02Y1598269I1661J1458D01*
G03X108270Y1598401I-150J132D01*
G01Y1599021D01*
G02X108472Y1599224I202J1D01*
G37*
G36*
G01X125795D02*
X128615D01*
G02X128818Y1599021I0J-203D01*
G01Y1598399D01*
G03X128868Y1598267I200J0D01*
G02Y1595355I-1664J-1456D01*
G03X128818Y1595223I150J-132D01*
G01Y1593281D01*
G03X128868Y1593149I200J0D01*
G02Y1590237I-1664J-1456D01*
G03X128818Y1590105I150J-132D01*
G01Y1589483D01*
G02X128615Y1589280I-203J0D01*
G01X125795D01*
G02X125592Y1589483I0J203D01*
G01Y1590105D01*
G03X125542Y1590237I-200J0D01*
G02Y1593149I1664J1456D01*
G03X125592Y1593281I-150J132D01*
G01Y1595223D01*
G03X125542Y1595355I-200J0D01*
G02Y1598267I1664J1456D01*
G03X125592Y1598399I-150J132D01*
G01Y1599021D01*
G02X125795Y1599224I203J0D01*
G37*
G36*
G01X143118D02*
X145938D01*
G02X146140Y1599021I-1J-203D01*
G01Y1598401D01*
G03X146190Y1598269I200J0D01*
G02Y1595353I-1661J-1458D01*
G03X146140Y1595221I150J-132D01*
G01Y1593283D01*
G03X146190Y1593151I200J0D01*
G02Y1590235I-1661J-1458D01*
G03X146140Y1590103I150J-132D01*
G01Y1589483D01*
G02X145938Y1589280I-202J-1D01*
G01X143118D01*
G02X142916Y1589483I1J203D01*
G01Y1590103D01*
G03X142866Y1590235I-200J0D01*
G02Y1593151I1661J1458D01*
G03X142916Y1593283I-150J132D01*
G01Y1595221D01*
G03X142866Y1595353I-200J0D01*
G02Y1598269I1661J1458D01*
G03X142916Y1598401I-150J132D01*
G01Y1599021D01*
G02X143118Y1599224I202J1D01*
G37*
G36*
G01X160440D02*
X163260D01*
G02X163462Y1599021I-1J-203D01*
G01Y1598401D01*
G03X163512Y1598269I200J0D01*
G02Y1595353I-1661J-1458D01*
G03X163462Y1595221I150J-132D01*
G01Y1593283D01*
G03X163512Y1593151I200J0D01*
G02Y1590235I-1661J-1458D01*
G03X163462Y1590103I150J-132D01*
G01Y1589483D01*
G02X163260Y1589280I-202J-1D01*
G01X160440D01*
G02X160238Y1589483I1J203D01*
G01Y1590103D01*
G03X160188Y1590235I-200J0D01*
G02Y1593151I1661J1458D01*
G03X160238Y1593283I-150J132D01*
G01Y1595221D01*
G03X160188Y1595353I-200J0D01*
G02Y1598269I1661J1458D01*
G03X160238Y1598401I-150J132D01*
G01Y1599021D01*
G02X160440Y1599224I202J1D01*
G37*
G36*
G01X281700D02*
X284520D01*
G02X284722Y1599021I-1J-203D01*
G01Y1598401D01*
G03X284772Y1598269I200J0D01*
G02Y1595353I-1661J-1458D01*
G03X284722Y1595221I150J-132D01*
G01Y1593283D01*
G03X284772Y1593151I200J0D01*
G02Y1590235I-1661J-1458D01*
G03X284722Y1590103I150J-132D01*
G01Y1589483D01*
G02X284520Y1589280I-202J-1D01*
G01X281700D01*
G02X281498Y1589483I1J203D01*
G01Y1590103D01*
G03X281448Y1590235I-200J0D01*
G02Y1593151I1661J1458D01*
G03X281498Y1593283I-150J132D01*
G01Y1595221D01*
G03X281448Y1595353I-200J0D01*
G02Y1598269I1661J1458D01*
G03X281498Y1598401I-150J132D01*
G01Y1599021D01*
G02X281700Y1599224I202J1D01*
G37*
G36*
G01X299023D02*
X301843D01*
G02X302046Y1599021I0J-203D01*
G01Y1598399D01*
G03X302096Y1598267I200J0D01*
G02Y1595355I-1664J-1456D01*
G03X302046Y1595223I150J-132D01*
G01Y1593281D01*
G03X302096Y1593149I200J0D01*
G02Y1590237I-1664J-1456D01*
G03X302046Y1590105I150J-132D01*
G01Y1589483D01*
G02X301843Y1589280I-203J0D01*
G01X299023D01*
G02X298820Y1589483I0J203D01*
G01Y1590105D01*
G03X298770Y1590237I-200J0D01*
G02Y1593149I1664J1456D01*
G03X298820Y1593281I-150J132D01*
G01Y1595223D01*
G03X298770Y1595355I-200J0D01*
G02Y1598267I1664J1456D01*
G03X298820Y1598399I-150J132D01*
G01Y1599021D01*
G02X299023Y1599224I203J0D01*
G37*
G36*
G01X316346D02*
X319166D01*
G02X319368Y1599021I-1J-203D01*
G01Y1598401D01*
G03X319418Y1598269I200J0D01*
G02Y1595353I-1661J-1458D01*
G03X319368Y1595221I150J-132D01*
G01Y1593283D01*
G03X319418Y1593151I200J0D01*
G02Y1590235I-1661J-1458D01*
G03X319368Y1590103I150J-132D01*
G01Y1589483D01*
G02X319166Y1589280I-202J-1D01*
G01X316346D01*
G02X316144Y1589483I1J203D01*
G01Y1590103D01*
G03X316094Y1590235I-200J0D01*
G02Y1593151I1661J1458D01*
G03X316144Y1593283I-150J132D01*
G01Y1595221D01*
G03X316094Y1595353I-200J0D01*
G02Y1598269I1661J1458D01*
G03X316144Y1598401I-150J132D01*
G01Y1599021D01*
G02X316346Y1599224I202J1D01*
G37*
G36*
G01X333668D02*
X336488D01*
G02X336690Y1599021I-1J-203D01*
G01Y1598401D01*
G03X336740Y1598269I200J0D01*
G02Y1595353I-1661J-1458D01*
G03X336690Y1595221I150J-132D01*
G01Y1593283D01*
G03X336740Y1593151I200J0D01*
G02Y1590235I-1661J-1458D01*
G03X336690Y1590103I150J-132D01*
G01Y1589483D01*
G02X336488Y1589280I-202J-1D01*
G01X333668D01*
G02X333466Y1589483I1J203D01*
G01Y1590103D01*
G03X333416Y1590235I-200J0D01*
G02Y1593151I1661J1458D01*
G03X333466Y1593283I-150J132D01*
G01Y1595221D01*
G03X333416Y1595353I-200J0D01*
G02Y1598269I1661J1458D01*
G03X333466Y1598401I-150J132D01*
G01Y1599021D01*
G02X333668Y1599224I202J1D01*
G37*
G36*
G01X628157D02*
X630977D01*
G02X631180Y1599021I0J-203D01*
G01Y1598399D01*
G03X631230Y1598267I200J0D01*
G02Y1595355I-1664J-1456D01*
G03X631180Y1595223I150J-132D01*
G01Y1593281D01*
G03X631230Y1593149I200J0D01*
G02Y1590237I-1664J-1456D01*
G03X631180Y1590105I150J-132D01*
G01Y1589483D01*
G02X630977Y1589280I-203J0D01*
G01X628157D01*
G02X627954Y1589483I0J203D01*
G01Y1590105D01*
G03X627904Y1590237I-200J0D01*
G02Y1593149I1664J1456D01*
G03X627954Y1593281I-150J132D01*
G01Y1595223D01*
G03X627904Y1595355I-200J0D01*
G02Y1598267I1664J1456D01*
G03X627954Y1598399I-150J132D01*
G01Y1599021D01*
G02X628157Y1599224I203J0D01*
G37*
G36*
G01X645480D02*
X648300D01*
G02X648502Y1599021I-1J-203D01*
G01Y1598401D01*
G03X648552Y1598269I200J0D01*
G02Y1595353I-1661J-1458D01*
G03X648502Y1595221I150J-132D01*
G01Y1593283D01*
G03X648552Y1593151I200J0D01*
G02Y1590235I-1661J-1458D01*
G03X648502Y1590103I150J-132D01*
G01Y1589483D01*
G02X648300Y1589280I-202J-1D01*
G01X645480D01*
G02X645278Y1589483I1J203D01*
G01Y1590103D01*
G03X645228Y1590235I-200J0D01*
G02Y1593151I1661J1458D01*
G03X645278Y1593283I-150J132D01*
G01Y1595221D01*
G03X645228Y1595353I-200J0D01*
G02Y1598269I1661J1458D01*
G03X645278Y1598401I-150J132D01*
G01Y1599021D01*
G02X645480Y1599224I202J1D01*
G37*
G36*
G01X662803D02*
X665623D01*
G02X665826Y1599021I0J-203D01*
G01Y1598399D01*
G03X665876Y1598267I200J0D01*
G02Y1595355I-1664J-1456D01*
G03X665826Y1595223I150J-132D01*
G01Y1593281D01*
G03X665876Y1593149I200J0D01*
G02Y1590237I-1664J-1456D01*
G03X665826Y1590105I150J-132D01*
G01Y1589483D01*
G02X665623Y1589280I-203J0D01*
G01X662803D01*
G02X662600Y1589483I0J203D01*
G01Y1590105D01*
G03X662550Y1590237I-200J0D01*
G02Y1593149I1664J1456D01*
G03X662600Y1593281I-150J132D01*
G01Y1595223D01*
G03X662550Y1595355I-200J0D01*
G02Y1598267I1664J1456D01*
G03X662600Y1598399I-150J132D01*
G01Y1599021D01*
G02X662803Y1599224I203J0D01*
G37*
G36*
G01X680125D02*
X682945D01*
G02X683148Y1599021I0J-203D01*
G01Y1598399D01*
G03X683198Y1598267I200J0D01*
G02Y1595355I-1664J-1456D01*
G03X683148Y1595223I150J-132D01*
G01Y1593281D01*
G03X683198Y1593149I200J0D01*
G02Y1590237I-1664J-1456D01*
G03X683148Y1590105I150J-132D01*
G01Y1589483D01*
G02X682945Y1589280I-203J0D01*
G01X680125D01*
G02X679922Y1589483I0J203D01*
G01Y1590105D01*
G03X679872Y1590237I-200J0D01*
G02Y1593149I1664J1456D01*
G03X679922Y1593281I-150J132D01*
G01Y1595223D01*
G03X679872Y1595355I-200J0D01*
G02Y1598267I1664J1456D01*
G03X679922Y1598399I-150J132D01*
G01Y1599021D01*
G02X680125Y1599224I203J0D01*
G37*
G36*
G01X1130440D02*
X1133260D01*
G02X1133462Y1599021I-1J-203D01*
G01Y1598401D01*
G03X1133512Y1598269I200J0D01*
G02Y1595353I-1661J-1458D01*
G03X1133462Y1595221I150J-132D01*
G01Y1593283D01*
G03X1133512Y1593151I200J0D01*
G02Y1590235I-1661J-1458D01*
G03X1133462Y1590103I150J-132D01*
G01Y1589483D01*
G02X1133260Y1589280I-202J-1D01*
G01X1130440D01*
G02X1130238Y1589483I1J203D01*
G01Y1590103D01*
G03X1130188Y1590235I-200J0D01*
G02Y1593151I1661J1458D01*
G03X1130238Y1593283I-150J132D01*
G01Y1595221D01*
G03X1130188Y1595353I-200J0D01*
G02Y1598269I1661J1458D01*
G03X1130238Y1598401I-150J132D01*
G01Y1599021D01*
G02X1130440Y1599224I202J1D01*
G37*
G36*
G01X1147763D02*
X1150583D01*
G02X1150786Y1599021I0J-203D01*
G01Y1598399D01*
G03X1150836Y1598267I200J0D01*
G02Y1595355I-1664J-1456D01*
G03X1150786Y1595223I150J-132D01*
G01Y1593281D01*
G03X1150836Y1593149I200J0D01*
G02Y1590237I-1664J-1456D01*
G03X1150786Y1590105I150J-132D01*
G01Y1589483D01*
G02X1150583Y1589280I-203J0D01*
G01X1147763D01*
G02X1147560Y1589483I0J203D01*
G01Y1590105D01*
G03X1147510Y1590237I-200J0D01*
G02Y1593149I1664J1456D01*
G03X1147560Y1593281I-150J132D01*
G01Y1595223D01*
G03X1147510Y1595355I-200J0D01*
G02Y1598267I1664J1456D01*
G03X1147560Y1598399I-150J132D01*
G01Y1599021D01*
G02X1147763Y1599224I203J0D01*
G37*
G36*
G01X1165086D02*
X1167906D01*
G02X1168108Y1599021I-1J-203D01*
G01Y1598401D01*
G03X1168158Y1598269I200J0D01*
G02Y1595353I-1661J-1458D01*
G03X1168108Y1595221I150J-132D01*
G01Y1593283D01*
G03X1168158Y1593151I200J0D01*
G02Y1590235I-1661J-1458D01*
G03X1168108Y1590103I150J-132D01*
G01Y1589483D01*
G02X1167906Y1589280I-202J-1D01*
G01X1165086D01*
G02X1164884Y1589483I1J203D01*
G01Y1590103D01*
G03X1164834Y1590235I-200J0D01*
G02Y1593151I1661J1458D01*
G03X1164884Y1593283I-150J132D01*
G01Y1595221D01*
G03X1164834Y1595353I-200J0D01*
G02Y1598269I1661J1458D01*
G03X1164884Y1598401I-150J132D01*
G01Y1599021D01*
G02X1165086Y1599224I202J1D01*
G37*
G36*
G01X1182408D02*
X1185228D01*
G02X1185430Y1599021I-1J-203D01*
G01Y1598401D01*
G03X1185480Y1598269I200J0D01*
G02Y1595353I-1661J-1458D01*
G03X1185430Y1595221I150J-132D01*
G01Y1593283D01*
G03X1185480Y1593151I200J0D01*
G02Y1590235I-1661J-1458D01*
G03X1185430Y1590103I150J-132D01*
G01Y1589483D01*
G02X1185228Y1589280I-202J-1D01*
G01X1182408D01*
G02X1182206Y1589483I1J203D01*
G01Y1590103D01*
G03X1182156Y1590235I-200J0D01*
G02Y1593151I1661J1458D01*
G03X1182206Y1593283I-150J132D01*
G01Y1595221D01*
G03X1182156Y1595353I-200J0D01*
G02Y1598269I1661J1458D01*
G03X1182206Y1598401I-150J132D01*
G01Y1599021D01*
G02X1182408Y1599224I202J1D01*
G37*
G36*
G01X1303669D02*
X1306489D01*
G02X1306692Y1599021I0J-203D01*
G01Y1598399D01*
G03X1306742Y1598267I200J0D01*
G02Y1595355I-1664J-1456D01*
G03X1306692Y1595223I150J-132D01*
G01Y1593281D01*
G03X1306742Y1593149I200J0D01*
G02Y1590237I-1664J-1456D01*
G03X1306692Y1590105I150J-132D01*
G01Y1589483D01*
G02X1306489Y1589280I-203J0D01*
G01X1303669D01*
G02X1303466Y1589483I0J203D01*
G01Y1590105D01*
G03X1303416Y1590237I-200J0D01*
G02Y1593149I1664J1456D01*
G03X1303466Y1593281I-150J132D01*
G01Y1595223D01*
G03X1303416Y1595355I-200J0D01*
G02Y1598267I1664J1456D01*
G03X1303466Y1598399I-150J132D01*
G01Y1599021D01*
G02X1303669Y1599224I203J0D01*
G37*
G36*
G01X1320992D02*
X1323812D01*
G02X1324014Y1599021I-1J-203D01*
G01Y1598401D01*
G03X1324064Y1598269I200J0D01*
G02Y1595353I-1661J-1458D01*
G03X1324014Y1595221I150J-132D01*
G01Y1593283D01*
G03X1324064Y1593151I200J0D01*
G02Y1590235I-1661J-1458D01*
G03X1324014Y1590103I150J-132D01*
G01Y1589483D01*
G02X1323812Y1589280I-202J-1D01*
G01X1320992D01*
G02X1320790Y1589483I1J203D01*
G01Y1590103D01*
G03X1320740Y1590235I-200J0D01*
G02Y1593151I1661J1458D01*
G03X1320790Y1593283I-150J132D01*
G01Y1595221D01*
G03X1320740Y1595353I-200J0D01*
G02Y1598269I1661J1458D01*
G03X1320790Y1598401I-150J132D01*
G01Y1599021D01*
G02X1320992Y1599224I202J1D01*
G37*
G36*
G01X1338315D02*
X1341135D01*
G02X1341338Y1599021I0J-203D01*
G01Y1598399D01*
G03X1341388Y1598267I200J0D01*
G02Y1595355I-1664J-1456D01*
G03X1341338Y1595223I150J-132D01*
G01Y1593281D01*
G03X1341388Y1593149I200J0D01*
G02Y1590237I-1664J-1456D01*
G03X1341338Y1590105I150J-132D01*
G01Y1589483D01*
G02X1341135Y1589280I-203J0D01*
G01X1338315D01*
G02X1338112Y1589483I0J203D01*
G01Y1590105D01*
G03X1338062Y1590237I-200J0D01*
G02Y1593149I1664J1456D01*
G03X1338112Y1593281I-150J132D01*
G01Y1595223D01*
G03X1338062Y1595355I-200J0D01*
G02Y1598267I1664J1456D01*
G03X1338112Y1598399I-150J132D01*
G01Y1599021D01*
G02X1338315Y1599224I203J0D01*
G37*
G36*
G01X1355637D02*
X1358457D01*
G02X1358660Y1599021I0J-203D01*
G01Y1598399D01*
G03X1358710Y1598267I200J0D01*
G02Y1595355I-1664J-1456D01*
G03X1358660Y1595223I150J-132D01*
G01Y1593281D01*
G03X1358710Y1593149I200J0D01*
G02Y1590237I-1664J-1456D01*
G03X1358660Y1590105I150J-132D01*
G01Y1589483D01*
G02X1358457Y1589280I-203J0D01*
G01X1355637D01*
G02X1355434Y1589483I0J203D01*
G01Y1590105D01*
G03X1355384Y1590237I-200J0D01*
G02Y1593149I1664J1456D01*
G03X1355434Y1593281I-150J132D01*
G01Y1595223D01*
G03X1355384Y1595355I-200J0D01*
G02Y1598267I1664J1456D01*
G03X1355434Y1598399I-150J132D01*
G01Y1599021D01*
G02X1355637Y1599224I203J0D01*
G37*
G36*
G01X1476897D02*
X1479717D01*
G02X1479920Y1599021I0J-203D01*
G01Y1598399D01*
G03X1479970Y1598267I200J0D01*
G02Y1595355I-1664J-1456D01*
G03X1479920Y1595223I150J-132D01*
G01Y1593281D01*
G03X1479970Y1593149I200J0D01*
G02Y1590237I-1664J-1456D01*
G03X1479920Y1590105I150J-132D01*
G01Y1589483D01*
G02X1479717Y1589280I-203J0D01*
G01X1476897D01*
G02X1476694Y1589483I0J203D01*
G01Y1590105D01*
G03X1476644Y1590237I-200J0D01*
G02Y1593149I1664J1456D01*
G03X1476694Y1593281I-150J132D01*
G01Y1595223D01*
G03X1476644Y1595355I-200J0D01*
G02Y1598267I1664J1456D01*
G03X1476694Y1598399I-150J132D01*
G01Y1599021D01*
G02X1476897Y1599224I203J0D01*
G37*
G36*
G01X1650125D02*
X1652945D01*
G02X1653148Y1599021I0J-203D01*
G01Y1598399D01*
G03X1653198Y1598267I200J0D01*
G02Y1595355I-1664J-1456D01*
G03X1653148Y1595223I150J-132D01*
G01Y1593281D01*
G03X1653198Y1593149I200J0D01*
G02Y1590237I-1664J-1456D01*
G03X1653148Y1590105I150J-132D01*
G01Y1589483D01*
G02X1652945Y1589280I-203J0D01*
G01X1650125D01*
G02X1649922Y1589483I0J203D01*
G01Y1590105D01*
G03X1649872Y1590237I-200J0D01*
G02Y1593149I1664J1456D01*
G03X1649922Y1593281I-150J132D01*
G01Y1595223D01*
G03X1649872Y1595355I-200J0D01*
G02Y1598267I1664J1456D01*
G03X1649922Y1598399I-150J132D01*
G01Y1599021D01*
G02X1650125Y1599224I203J0D01*
G37*
G36*
G01X1667448D02*
X1670268D01*
G02X1670470Y1599021I-1J-203D01*
G01Y1598401D01*
G03X1670520Y1598269I200J0D01*
G02Y1595353I-1661J-1458D01*
G03X1670470Y1595221I150J-132D01*
G01Y1593283D01*
G03X1670520Y1593151I200J0D01*
G02Y1590235I-1661J-1458D01*
G03X1670470Y1590103I150J-132D01*
G01Y1589483D01*
G02X1670268Y1589280I-202J-1D01*
G01X1667448D01*
G02X1667246Y1589483I1J203D01*
G01Y1590103D01*
G03X1667196Y1590235I-200J0D01*
G02Y1593151I1661J1458D01*
G03X1667246Y1593283I-150J132D01*
G01Y1595221D01*
G03X1667196Y1595353I-200J0D01*
G02Y1598269I1661J1458D01*
G03X1667246Y1598401I-150J132D01*
G01Y1599021D01*
G02X1667448Y1599224I202J1D01*
G37*
G36*
G01X1684771D02*
X1687591D01*
G02X1687794Y1599021I0J-203D01*
G01Y1598399D01*
G03X1687844Y1598267I200J0D01*
G02Y1595355I-1664J-1456D01*
G03X1687794Y1595223I150J-132D01*
G01Y1593281D01*
G03X1687844Y1593149I200J0D01*
G02Y1590237I-1664J-1456D01*
G03X1687794Y1590105I150J-132D01*
G01Y1589483D01*
G02X1687591Y1589280I-203J0D01*
G01X1684771D01*
G02X1684568Y1589483I0J203D01*
G01Y1590105D01*
G03X1684518Y1590237I-200J0D01*
G02Y1593149I1664J1456D01*
G03X1684568Y1593281I-150J132D01*
G01Y1595223D01*
G03X1684518Y1595355I-200J0D01*
G02Y1598267I1664J1456D01*
G03X1684568Y1598399I-150J132D01*
G01Y1599021D01*
G02X1684771Y1599224I203J0D01*
G37*
G36*
G01X1702093D02*
X1704913D01*
G02X1705116Y1599021I0J-203D01*
G01Y1598399D01*
G03X1705166Y1598267I200J0D01*
G02Y1595355I-1664J-1456D01*
G03X1705116Y1595223I150J-132D01*
G01Y1593281D01*
G03X1705166Y1593149I200J0D01*
G02Y1590237I-1664J-1456D01*
G03X1705116Y1590105I150J-132D01*
G01Y1589483D01*
G02X1704913Y1589280I-203J0D01*
G01X1702093D01*
G02X1701890Y1589483I0J203D01*
G01Y1590105D01*
G03X1701840Y1590237I-200J0D01*
G02Y1593149I1664J1456D01*
G03X1701890Y1593281I-150J132D01*
G01Y1595223D01*
G03X1701840Y1595355I-200J0D01*
G02Y1598267I1664J1456D01*
G03X1701890Y1598399I-150J132D01*
G01Y1599021D01*
G02X1702093Y1599224I203J0D01*
G37*
G36*
G01X134456Y1603554D02*
X137276D01*
G02X137478Y1603352I0J-202D01*
G01Y1602732D01*
G03X137528Y1602600I200J0D01*
G02Y1599684I-1661J-1458D01*
G03X137478Y1599552I150J-132D01*
G01Y1597614D01*
G03X137528Y1597482I200J0D01*
G02Y1594566I-1661J-1458D01*
G03X137478Y1594434I150J-132D01*
G01Y1593814D01*
G02X137276Y1593612I-202J0D01*
G01X134456D01*
G02X134254Y1593814I0J202D01*
G01Y1594434D01*
G03X134204Y1594566I-200J0D01*
G02Y1597482I1661J1458D01*
G03X134254Y1597614I-150J132D01*
G01Y1599552D01*
G03X134204Y1599684I-200J0D01*
G02Y1602600I1661J1458D01*
G03X134254Y1602732I-150J132D01*
G01Y1603352D01*
G02X134456Y1603554I202J0D01*
G37*
G36*
G01X169102D02*
X171922D01*
G02X172124Y1603352I0J-202D01*
G01Y1602732D01*
G03X172174Y1602600I200J0D01*
G02Y1599684I-1661J-1458D01*
G03X172124Y1599552I150J-132D01*
G01Y1597614D01*
G03X172174Y1597482I200J0D01*
G02Y1594566I-1661J-1458D01*
G03X172124Y1594434I150J-132D01*
G01Y1593814D01*
G02X171922Y1593612I-202J0D01*
G01X169102D01*
G02X168900Y1593814I0J202D01*
G01Y1594434D01*
G03X168850Y1594566I-200J0D01*
G02Y1597482I1661J1458D01*
G03X168900Y1597614I-150J132D01*
G01Y1599552D01*
G03X168850Y1599684I-200J0D01*
G02Y1602600I1661J1458D01*
G03X168900Y1602732I-150J132D01*
G01Y1603352D01*
G02X169102Y1603554I202J0D01*
G37*
G36*
G01X307684D02*
X310504D01*
G02X310706Y1603352I0J-202D01*
G01Y1602732D01*
G03X310756Y1602600I200J0D01*
G02Y1599684I-1661J-1458D01*
G03X310706Y1599552I150J-132D01*
G01Y1597614D01*
G03X310756Y1597482I200J0D01*
G02Y1594566I-1661J-1458D01*
G03X310706Y1594434I150J-132D01*
G01Y1593814D01*
G02X310504Y1593612I-202J0D01*
G01X307684D01*
G02X307482Y1593814I0J202D01*
G01Y1594434D01*
G03X307432Y1594566I-200J0D01*
G02Y1597482I1661J1458D01*
G03X307482Y1597614I-150J132D01*
G01Y1599552D01*
G03X307432Y1599684I-200J0D01*
G02Y1602600I1661J1458D01*
G03X307482Y1602732I-150J132D01*
G01Y1603352D01*
G02X307684Y1603554I202J0D01*
G37*
G36*
G01X342330D02*
X345150D01*
G02X345352Y1603352I0J-202D01*
G01Y1602732D01*
G03X345402Y1602600I200J0D01*
G02Y1599684I-1661J-1458D01*
G03X345352Y1599552I150J-132D01*
G01Y1597614D01*
G03X345402Y1597482I200J0D01*
G02Y1594566I-1661J-1458D01*
G03X345352Y1594434I150J-132D01*
G01Y1593814D01*
G02X345150Y1593612I-202J0D01*
G01X342330D01*
G02X342128Y1593814I0J202D01*
G01Y1594434D01*
G03X342078Y1594566I-200J0D01*
G02Y1597482I1661J1458D01*
G03X342128Y1597614I-150J132D01*
G01Y1599552D01*
G03X342078Y1599684I-200J0D01*
G02Y1602600I1661J1458D01*
G03X342128Y1602732I-150J132D01*
G01Y1603352D01*
G02X342330Y1603554I202J0D01*
G37*
G36*
G01X636818D02*
X639638D01*
G02X639840Y1603352I0J-202D01*
G01Y1602732D01*
G03X639890Y1602600I200J0D01*
G02Y1599684I-1661J-1458D01*
G03X639840Y1599552I150J-132D01*
G01Y1597614D01*
G03X639890Y1597482I200J0D01*
G02Y1594566I-1661J-1458D01*
G03X639840Y1594434I150J-132D01*
G01Y1593814D01*
G02X639638Y1593612I-202J0D01*
G01X636818D01*
G02X636616Y1593814I0J202D01*
G01Y1594434D01*
G03X636566Y1594566I-200J0D01*
G02Y1597482I1661J1458D01*
G03X636616Y1597614I-150J132D01*
G01Y1599552D01*
G03X636566Y1599684I-200J0D01*
G02Y1602600I1661J1458D01*
G03X636616Y1602732I-150J132D01*
G01Y1603352D01*
G02X636818Y1603554I202J0D01*
G37*
G36*
G01X671464D02*
X674284D01*
G02X674486Y1603352I0J-202D01*
G01Y1602732D01*
G03X674536Y1602600I200J0D01*
G02Y1599684I-1661J-1458D01*
G03X674486Y1599552I150J-132D01*
G01Y1597614D01*
G03X674536Y1597482I200J0D01*
G02Y1594566I-1661J-1458D01*
G03X674486Y1594434I150J-132D01*
G01Y1593814D01*
G02X674284Y1593612I-202J0D01*
G01X671464D01*
G02X671262Y1593814I0J202D01*
G01Y1594434D01*
G03X671212Y1594566I-200J0D01*
G02Y1597482I1661J1458D01*
G03X671262Y1597614I-150J132D01*
G01Y1599552D01*
G03X671212Y1599684I-200J0D01*
G02Y1602600I1661J1458D01*
G03X671262Y1602732I-150J132D01*
G01Y1603352D01*
G02X671464Y1603554I202J0D01*
G37*
G36*
G01X1156424D02*
X1159244D01*
G02X1159446Y1603352I0J-202D01*
G01Y1602732D01*
G03X1159496Y1602600I200J0D01*
G02Y1599684I-1661J-1458D01*
G03X1159446Y1599552I150J-132D01*
G01Y1597614D01*
G03X1159496Y1597482I200J0D01*
G02Y1594566I-1661J-1458D01*
G03X1159446Y1594434I150J-132D01*
G01Y1593814D01*
G02X1159244Y1593612I-202J0D01*
G01X1156424D01*
G02X1156222Y1593814I0J202D01*
G01Y1594434D01*
G03X1156172Y1594566I-200J0D01*
G02Y1597482I1661J1458D01*
G03X1156222Y1597614I-150J132D01*
G01Y1599552D01*
G03X1156172Y1599684I-200J0D01*
G02Y1602600I1661J1458D01*
G03X1156222Y1602732I-150J132D01*
G01Y1603352D01*
G02X1156424Y1603554I202J0D01*
G37*
G36*
G01X1191070D02*
X1193890D01*
G02X1194092Y1603352I0J-202D01*
G01Y1602732D01*
G03X1194142Y1602600I200J0D01*
G02Y1599684I-1661J-1458D01*
G03X1194092Y1599552I150J-132D01*
G01Y1597614D01*
G03X1194142Y1597482I200J0D01*
G02Y1594566I-1661J-1458D01*
G03X1194092Y1594434I150J-132D01*
G01Y1593814D01*
G02X1193890Y1593612I-202J0D01*
G01X1191070D01*
G02X1190868Y1593814I0J202D01*
G01Y1594434D01*
G03X1190818Y1594566I-200J0D01*
G02Y1597482I1661J1458D01*
G03X1190868Y1597614I-150J132D01*
G01Y1599552D01*
G03X1190818Y1599684I-200J0D01*
G02Y1602600I1661J1458D01*
G03X1190868Y1602732I-150J132D01*
G01Y1603352D01*
G02X1191070Y1603554I202J0D01*
G37*
G36*
G01X1312330D02*
X1315150D01*
G02X1315352Y1603352I0J-202D01*
G01Y1602732D01*
G03X1315402Y1602600I200J0D01*
G02Y1599684I-1661J-1458D01*
G03X1315352Y1599552I150J-132D01*
G01Y1597614D01*
G03X1315402Y1597482I200J0D01*
G02Y1594566I-1661J-1458D01*
G03X1315352Y1594434I150J-132D01*
G01Y1593814D01*
G02X1315150Y1593612I-202J0D01*
G01X1312330D01*
G02X1312128Y1593814I0J202D01*
G01Y1594434D01*
G03X1312078Y1594566I-200J0D01*
G02Y1597482I1661J1458D01*
G03X1312128Y1597614I-150J132D01*
G01Y1599552D01*
G03X1312078Y1599684I-200J0D01*
G02Y1602600I1661J1458D01*
G03X1312128Y1602732I-150J132D01*
G01Y1603352D01*
G02X1312330Y1603554I202J0D01*
G37*
G36*
G01X1346976D02*
X1349796D01*
G02X1349998Y1603352I0J-202D01*
G01Y1602732D01*
G03X1350048Y1602600I200J0D01*
G02Y1599684I-1661J-1458D01*
G03X1349998Y1599552I150J-132D01*
G01Y1597614D01*
G03X1350048Y1597482I200J0D01*
G02Y1594566I-1661J-1458D01*
G03X1349998Y1594434I150J-132D01*
G01Y1593814D01*
G02X1349796Y1593612I-202J0D01*
G01X1346976D01*
G02X1346774Y1593814I0J202D01*
G01Y1594434D01*
G03X1346724Y1594566I-200J0D01*
G02Y1597482I1661J1458D01*
G03X1346774Y1597614I-150J132D01*
G01Y1599552D01*
G03X1346724Y1599684I-200J0D01*
G02Y1602600I1661J1458D01*
G03X1346774Y1602732I-150J132D01*
G01Y1603352D01*
G02X1346976Y1603554I202J0D01*
G37*
G36*
G01X1658786D02*
X1661606D01*
G02X1661808Y1603352I0J-202D01*
G01Y1602732D01*
G03X1661858Y1602600I200J0D01*
G02Y1599684I-1661J-1458D01*
G03X1661808Y1599552I150J-132D01*
G01Y1597614D01*
G03X1661858Y1597482I200J0D01*
G02Y1594566I-1661J-1458D01*
G03X1661808Y1594434I150J-132D01*
G01Y1593814D01*
G02X1661606Y1593612I-202J0D01*
G01X1658786D01*
G02X1658584Y1593814I0J202D01*
G01Y1594434D01*
G03X1658534Y1594566I-200J0D01*
G02Y1597482I1661J1458D01*
G03X1658584Y1597614I-150J132D01*
G01Y1599552D01*
G03X1658534Y1599684I-200J0D01*
G02Y1602600I1661J1458D01*
G03X1658584Y1602732I-150J132D01*
G01Y1603352D01*
G02X1658786Y1603554I202J0D01*
G37*
G36*
G01X1693432D02*
X1696252D01*
G02X1696454Y1603352I0J-202D01*
G01Y1602732D01*
G03X1696504Y1602600I200J0D01*
G02Y1599684I-1661J-1458D01*
G03X1696454Y1599552I150J-132D01*
G01Y1597614D01*
G03X1696504Y1597482I200J0D01*
G02Y1594566I-1661J-1458D01*
G03X1696454Y1594434I150J-132D01*
G01Y1593814D01*
G02X1696252Y1593612I-202J0D01*
G01X1693432D01*
G02X1693230Y1593814I0J202D01*
G01Y1594434D01*
G03X1693180Y1594566I-200J0D01*
G02Y1597482I1661J1458D01*
G03X1693230Y1597614I-150J132D01*
G01Y1599552D01*
G03X1693180Y1599684I-200J0D01*
G02Y1602600I1661J1458D01*
G03X1693230Y1602732I-150J132D01*
G01Y1603352D01*
G02X1693432Y1603554I202J0D01*
G37*
G36*
G01X117133D02*
X119953D01*
G02X120156Y1603352I1J-202D01*
G01Y1602730D01*
G03X120206Y1602598I200J0D01*
G02Y1599686I-1664J-1456D01*
G03X120156Y1599554I150J-132D01*
G01Y1597612D01*
G03X120206Y1597480I200J0D01*
G02Y1594568I-1664J-1456D01*
G03X120156Y1594436I150J-132D01*
G01Y1593814D01*
G02X119953Y1593612I-203J1D01*
G01X117133D01*
G02X116930Y1593814I-1J202D01*
G01Y1594436D01*
G03X116880Y1594568I-200J0D01*
G02Y1597480I1664J1456D01*
G03X116930Y1597612I-150J132D01*
G01Y1599554D01*
G03X116880Y1599686I-200J0D01*
G02Y1602598I1664J1456D01*
G03X116930Y1602730I-150J132D01*
G01Y1603352D01*
G02X117133Y1603554I203J-1D01*
G37*
G36*
G01X151779D02*
X154599D01*
G02X154802Y1603352I1J-202D01*
G01Y1602730D01*
G03X154852Y1602598I200J0D01*
G02Y1599686I-1664J-1456D01*
G03X154802Y1599554I150J-132D01*
G01Y1597612D01*
G03X154852Y1597480I200J0D01*
G02Y1594568I-1664J-1456D01*
G03X154802Y1594436I150J-132D01*
G01Y1593814D01*
G02X154599Y1593612I-203J1D01*
G01X151779D01*
G02X151576Y1593814I-1J202D01*
G01Y1594436D01*
G03X151526Y1594568I-200J0D01*
G02Y1597480I1664J1456D01*
G03X151576Y1597612I-150J132D01*
G01Y1599554D01*
G03X151526Y1599686I-200J0D01*
G02Y1602598I1664J1456D01*
G03X151576Y1602730I-150J132D01*
G01Y1603352D01*
G02X151779Y1603554I203J-1D01*
G37*
G36*
G01X186425D02*
X189245D01*
G02X189448Y1603352I1J-202D01*
G01Y1602730D01*
G03X189498Y1602598I200J0D01*
G02Y1599686I-1664J-1456D01*
G03X189448Y1599554I150J-132D01*
G01Y1597612D01*
G03X189498Y1597480I200J0D01*
G02Y1594568I-1664J-1456D01*
G03X189448Y1594436I150J-132D01*
G01Y1593814D01*
G02X189245Y1593612I-203J1D01*
G01X186425D01*
G02X186222Y1593814I-1J202D01*
G01Y1594436D01*
G03X186172Y1594568I-200J0D01*
G02Y1597480I1664J1456D01*
G03X186222Y1597612I-150J132D01*
G01Y1599554D01*
G03X186172Y1599686I-200J0D01*
G02Y1602598I1664J1456D01*
G03X186222Y1602730I-150J132D01*
G01Y1603352D01*
G02X186425Y1603554I203J-1D01*
G37*
G36*
G01X290361D02*
X293181D01*
G02X293384Y1603352I1J-202D01*
G01Y1602730D01*
G03X293434Y1602598I200J0D01*
G02Y1599686I-1664J-1456D01*
G03X293384Y1599554I150J-132D01*
G01Y1597612D01*
G03X293434Y1597480I200J0D01*
G02Y1594568I-1664J-1456D01*
G03X293384Y1594436I150J-132D01*
G01Y1593814D01*
G02X293181Y1593612I-203J1D01*
G01X290361D01*
G02X290158Y1593814I-1J202D01*
G01Y1594436D01*
G03X290108Y1594568I-200J0D01*
G02Y1597480I1664J1456D01*
G03X290158Y1597612I-150J132D01*
G01Y1599554D01*
G03X290108Y1599686I-200J0D01*
G02Y1602598I1664J1456D01*
G03X290158Y1602730I-150J132D01*
G01Y1603352D01*
G02X290361Y1603554I203J-1D01*
G37*
G36*
G01X325007D02*
X327827D01*
G02X328030Y1603352I1J-202D01*
G01Y1602730D01*
G03X328080Y1602598I200J0D01*
G02Y1599686I-1664J-1456D01*
G03X328030Y1599554I150J-132D01*
G01Y1597612D01*
G03X328080Y1597480I200J0D01*
G02Y1594568I-1664J-1456D01*
G03X328030Y1594436I150J-132D01*
G01Y1593814D01*
G02X327827Y1593612I-203J1D01*
G01X325007D01*
G02X324804Y1593814I-1J202D01*
G01Y1594436D01*
G03X324754Y1594568I-200J0D01*
G02Y1597480I1664J1456D01*
G03X324804Y1597612I-150J132D01*
G01Y1599554D01*
G03X324754Y1599686I-200J0D01*
G02Y1602598I1664J1456D01*
G03X324804Y1602730I-150J132D01*
G01Y1603352D01*
G02X325007Y1603554I203J-1D01*
G37*
G36*
G01X359653D02*
X362473D01*
G02X362676Y1603352I1J-202D01*
G01Y1602730D01*
G03X362726Y1602598I200J0D01*
G02Y1599686I-1664J-1456D01*
G03X362676Y1599554I150J-132D01*
G01Y1597612D01*
G03X362726Y1597480I200J0D01*
G02Y1594568I-1664J-1456D01*
G03X362676Y1594436I150J-132D01*
G01Y1593814D01*
G02X362473Y1593612I-203J1D01*
G01X359653D01*
G02X359450Y1593814I-1J202D01*
G01Y1594436D01*
G03X359400Y1594568I-200J0D01*
G02Y1597480I1664J1456D01*
G03X359450Y1597612I-150J132D01*
G01Y1599554D01*
G03X359400Y1599686I-200J0D01*
G02Y1602598I1664J1456D01*
G03X359450Y1602730I-150J132D01*
G01Y1603352D01*
G02X359653Y1603554I203J-1D01*
G37*
G36*
G01X515559D02*
X518379D01*
G02X518582Y1603352I1J-202D01*
G01Y1602730D01*
G03X518632Y1602598I200J0D01*
G02Y1599686I-1664J-1456D01*
G03X518582Y1599554I150J-132D01*
G01Y1597612D01*
G03X518632Y1597480I200J0D01*
G02Y1594568I-1664J-1456D01*
G03X518582Y1594436I150J-132D01*
G01Y1593814D01*
G02X518379Y1593612I-203J1D01*
G01X515559D01*
G02X515356Y1593814I-1J202D01*
G01Y1594436D01*
G03X515306Y1594568I-200J0D01*
G02Y1597480I1664J1456D01*
G03X515356Y1597612I-150J132D01*
G01Y1599554D01*
G03X515306Y1599686I-200J0D01*
G02Y1602598I1664J1456D01*
G03X515356Y1602730I-150J132D01*
G01Y1603352D01*
G02X515559Y1603554I203J-1D01*
G37*
G36*
G01X654141D02*
X656961D01*
G02X657164Y1603352I1J-202D01*
G01Y1602730D01*
G03X657214Y1602598I200J0D01*
G02Y1599686I-1664J-1456D01*
G03X657164Y1599554I150J-132D01*
G01Y1597612D01*
G03X657214Y1597480I200J0D01*
G02Y1594568I-1664J-1456D01*
G03X657164Y1594436I150J-132D01*
G01Y1593814D01*
G02X656961Y1593612I-203J1D01*
G01X654141D01*
G02X653938Y1593814I-1J202D01*
G01Y1594436D01*
G03X653888Y1594568I-200J0D01*
G02Y1597480I1664J1456D01*
G03X653938Y1597612I-150J132D01*
G01Y1599554D01*
G03X653888Y1599686I-200J0D01*
G02Y1602598I1664J1456D01*
G03X653938Y1602730I-150J132D01*
G01Y1603352D01*
G02X654141Y1603554I203J-1D01*
G37*
G36*
G01X688787D02*
X691607D01*
G02X691810Y1603352I1J-202D01*
G01Y1602730D01*
G03X691860Y1602598I200J0D01*
G02Y1599686I-1664J-1456D01*
G03X691810Y1599554I150J-132D01*
G01Y1597612D01*
G03X691860Y1597480I200J0D01*
G02Y1594568I-1664J-1456D01*
G03X691810Y1594436I150J-132D01*
G01Y1593814D01*
G02X691607Y1593612I-203J1D01*
G01X688787D01*
G02X688584Y1593814I-1J202D01*
G01Y1594436D01*
G03X688534Y1594568I-200J0D01*
G02Y1597480I1664J1456D01*
G03X688584Y1597612I-150J132D01*
G01Y1599554D01*
G03X688534Y1599686I-200J0D01*
G02Y1602598I1664J1456D01*
G03X688584Y1602730I-150J132D01*
G01Y1603352D01*
G02X688787Y1603554I203J-1D01*
G37*
G36*
G01X1139101D02*
X1141921D01*
G02X1142124Y1603352I1J-202D01*
G01Y1602730D01*
G03X1142174Y1602598I200J0D01*
G02Y1599686I-1664J-1456D01*
G03X1142124Y1599554I150J-132D01*
G01Y1597612D01*
G03X1142174Y1597480I200J0D01*
G02Y1594568I-1664J-1456D01*
G03X1142124Y1594436I150J-132D01*
G01Y1593814D01*
G02X1141921Y1593612I-203J1D01*
G01X1139101D01*
G02X1138898Y1593814I-1J202D01*
G01Y1594436D01*
G03X1138848Y1594568I-200J0D01*
G02Y1597480I1664J1456D01*
G03X1138898Y1597612I-150J132D01*
G01Y1599554D01*
G03X1138848Y1599686I-200J0D01*
G02Y1602598I1664J1456D01*
G03X1138898Y1602730I-150J132D01*
G01Y1603352D01*
G02X1139101Y1603554I203J-1D01*
G37*
G36*
G01X1173747D02*
X1176567D01*
G02X1176770Y1603352I1J-202D01*
G01Y1602730D01*
G03X1176820Y1602598I200J0D01*
G02Y1599686I-1664J-1456D01*
G03X1176770Y1599554I150J-132D01*
G01Y1597612D01*
G03X1176820Y1597480I200J0D01*
G02Y1594568I-1664J-1456D01*
G03X1176770Y1594436I150J-132D01*
G01Y1593814D01*
G02X1176567Y1593612I-203J1D01*
G01X1173747D01*
G02X1173544Y1593814I-1J202D01*
G01Y1594436D01*
G03X1173494Y1594568I-200J0D01*
G02Y1597480I1664J1456D01*
G03X1173544Y1597612I-150J132D01*
G01Y1599554D01*
G03X1173494Y1599686I-200J0D01*
G02Y1602598I1664J1456D01*
G03X1173544Y1602730I-150J132D01*
G01Y1603352D01*
G02X1173747Y1603554I203J-1D01*
G37*
G36*
G01X1329653D02*
X1332473D01*
G02X1332676Y1603352I1J-202D01*
G01Y1602730D01*
G03X1332726Y1602598I200J0D01*
G02Y1599686I-1664J-1456D01*
G03X1332676Y1599554I150J-132D01*
G01Y1597612D01*
G03X1332726Y1597480I200J0D01*
G02Y1594568I-1664J-1456D01*
G03X1332676Y1594436I150J-132D01*
G01Y1593814D01*
G02X1332473Y1593612I-203J1D01*
G01X1329653D01*
G02X1329450Y1593814I-1J202D01*
G01Y1594436D01*
G03X1329400Y1594568I-200J0D01*
G02Y1597480I1664J1456D01*
G03X1329450Y1597612I-150J132D01*
G01Y1599554D01*
G03X1329400Y1599686I-200J0D01*
G02Y1602598I1664J1456D01*
G03X1329450Y1602730I-150J132D01*
G01Y1603352D01*
G02X1329653Y1603554I203J-1D01*
G37*
G36*
G01X1364299D02*
X1367119D01*
G02X1367322Y1603352I1J-202D01*
G01Y1602730D01*
G03X1367372Y1602598I200J0D01*
G02Y1599686I-1664J-1456D01*
G03X1367322Y1599554I150J-132D01*
G01Y1597612D01*
G03X1367372Y1597480I200J0D01*
G02Y1594568I-1664J-1456D01*
G03X1367322Y1594436I150J-132D01*
G01Y1593814D01*
G02X1367119Y1593612I-203J1D01*
G01X1364299D01*
G02X1364096Y1593814I-1J202D01*
G01Y1594436D01*
G03X1364046Y1594568I-200J0D01*
G02Y1597480I1664J1456D01*
G03X1364096Y1597612I-150J132D01*
G01Y1599554D01*
G03X1364046Y1599686I-200J0D01*
G02Y1602598I1664J1456D01*
G03X1364096Y1602730I-150J132D01*
G01Y1603352D01*
G02X1364299Y1603554I203J-1D01*
G37*
G36*
G01X1676109D02*
X1678929D01*
G02X1679132Y1603352I1J-202D01*
G01Y1602730D01*
G03X1679182Y1602598I200J0D01*
G02Y1599686I-1664J-1456D01*
G03X1679132Y1599554I150J-132D01*
G01Y1597612D01*
G03X1679182Y1597480I200J0D01*
G02Y1594568I-1664J-1456D01*
G03X1679132Y1594436I150J-132D01*
G01Y1593814D01*
G02X1678929Y1593612I-203J1D01*
G01X1676109D01*
G02X1675906Y1593814I-1J202D01*
G01Y1594436D01*
G03X1675856Y1594568I-200J0D01*
G02Y1597480I1664J1456D01*
G03X1675906Y1597612I-150J132D01*
G01Y1599554D01*
G03X1675856Y1599686I-200J0D01*
G02Y1602598I1664J1456D01*
G03X1675906Y1602730I-150J132D01*
G01Y1603352D01*
G02X1676109Y1603554I203J-1D01*
G37*
G36*
G01X1710755D02*
X1713575D01*
G02X1713778Y1603352I1J-202D01*
G01Y1602730D01*
G03X1713828Y1602598I200J0D01*
G02Y1599686I-1664J-1456D01*
G03X1713778Y1599554I150J-132D01*
G01Y1597612D01*
G03X1713828Y1597480I200J0D01*
G02Y1594568I-1664J-1456D01*
G03X1713778Y1594436I150J-132D01*
G01Y1593814D01*
G02X1713575Y1593612I-203J1D01*
G01X1710755D01*
G02X1710552Y1593814I-1J202D01*
G01Y1594436D01*
G03X1710502Y1594568I-200J0D01*
G02Y1597480I1664J1456D01*
G03X1710552Y1597612I-150J132D01*
G01Y1599554D01*
G03X1710502Y1599686I-200J0D01*
G02Y1602598I1664J1456D01*
G03X1710552Y1602730I-150J132D01*
G01Y1603352D01*
G02X1710755Y1603554I203J-1D01*
G37*
G36*
G01X108472Y1614578D02*
X111292D01*
G02X111494Y1614376I0J-202D01*
G01Y1613756D01*
G03X111544Y1613624I200J0D01*
G02Y1610708I-1661J-1458D01*
G03X111494Y1610576I150J-132D01*
G01Y1608638D01*
G03X111544Y1608506I200J0D01*
G02Y1605590I-1661J-1458D01*
G03X111494Y1605458I150J-132D01*
G01Y1604838D01*
G02X111292Y1604636I-202J0D01*
G01X108472D01*
G02X108270Y1604838I0J202D01*
G01Y1605458D01*
G03X108220Y1605590I-200J0D01*
G02Y1608506I1661J1458D01*
G03X108270Y1608638I-150J132D01*
G01Y1610576D01*
G03X108220Y1610708I-200J0D01*
G02Y1613624I1661J1458D01*
G03X108270Y1613756I-150J132D01*
G01Y1614376D01*
G02X108472Y1614578I202J0D01*
G37*
G36*
G01X143118D02*
X145938D01*
G02X146140Y1614376I0J-202D01*
G01Y1613756D01*
G03X146190Y1613624I200J0D01*
G02Y1610708I-1661J-1458D01*
G03X146140Y1610576I150J-132D01*
G01Y1608638D01*
G03X146190Y1608506I200J0D01*
G02Y1605590I-1661J-1458D01*
G03X146140Y1605458I150J-132D01*
G01Y1604838D01*
G02X145938Y1604636I-202J0D01*
G01X143118D01*
G02X142916Y1604838I0J202D01*
G01Y1605458D01*
G03X142866Y1605590I-200J0D01*
G02Y1608506I1661J1458D01*
G03X142916Y1608638I-150J132D01*
G01Y1610576D01*
G03X142866Y1610708I-200J0D01*
G02Y1613624I1661J1458D01*
G03X142916Y1613756I-150J132D01*
G01Y1614376D01*
G02X143118Y1614578I202J0D01*
G37*
G36*
G01X160440D02*
X163260D01*
G02X163462Y1614376I0J-202D01*
G01Y1613756D01*
G03X163512Y1613624I200J0D01*
G02Y1610708I-1661J-1458D01*
G03X163462Y1610576I150J-132D01*
G01Y1608638D01*
G03X163512Y1608506I200J0D01*
G02Y1605590I-1661J-1458D01*
G03X163462Y1605458I150J-132D01*
G01Y1604838D01*
G02X163260Y1604636I-202J0D01*
G01X160440D01*
G02X160238Y1604838I0J202D01*
G01Y1605458D01*
G03X160188Y1605590I-200J0D01*
G02Y1608506I1661J1458D01*
G03X160238Y1608638I-150J132D01*
G01Y1610576D01*
G03X160188Y1610708I-200J0D01*
G02Y1613624I1661J1458D01*
G03X160238Y1613756I-150J132D01*
G01Y1614376D01*
G02X160440Y1614578I202J0D01*
G37*
G36*
G01X281700D02*
X284520D01*
G02X284722Y1614376I0J-202D01*
G01Y1613756D01*
G03X284772Y1613624I200J0D01*
G02Y1610708I-1661J-1458D01*
G03X284722Y1610576I150J-132D01*
G01Y1608638D01*
G03X284772Y1608506I200J0D01*
G02Y1605590I-1661J-1458D01*
G03X284722Y1605458I150J-132D01*
G01Y1604838D01*
G02X284520Y1604636I-202J0D01*
G01X281700D01*
G02X281498Y1604838I0J202D01*
G01Y1605458D01*
G03X281448Y1605590I-200J0D01*
G02Y1608506I1661J1458D01*
G03X281498Y1608638I-150J132D01*
G01Y1610576D01*
G03X281448Y1610708I-200J0D01*
G02Y1613624I1661J1458D01*
G03X281498Y1613756I-150J132D01*
G01Y1614376D01*
G02X281700Y1614578I202J0D01*
G37*
G36*
G01X316346D02*
X319166D01*
G02X319368Y1614376I0J-202D01*
G01Y1613756D01*
G03X319418Y1613624I200J0D01*
G02Y1610708I-1661J-1458D01*
G03X319368Y1610576I150J-132D01*
G01Y1608638D01*
G03X319418Y1608506I200J0D01*
G02Y1605590I-1661J-1458D01*
G03X319368Y1605458I150J-132D01*
G01Y1604838D01*
G02X319166Y1604636I-202J0D01*
G01X316346D01*
G02X316144Y1604838I0J202D01*
G01Y1605458D01*
G03X316094Y1605590I-200J0D01*
G02Y1608506I1661J1458D01*
G03X316144Y1608638I-150J132D01*
G01Y1610576D01*
G03X316094Y1610708I-200J0D01*
G02Y1613624I1661J1458D01*
G03X316144Y1613756I-150J132D01*
G01Y1614376D01*
G02X316346Y1614578I202J0D01*
G37*
G36*
G01X333668D02*
X336488D01*
G02X336690Y1614376I0J-202D01*
G01Y1613756D01*
G03X336740Y1613624I200J0D01*
G02Y1610708I-1661J-1458D01*
G03X336690Y1610576I150J-132D01*
G01Y1608638D01*
G03X336740Y1608506I200J0D01*
G02Y1605590I-1661J-1458D01*
G03X336690Y1605458I150J-132D01*
G01Y1604838D01*
G02X336488Y1604636I-202J0D01*
G01X333668D01*
G02X333466Y1604838I0J202D01*
G01Y1605458D01*
G03X333416Y1605590I-200J0D01*
G02Y1608506I1661J1458D01*
G03X333466Y1608638I-150J132D01*
G01Y1610576D01*
G03X333416Y1610708I-200J0D01*
G02Y1613624I1661J1458D01*
G03X333466Y1613756I-150J132D01*
G01Y1614376D01*
G02X333668Y1614578I202J0D01*
G37*
G36*
G01X645480D02*
X648300D01*
G02X648502Y1614376I0J-202D01*
G01Y1613756D01*
G03X648552Y1613624I200J0D01*
G02Y1610708I-1661J-1458D01*
G03X648502Y1610576I150J-132D01*
G01Y1608638D01*
G03X648552Y1608506I200J0D01*
G02Y1605590I-1661J-1458D01*
G03X648502Y1605458I150J-132D01*
G01Y1604838D01*
G02X648300Y1604636I-202J0D01*
G01X645480D01*
G02X645278Y1604838I0J202D01*
G01Y1605458D01*
G03X645228Y1605590I-200J0D01*
G02Y1608506I1661J1458D01*
G03X645278Y1608638I-150J132D01*
G01Y1610576D01*
G03X645228Y1610708I-200J0D01*
G02Y1613624I1661J1458D01*
G03X645278Y1613756I-150J132D01*
G01Y1614376D01*
G02X645480Y1614578I202J0D01*
G37*
G36*
G01X1130440D02*
X1133260D01*
G02X1133462Y1614376I0J-202D01*
G01Y1613756D01*
G03X1133512Y1613624I200J0D01*
G02Y1610708I-1661J-1458D01*
G03X1133462Y1610576I150J-132D01*
G01Y1608638D01*
G03X1133512Y1608506I200J0D01*
G02Y1605590I-1661J-1458D01*
G03X1133462Y1605458I150J-132D01*
G01Y1604838D01*
G02X1133260Y1604636I-202J0D01*
G01X1130440D01*
G02X1130238Y1604838I0J202D01*
G01Y1605458D01*
G03X1130188Y1605590I-200J0D01*
G02Y1608506I1661J1458D01*
G03X1130238Y1608638I-150J132D01*
G01Y1610576D01*
G03X1130188Y1610708I-200J0D01*
G02Y1613624I1661J1458D01*
G03X1130238Y1613756I-150J132D01*
G01Y1614376D01*
G02X1130440Y1614578I202J0D01*
G37*
G36*
G01X1165086D02*
X1167906D01*
G02X1168108Y1614376I0J-202D01*
G01Y1613756D01*
G03X1168158Y1613624I200J0D01*
G02Y1610708I-1661J-1458D01*
G03X1168108Y1610576I150J-132D01*
G01Y1608638D01*
G03X1168158Y1608506I200J0D01*
G02Y1605590I-1661J-1458D01*
G03X1168108Y1605458I150J-132D01*
G01Y1604838D01*
G02X1167906Y1604636I-202J0D01*
G01X1165086D01*
G02X1164884Y1604838I0J202D01*
G01Y1605458D01*
G03X1164834Y1605590I-200J0D01*
G02Y1608506I1661J1458D01*
G03X1164884Y1608638I-150J132D01*
G01Y1610576D01*
G03X1164834Y1610708I-200J0D01*
G02Y1613624I1661J1458D01*
G03X1164884Y1613756I-150J132D01*
G01Y1614376D01*
G02X1165086Y1614578I202J0D01*
G37*
G36*
G01X1182408D02*
X1185228D01*
G02X1185430Y1614376I0J-202D01*
G01Y1613756D01*
G03X1185480Y1613624I200J0D01*
G02Y1610708I-1661J-1458D01*
G03X1185430Y1610576I150J-132D01*
G01Y1608638D01*
G03X1185480Y1608506I200J0D01*
G02Y1605590I-1661J-1458D01*
G03X1185430Y1605458I150J-132D01*
G01Y1604838D01*
G02X1185228Y1604636I-202J0D01*
G01X1182408D01*
G02X1182206Y1604838I0J202D01*
G01Y1605458D01*
G03X1182156Y1605590I-200J0D01*
G02Y1608506I1661J1458D01*
G03X1182206Y1608638I-150J132D01*
G01Y1610576D01*
G03X1182156Y1610708I-200J0D01*
G02Y1613624I1661J1458D01*
G03X1182206Y1613756I-150J132D01*
G01Y1614376D01*
G02X1182408Y1614578I202J0D01*
G37*
G36*
G01X1320992D02*
X1323812D01*
G02X1324014Y1614376I0J-202D01*
G01Y1613756D01*
G03X1324064Y1613624I200J0D01*
G02Y1610708I-1661J-1458D01*
G03X1324014Y1610576I150J-132D01*
G01Y1608638D01*
G03X1324064Y1608506I200J0D01*
G02Y1605590I-1661J-1458D01*
G03X1324014Y1605458I150J-132D01*
G01Y1604838D01*
G02X1323812Y1604636I-202J0D01*
G01X1320992D01*
G02X1320790Y1604838I0J202D01*
G01Y1605458D01*
G03X1320740Y1605590I-200J0D01*
G02Y1608506I1661J1458D01*
G03X1320790Y1608638I-150J132D01*
G01Y1610576D01*
G03X1320740Y1610708I-200J0D01*
G02Y1613624I1661J1458D01*
G03X1320790Y1613756I-150J132D01*
G01Y1614376D01*
G02X1320992Y1614578I202J0D01*
G37*
G36*
G01X1667448D02*
X1670268D01*
G02X1670470Y1614376I0J-202D01*
G01Y1613756D01*
G03X1670520Y1613624I200J0D01*
G02Y1610708I-1661J-1458D01*
G03X1670470Y1610576I150J-132D01*
G01Y1608638D01*
G03X1670520Y1608506I200J0D01*
G02Y1605590I-1661J-1458D01*
G03X1670470Y1605458I150J-132D01*
G01Y1604838D01*
G02X1670268Y1604636I-202J0D01*
G01X1667448D01*
G02X1667246Y1604838I0J202D01*
G01Y1605458D01*
G03X1667196Y1605590I-200J0D01*
G02Y1608506I1661J1458D01*
G03X1667246Y1608638I-150J132D01*
G01Y1610576D01*
G03X1667196Y1610708I-200J0D01*
G02Y1613624I1661J1458D01*
G03X1667246Y1613756I-150J132D01*
G01Y1614376D01*
G02X1667448Y1614578I202J0D01*
G37*
G36*
G01X125795D02*
X128615D01*
G02X128818Y1614376I1J-202D01*
G01Y1613754D01*
G03X128868Y1613622I200J0D01*
G02Y1610710I-1664J-1456D01*
G03X128818Y1610578I150J-132D01*
G01Y1608636D01*
G03X128868Y1608504I200J0D01*
G02Y1605592I-1664J-1456D01*
G03X128818Y1605460I150J-132D01*
G01Y1604838D01*
G02X128615Y1604636I-203J1D01*
G01X125795D01*
G02X125592Y1604838I-1J202D01*
G01Y1605460D01*
G03X125542Y1605592I-200J0D01*
G02Y1608504I1664J1456D01*
G03X125592Y1608636I-150J132D01*
G01Y1610578D01*
G03X125542Y1610710I-200J0D01*
G02Y1613622I1664J1456D01*
G03X125592Y1613754I-150J132D01*
G01Y1614376D01*
G02X125795Y1614578I203J-1D01*
G37*
G36*
G01X299023D02*
X301843D01*
G02X302046Y1614376I1J-202D01*
G01Y1613754D01*
G03X302096Y1613622I200J0D01*
G02Y1610710I-1664J-1456D01*
G03X302046Y1610578I150J-132D01*
G01Y1608636D01*
G03X302096Y1608504I200J0D01*
G02Y1605592I-1664J-1456D01*
G03X302046Y1605460I150J-132D01*
G01Y1604838D01*
G02X301843Y1604636I-203J1D01*
G01X299023D01*
G02X298820Y1604838I-1J202D01*
G01Y1605460D01*
G03X298770Y1605592I-200J0D01*
G02Y1608504I1664J1456D01*
G03X298820Y1608636I-150J132D01*
G01Y1610578D01*
G03X298770Y1610710I-200J0D01*
G02Y1613622I1664J1456D01*
G03X298820Y1613754I-150J132D01*
G01Y1614376D01*
G02X299023Y1614578I203J-1D01*
G37*
G36*
G01X628157D02*
X630977D01*
G02X631180Y1614376I1J-202D01*
G01Y1613754D01*
G03X631230Y1613622I200J0D01*
G02Y1610710I-1664J-1456D01*
G03X631180Y1610578I150J-132D01*
G01Y1608636D01*
G03X631230Y1608504I200J0D01*
G02Y1605592I-1664J-1456D01*
G03X631180Y1605460I150J-132D01*
G01Y1604838D01*
G02X630977Y1604636I-203J1D01*
G01X628157D01*
G02X627954Y1604838I-1J202D01*
G01Y1605460D01*
G03X627904Y1605592I-200J0D01*
G02Y1608504I1664J1456D01*
G03X627954Y1608636I-150J132D01*
G01Y1610578D01*
G03X627904Y1610710I-200J0D01*
G02Y1613622I1664J1456D01*
G03X627954Y1613754I-150J132D01*
G01Y1614376D01*
G02X628157Y1614578I203J-1D01*
G37*
G36*
G01X662803D02*
X665623D01*
G02X665826Y1614376I1J-202D01*
G01Y1613754D01*
G03X665876Y1613622I200J0D01*
G02Y1610710I-1664J-1456D01*
G03X665826Y1610578I150J-132D01*
G01Y1608636D01*
G03X665876Y1608504I200J0D01*
G02Y1605592I-1664J-1456D01*
G03X665826Y1605460I150J-132D01*
G01Y1604838D01*
G02X665623Y1604636I-203J1D01*
G01X662803D01*
G02X662600Y1604838I-1J202D01*
G01Y1605460D01*
G03X662550Y1605592I-200J0D01*
G02Y1608504I1664J1456D01*
G03X662600Y1608636I-150J132D01*
G01Y1610578D01*
G03X662550Y1610710I-200J0D01*
G02Y1613622I1664J1456D01*
G03X662600Y1613754I-150J132D01*
G01Y1614376D01*
G02X662803Y1614578I203J-1D01*
G37*
G36*
G01X680125D02*
X682945D01*
G02X683148Y1614376I1J-202D01*
G01Y1613754D01*
G03X683198Y1613622I200J0D01*
G02Y1610710I-1664J-1456D01*
G03X683148Y1610578I150J-132D01*
G01Y1608636D01*
G03X683198Y1608504I200J0D01*
G02Y1605592I-1664J-1456D01*
G03X683148Y1605460I150J-132D01*
G01Y1604838D01*
G02X682945Y1604636I-203J1D01*
G01X680125D01*
G02X679922Y1604838I-1J202D01*
G01Y1605460D01*
G03X679872Y1605592I-200J0D01*
G02Y1608504I1664J1456D01*
G03X679922Y1608636I-150J132D01*
G01Y1610578D01*
G03X679872Y1610710I-200J0D01*
G02Y1613622I1664J1456D01*
G03X679922Y1613754I-150J132D01*
G01Y1614376D01*
G02X680125Y1614578I203J-1D01*
G37*
G36*
G01X1147763D02*
X1150583D01*
G02X1150786Y1614376I1J-202D01*
G01Y1613754D01*
G03X1150836Y1613622I200J0D01*
G02Y1610710I-1664J-1456D01*
G03X1150786Y1610578I150J-132D01*
G01Y1608636D01*
G03X1150836Y1608504I200J0D01*
G02Y1605592I-1664J-1456D01*
G03X1150786Y1605460I150J-132D01*
G01Y1604838D01*
G02X1150583Y1604636I-203J1D01*
G01X1147763D01*
G02X1147560Y1604838I-1J202D01*
G01Y1605460D01*
G03X1147510Y1605592I-200J0D01*
G02Y1608504I1664J1456D01*
G03X1147560Y1608636I-150J132D01*
G01Y1610578D01*
G03X1147510Y1610710I-200J0D01*
G02Y1613622I1664J1456D01*
G03X1147560Y1613754I-150J132D01*
G01Y1614376D01*
G02X1147763Y1614578I203J-1D01*
G37*
G36*
G01X1303669D02*
X1306489D01*
G02X1306692Y1614376I1J-202D01*
G01Y1613754D01*
G03X1306742Y1613622I200J0D01*
G02Y1610710I-1664J-1456D01*
G03X1306692Y1610578I150J-132D01*
G01Y1608636D01*
G03X1306742Y1608504I200J0D01*
G02Y1605592I-1664J-1456D01*
G03X1306692Y1605460I150J-132D01*
G01Y1604838D01*
G02X1306489Y1604636I-203J1D01*
G01X1303669D01*
G02X1303466Y1604838I-1J202D01*
G01Y1605460D01*
G03X1303416Y1605592I-200J0D01*
G02Y1608504I1664J1456D01*
G03X1303466Y1608636I-150J132D01*
G01Y1610578D01*
G03X1303416Y1610710I-200J0D01*
G02Y1613622I1664J1456D01*
G03X1303466Y1613754I-150J132D01*
G01Y1614376D01*
G02X1303669Y1614578I203J-1D01*
G37*
G36*
G01X1338315D02*
X1341135D01*
G02X1341338Y1614376I1J-202D01*
G01Y1613754D01*
G03X1341388Y1613622I200J0D01*
G02Y1610710I-1664J-1456D01*
G03X1341338Y1610578I150J-132D01*
G01Y1608636D01*
G03X1341388Y1608504I200J0D01*
G02Y1605592I-1664J-1456D01*
G03X1341338Y1605460I150J-132D01*
G01Y1604838D01*
G02X1341135Y1604636I-203J1D01*
G01X1338315D01*
G02X1338112Y1604838I-1J202D01*
G01Y1605460D01*
G03X1338062Y1605592I-200J0D01*
G02Y1608504I1664J1456D01*
G03X1338112Y1608636I-150J132D01*
G01Y1610578D01*
G03X1338062Y1610710I-200J0D01*
G02Y1613622I1664J1456D01*
G03X1338112Y1613754I-150J132D01*
G01Y1614376D01*
G02X1338315Y1614578I203J-1D01*
G37*
G36*
G01X1355637D02*
X1358457D01*
G02X1358660Y1614376I1J-202D01*
G01Y1613754D01*
G03X1358710Y1613622I200J0D01*
G02Y1610710I-1664J-1456D01*
G03X1358660Y1610578I150J-132D01*
G01Y1608636D01*
G03X1358710Y1608504I200J0D01*
G02Y1605592I-1664J-1456D01*
G03X1358660Y1605460I150J-132D01*
G01Y1604838D01*
G02X1358457Y1604636I-203J1D01*
G01X1355637D01*
G02X1355434Y1604838I-1J202D01*
G01Y1605460D01*
G03X1355384Y1605592I-200J0D01*
G02Y1608504I1664J1456D01*
G03X1355434Y1608636I-150J132D01*
G01Y1610578D01*
G03X1355384Y1610710I-200J0D01*
G02Y1613622I1664J1456D01*
G03X1355434Y1613754I-150J132D01*
G01Y1614376D01*
G02X1355637Y1614578I203J-1D01*
G37*
G36*
G01X1476897D02*
X1479717D01*
G02X1479920Y1614376I1J-202D01*
G01Y1613754D01*
G03X1479970Y1613622I200J0D01*
G02Y1610710I-1664J-1456D01*
G03X1479920Y1610578I150J-132D01*
G01Y1608636D01*
G03X1479970Y1608504I200J0D01*
G02Y1605592I-1664J-1456D01*
G03X1479920Y1605460I150J-132D01*
G01Y1604838D01*
G02X1479717Y1604636I-203J1D01*
G01X1476897D01*
G02X1476694Y1604838I-1J202D01*
G01Y1605460D01*
G03X1476644Y1605592I-200J0D01*
G02Y1608504I1664J1456D01*
G03X1476694Y1608636I-150J132D01*
G01Y1610578D01*
G03X1476644Y1610710I-200J0D01*
G02Y1613622I1664J1456D01*
G03X1476694Y1613754I-150J132D01*
G01Y1614376D01*
G02X1476897Y1614578I203J-1D01*
G37*
G36*
G01X1650125D02*
X1652945D01*
G02X1653148Y1614376I1J-202D01*
G01Y1613754D01*
G03X1653198Y1613622I200J0D01*
G02Y1610710I-1664J-1456D01*
G03X1653148Y1610578I150J-132D01*
G01Y1608636D01*
G03X1653198Y1608504I200J0D01*
G02Y1605592I-1664J-1456D01*
G03X1653148Y1605460I150J-132D01*
G01Y1604838D01*
G02X1652945Y1604636I-203J1D01*
G01X1650125D01*
G02X1649922Y1604838I-1J202D01*
G01Y1605460D01*
G03X1649872Y1605592I-200J0D01*
G02Y1608504I1664J1456D01*
G03X1649922Y1608636I-150J132D01*
G01Y1610578D01*
G03X1649872Y1610710I-200J0D01*
G02Y1613622I1664J1456D01*
G03X1649922Y1613754I-150J132D01*
G01Y1614376D01*
G02X1650125Y1614578I203J-1D01*
G37*
G36*
G01X1684771D02*
X1687591D01*
G02X1687794Y1614376I1J-202D01*
G01Y1613754D01*
G03X1687844Y1613622I200J0D01*
G02Y1610710I-1664J-1456D01*
G03X1687794Y1610578I150J-132D01*
G01Y1608636D01*
G03X1687844Y1608504I200J0D01*
G02Y1605592I-1664J-1456D01*
G03X1687794Y1605460I150J-132D01*
G01Y1604838D01*
G02X1687591Y1604636I-203J1D01*
G01X1684771D01*
G02X1684568Y1604838I-1J202D01*
G01Y1605460D01*
G03X1684518Y1605592I-200J0D01*
G02Y1608504I1664J1456D01*
G03X1684568Y1608636I-150J132D01*
G01Y1610578D01*
G03X1684518Y1610710I-200J0D01*
G02Y1613622I1664J1456D01*
G03X1684568Y1613754I-150J132D01*
G01Y1614376D01*
G02X1684771Y1614578I203J-1D01*
G37*
G36*
G01X1702093D02*
X1704913D01*
G02X1705116Y1614376I1J-202D01*
G01Y1613754D01*
G03X1705166Y1613622I200J0D01*
G02Y1610710I-1664J-1456D01*
G03X1705116Y1610578I150J-132D01*
G01Y1608636D01*
G03X1705166Y1608504I200J0D01*
G02Y1605592I-1664J-1456D01*
G03X1705116Y1605460I150J-132D01*
G01Y1604838D01*
G02X1704913Y1604636I-203J1D01*
G01X1702093D01*
G02X1701890Y1604838I-1J202D01*
G01Y1605460D01*
G03X1701840Y1605592I-200J0D01*
G02Y1608504I1664J1456D01*
G03X1701890Y1608636I-150J132D01*
G01Y1610578D01*
G03X1701840Y1610710I-200J0D01*
G02Y1613622I1664J1456D01*
G03X1701890Y1613754I-150J132D01*
G01Y1614376D01*
G02X1702093Y1614578I203J-1D01*
G37*
G36*
G01X134456Y1618908D02*
X137276D01*
G02X137478Y1618706I0J-202D01*
G01Y1618086D01*
G03X137528Y1617954I200J0D01*
G02Y1615038I-1661J-1458D01*
G03X137478Y1614906I150J-132D01*
G01Y1612968D01*
G03X137528Y1612836I200J0D01*
G02Y1609920I-1661J-1458D01*
G03X137478Y1609788I150J-132D01*
G01Y1609168D01*
G02X137276Y1608966I-202J0D01*
G01X134456D01*
G02X134254Y1609168I0J202D01*
G01Y1609788D01*
G03X134204Y1609920I-200J0D01*
G02Y1612836I1661J1458D01*
G03X134254Y1612968I-150J132D01*
G01Y1614906D01*
G03X134204Y1615038I-200J0D01*
G02Y1617954I1661J1458D01*
G03X134254Y1618086I-150J132D01*
G01Y1618706D01*
G02X134456Y1618908I202J0D01*
G37*
G36*
G01X169102D02*
X171922D01*
G02X172124Y1618706I0J-202D01*
G01Y1618086D01*
G03X172174Y1617954I200J0D01*
G02Y1615038I-1661J-1458D01*
G03X172124Y1614906I150J-132D01*
G01Y1612968D01*
G03X172174Y1612836I200J0D01*
G02Y1609920I-1661J-1458D01*
G03X172124Y1609788I150J-132D01*
G01Y1609168D01*
G02X171922Y1608966I-202J0D01*
G01X169102D01*
G02X168900Y1609168I0J202D01*
G01Y1609788D01*
G03X168850Y1609920I-200J0D01*
G02Y1612836I1661J1458D01*
G03X168900Y1612968I-150J132D01*
G01Y1614906D01*
G03X168850Y1615038I-200J0D01*
G02Y1617954I1661J1458D01*
G03X168900Y1618086I-150J132D01*
G01Y1618706D01*
G02X169102Y1618908I202J0D01*
G37*
G36*
G01X307684D02*
X310504D01*
G02X310706Y1618706I0J-202D01*
G01Y1618086D01*
G03X310756Y1617954I200J0D01*
G02Y1615038I-1661J-1458D01*
G03X310706Y1614906I150J-132D01*
G01Y1612968D01*
G03X310756Y1612836I200J0D01*
G02Y1609920I-1661J-1458D01*
G03X310706Y1609788I150J-132D01*
G01Y1609168D01*
G02X310504Y1608966I-202J0D01*
G01X307684D01*
G02X307482Y1609168I0J202D01*
G01Y1609788D01*
G03X307432Y1609920I-200J0D01*
G02Y1612836I1661J1458D01*
G03X307482Y1612968I-150J132D01*
G01Y1614906D01*
G03X307432Y1615038I-200J0D01*
G02Y1617954I1661J1458D01*
G03X307482Y1618086I-150J132D01*
G01Y1618706D01*
G02X307684Y1618908I202J0D01*
G37*
G36*
G01X342330D02*
X345150D01*
G02X345352Y1618706I0J-202D01*
G01Y1618086D01*
G03X345402Y1617954I200J0D01*
G02Y1615038I-1661J-1458D01*
G03X345352Y1614906I150J-132D01*
G01Y1612968D01*
G03X345402Y1612836I200J0D01*
G02Y1609920I-1661J-1458D01*
G03X345352Y1609788I150J-132D01*
G01Y1609168D01*
G02X345150Y1608966I-202J0D01*
G01X342330D01*
G02X342128Y1609168I0J202D01*
G01Y1609788D01*
G03X342078Y1609920I-200J0D01*
G02Y1612836I1661J1458D01*
G03X342128Y1612968I-150J132D01*
G01Y1614906D01*
G03X342078Y1615038I-200J0D01*
G02Y1617954I1661J1458D01*
G03X342128Y1618086I-150J132D01*
G01Y1618706D01*
G02X342330Y1618908I202J0D01*
G37*
G36*
G01X636818D02*
X639638D01*
G02X639840Y1618706I0J-202D01*
G01Y1618086D01*
G03X639890Y1617954I200J0D01*
G02Y1615038I-1661J-1458D01*
G03X639840Y1614906I150J-132D01*
G01Y1612968D01*
G03X639890Y1612836I200J0D01*
G02Y1609920I-1661J-1458D01*
G03X639840Y1609788I150J-132D01*
G01Y1609168D01*
G02X639638Y1608966I-202J0D01*
G01X636818D01*
G02X636616Y1609168I0J202D01*
G01Y1609788D01*
G03X636566Y1609920I-200J0D01*
G02Y1612836I1661J1458D01*
G03X636616Y1612968I-150J132D01*
G01Y1614906D01*
G03X636566Y1615038I-200J0D01*
G02Y1617954I1661J1458D01*
G03X636616Y1618086I-150J132D01*
G01Y1618706D01*
G02X636818Y1618908I202J0D01*
G37*
G36*
G01X671464D02*
X674284D01*
G02X674486Y1618706I0J-202D01*
G01Y1618086D01*
G03X674536Y1617954I200J0D01*
G02Y1615038I-1661J-1458D01*
G03X674486Y1614906I150J-132D01*
G01Y1612968D01*
G03X674536Y1612836I200J0D01*
G02Y1609920I-1661J-1458D01*
G03X674486Y1609788I150J-132D01*
G01Y1609168D01*
G02X674284Y1608966I-202J0D01*
G01X671464D01*
G02X671262Y1609168I0J202D01*
G01Y1609788D01*
G03X671212Y1609920I-200J0D01*
G02Y1612836I1661J1458D01*
G03X671262Y1612968I-150J132D01*
G01Y1614906D01*
G03X671212Y1615038I-200J0D01*
G02Y1617954I1661J1458D01*
G03X671262Y1618086I-150J132D01*
G01Y1618706D01*
G02X671464Y1618908I202J0D01*
G37*
G36*
G01X1156424D02*
X1159244D01*
G02X1159446Y1618706I0J-202D01*
G01Y1618086D01*
G03X1159496Y1617954I200J0D01*
G02Y1615038I-1661J-1458D01*
G03X1159446Y1614906I150J-132D01*
G01Y1612968D01*
G03X1159496Y1612836I200J0D01*
G02Y1609920I-1661J-1458D01*
G03X1159446Y1609788I150J-132D01*
G01Y1609168D01*
G02X1159244Y1608966I-202J0D01*
G01X1156424D01*
G02X1156222Y1609168I0J202D01*
G01Y1609788D01*
G03X1156172Y1609920I-200J0D01*
G02Y1612836I1661J1458D01*
G03X1156222Y1612968I-150J132D01*
G01Y1614906D01*
G03X1156172Y1615038I-200J0D01*
G02Y1617954I1661J1458D01*
G03X1156222Y1618086I-150J132D01*
G01Y1618706D01*
G02X1156424Y1618908I202J0D01*
G37*
G36*
G01X1191070D02*
X1193890D01*
G02X1194092Y1618706I0J-202D01*
G01Y1618086D01*
G03X1194142Y1617954I200J0D01*
G02Y1615038I-1661J-1458D01*
G03X1194092Y1614906I150J-132D01*
G01Y1612968D01*
G03X1194142Y1612836I200J0D01*
G02Y1609920I-1661J-1458D01*
G03X1194092Y1609788I150J-132D01*
G01Y1609168D01*
G02X1193890Y1608966I-202J0D01*
G01X1191070D01*
G02X1190868Y1609168I0J202D01*
G01Y1609788D01*
G03X1190818Y1609920I-200J0D01*
G02Y1612836I1661J1458D01*
G03X1190868Y1612968I-150J132D01*
G01Y1614906D01*
G03X1190818Y1615038I-200J0D01*
G02Y1617954I1661J1458D01*
G03X1190868Y1618086I-150J132D01*
G01Y1618706D01*
G02X1191070Y1618908I202J0D01*
G37*
G36*
G01X1312330D02*
X1315150D01*
G02X1315352Y1618706I0J-202D01*
G01Y1618086D01*
G03X1315402Y1617954I200J0D01*
G02Y1615038I-1661J-1458D01*
G03X1315352Y1614906I150J-132D01*
G01Y1612968D01*
G03X1315402Y1612836I200J0D01*
G02Y1609920I-1661J-1458D01*
G03X1315352Y1609788I150J-132D01*
G01Y1609168D01*
G02X1315150Y1608966I-202J0D01*
G01X1312330D01*
G02X1312128Y1609168I0J202D01*
G01Y1609788D01*
G03X1312078Y1609920I-200J0D01*
G02Y1612836I1661J1458D01*
G03X1312128Y1612968I-150J132D01*
G01Y1614906D01*
G03X1312078Y1615038I-200J0D01*
G02Y1617954I1661J1458D01*
G03X1312128Y1618086I-150J132D01*
G01Y1618706D01*
G02X1312330Y1618908I202J0D01*
G37*
G36*
G01X1346976D02*
X1349796D01*
G02X1349998Y1618706I0J-202D01*
G01Y1618086D01*
G03X1350048Y1617954I200J0D01*
G02Y1615038I-1661J-1458D01*
G03X1349998Y1614906I150J-132D01*
G01Y1612968D01*
G03X1350048Y1612836I200J0D01*
G02Y1609920I-1661J-1458D01*
G03X1349998Y1609788I150J-132D01*
G01Y1609168D01*
G02X1349796Y1608966I-202J0D01*
G01X1346976D01*
G02X1346774Y1609168I0J202D01*
G01Y1609788D01*
G03X1346724Y1609920I-200J0D01*
G02Y1612836I1661J1458D01*
G03X1346774Y1612968I-150J132D01*
G01Y1614906D01*
G03X1346724Y1615038I-200J0D01*
G02Y1617954I1661J1458D01*
G03X1346774Y1618086I-150J132D01*
G01Y1618706D01*
G02X1346976Y1618908I202J0D01*
G37*
G36*
G01X1658786D02*
X1661606D01*
G02X1661808Y1618706I0J-202D01*
G01Y1618086D01*
G03X1661858Y1617954I200J0D01*
G02Y1615038I-1661J-1458D01*
G03X1661808Y1614906I150J-132D01*
G01Y1612968D01*
G03X1661858Y1612836I200J0D01*
G02Y1609920I-1661J-1458D01*
G03X1661808Y1609788I150J-132D01*
G01Y1609168D01*
G02X1661606Y1608966I-202J0D01*
G01X1658786D01*
G02X1658584Y1609168I0J202D01*
G01Y1609788D01*
G03X1658534Y1609920I-200J0D01*
G02Y1612836I1661J1458D01*
G03X1658584Y1612968I-150J132D01*
G01Y1614906D01*
G03X1658534Y1615038I-200J0D01*
G02Y1617954I1661J1458D01*
G03X1658584Y1618086I-150J132D01*
G01Y1618706D01*
G02X1658786Y1618908I202J0D01*
G37*
G36*
G01X1693432D02*
X1696252D01*
G02X1696454Y1618706I0J-202D01*
G01Y1618086D01*
G03X1696504Y1617954I200J0D01*
G02Y1615038I-1661J-1458D01*
G03X1696454Y1614906I150J-132D01*
G01Y1612968D01*
G03X1696504Y1612836I200J0D01*
G02Y1609920I-1661J-1458D01*
G03X1696454Y1609788I150J-132D01*
G01Y1609168D01*
G02X1696252Y1608966I-202J0D01*
G01X1693432D01*
G02X1693230Y1609168I0J202D01*
G01Y1609788D01*
G03X1693180Y1609920I-200J0D01*
G02Y1612836I1661J1458D01*
G03X1693230Y1612968I-150J132D01*
G01Y1614906D01*
G03X1693180Y1615038I-200J0D01*
G02Y1617954I1661J1458D01*
G03X1693230Y1618086I-150J132D01*
G01Y1618706D01*
G02X1693432Y1618908I202J0D01*
G37*
G36*
G01X117133D02*
X119953D01*
G02X120156Y1618706I1J-202D01*
G01Y1618084D01*
G03X120206Y1617952I200J0D01*
G02Y1615040I-1664J-1456D01*
G03X120156Y1614908I150J-132D01*
G01Y1612966D01*
G03X120206Y1612834I200J0D01*
G02Y1609922I-1664J-1456D01*
G03X120156Y1609790I150J-132D01*
G01Y1609168D01*
G02X119953Y1608966I-203J1D01*
G01X117133D01*
G02X116930Y1609168I-1J202D01*
G01Y1609790D01*
G03X116880Y1609922I-200J0D01*
G02Y1612834I1664J1456D01*
G03X116930Y1612966I-150J132D01*
G01Y1614908D01*
G03X116880Y1615040I-200J0D01*
G02Y1617952I1664J1456D01*
G03X116930Y1618084I-150J132D01*
G01Y1618706D01*
G02X117133Y1618908I203J-1D01*
G37*
G36*
G01X151779D02*
X154599D01*
G02X154802Y1618706I1J-202D01*
G01Y1618084D01*
G03X154852Y1617952I200J0D01*
G02Y1615040I-1664J-1456D01*
G03X154802Y1614908I150J-132D01*
G01Y1612966D01*
G03X154852Y1612834I200J0D01*
G02Y1609922I-1664J-1456D01*
G03X154802Y1609790I150J-132D01*
G01Y1609168D01*
G02X154599Y1608966I-203J1D01*
G01X151779D01*
G02X151576Y1609168I-1J202D01*
G01Y1609790D01*
G03X151526Y1609922I-200J0D01*
G02Y1612834I1664J1456D01*
G03X151576Y1612966I-150J132D01*
G01Y1614908D01*
G03X151526Y1615040I-200J0D01*
G02Y1617952I1664J1456D01*
G03X151576Y1618084I-150J132D01*
G01Y1618706D01*
G02X151779Y1618908I203J-1D01*
G37*
G36*
G01X186425D02*
X189245D01*
G02X189448Y1618706I1J-202D01*
G01Y1618084D01*
G03X189498Y1617952I200J0D01*
G02Y1615040I-1664J-1456D01*
G03X189448Y1614908I150J-132D01*
G01Y1612966D01*
G03X189498Y1612834I200J0D01*
G02Y1609922I-1664J-1456D01*
G03X189448Y1609790I150J-132D01*
G01Y1609168D01*
G02X189245Y1608966I-203J1D01*
G01X186425D01*
G02X186222Y1609168I-1J202D01*
G01Y1609790D01*
G03X186172Y1609922I-200J0D01*
G02Y1612834I1664J1456D01*
G03X186222Y1612966I-150J132D01*
G01Y1614908D01*
G03X186172Y1615040I-200J0D01*
G02Y1617952I1664J1456D01*
G03X186222Y1618084I-150J132D01*
G01Y1618706D01*
G02X186425Y1618908I203J-1D01*
G37*
G36*
G01X290361D02*
X293181D01*
G02X293384Y1618706I1J-202D01*
G01Y1618084D01*
G03X293434Y1617952I200J0D01*
G02Y1615040I-1664J-1456D01*
G03X293384Y1614908I150J-132D01*
G01Y1612966D01*
G03X293434Y1612834I200J0D01*
G02Y1609922I-1664J-1456D01*
G03X293384Y1609790I150J-132D01*
G01Y1609168D01*
G02X293181Y1608966I-203J1D01*
G01X290361D01*
G02X290158Y1609168I-1J202D01*
G01Y1609790D01*
G03X290108Y1609922I-200J0D01*
G02Y1612834I1664J1456D01*
G03X290158Y1612966I-150J132D01*
G01Y1614908D01*
G03X290108Y1615040I-200J0D01*
G02Y1617952I1664J1456D01*
G03X290158Y1618084I-150J132D01*
G01Y1618706D01*
G02X290361Y1618908I203J-1D01*
G37*
G36*
G01X325007D02*
X327827D01*
G02X328030Y1618706I1J-202D01*
G01Y1618084D01*
G03X328080Y1617952I200J0D01*
G02Y1615040I-1664J-1456D01*
G03X328030Y1614908I150J-132D01*
G01Y1612966D01*
G03X328080Y1612834I200J0D01*
G02Y1609922I-1664J-1456D01*
G03X328030Y1609790I150J-132D01*
G01Y1609168D01*
G02X327827Y1608966I-203J1D01*
G01X325007D01*
G02X324804Y1609168I-1J202D01*
G01Y1609790D01*
G03X324754Y1609922I-200J0D01*
G02Y1612834I1664J1456D01*
G03X324804Y1612966I-150J132D01*
G01Y1614908D01*
G03X324754Y1615040I-200J0D01*
G02Y1617952I1664J1456D01*
G03X324804Y1618084I-150J132D01*
G01Y1618706D01*
G02X325007Y1618908I203J-1D01*
G37*
G36*
G01X359653D02*
X362473D01*
G02X362676Y1618706I1J-202D01*
G01Y1618084D01*
G03X362726Y1617952I200J0D01*
G02Y1615040I-1664J-1456D01*
G03X362676Y1614908I150J-132D01*
G01Y1612966D01*
G03X362726Y1612834I200J0D01*
G02Y1609922I-1664J-1456D01*
G03X362676Y1609790I150J-132D01*
G01Y1609168D01*
G02X362473Y1608966I-203J1D01*
G01X359653D01*
G02X359450Y1609168I-1J202D01*
G01Y1609790D01*
G03X359400Y1609922I-200J0D01*
G02Y1612834I1664J1456D01*
G03X359450Y1612966I-150J132D01*
G01Y1614908D01*
G03X359400Y1615040I-200J0D01*
G02Y1617952I1664J1456D01*
G03X359450Y1618084I-150J132D01*
G01Y1618706D01*
G02X359653Y1618908I203J-1D01*
G37*
G36*
G01X515559D02*
X518379D01*
G02X518582Y1618706I1J-202D01*
G01Y1618084D01*
G03X518632Y1617952I200J0D01*
G02Y1615040I-1664J-1456D01*
G03X518582Y1614908I150J-132D01*
G01Y1612966D01*
G03X518632Y1612834I200J0D01*
G02Y1609922I-1664J-1456D01*
G03X518582Y1609790I150J-132D01*
G01Y1609168D01*
G02X518379Y1608966I-203J1D01*
G01X515559D01*
G02X515356Y1609168I-1J202D01*
G01Y1609790D01*
G03X515306Y1609922I-200J0D01*
G02Y1612834I1664J1456D01*
G03X515356Y1612966I-150J132D01*
G01Y1614908D01*
G03X515306Y1615040I-200J0D01*
G02Y1617952I1664J1456D01*
G03X515356Y1618084I-150J132D01*
G01Y1618706D01*
G02X515559Y1618908I203J-1D01*
G37*
G36*
G01X654141D02*
X656961D01*
G02X657164Y1618706I1J-202D01*
G01Y1618084D01*
G03X657214Y1617952I200J0D01*
G02Y1615040I-1664J-1456D01*
G03X657164Y1614908I150J-132D01*
G01Y1612966D01*
G03X657214Y1612834I200J0D01*
G02Y1609922I-1664J-1456D01*
G03X657164Y1609790I150J-132D01*
G01Y1609168D01*
G02X656961Y1608966I-203J1D01*
G01X654141D01*
G02X653938Y1609168I-1J202D01*
G01Y1609790D01*
G03X653888Y1609922I-200J0D01*
G02Y1612834I1664J1456D01*
G03X653938Y1612966I-150J132D01*
G01Y1614908D01*
G03X653888Y1615040I-200J0D01*
G02Y1617952I1664J1456D01*
G03X653938Y1618084I-150J132D01*
G01Y1618706D01*
G02X654141Y1618908I203J-1D01*
G37*
G36*
G01X688787D02*
X691607D01*
G02X691810Y1618706I1J-202D01*
G01Y1618084D01*
G03X691860Y1617952I200J0D01*
G02Y1615040I-1664J-1456D01*
G03X691810Y1614908I150J-132D01*
G01Y1612966D01*
G03X691860Y1612834I200J0D01*
G02Y1609922I-1664J-1456D01*
G03X691810Y1609790I150J-132D01*
G01Y1609168D01*
G02X691607Y1608966I-203J1D01*
G01X688787D01*
G02X688584Y1609168I-1J202D01*
G01Y1609790D01*
G03X688534Y1609922I-200J0D01*
G02Y1612834I1664J1456D01*
G03X688584Y1612966I-150J132D01*
G01Y1614908D01*
G03X688534Y1615040I-200J0D01*
G02Y1617952I1664J1456D01*
G03X688584Y1618084I-150J132D01*
G01Y1618706D01*
G02X688787Y1618908I203J-1D01*
G37*
G36*
G01X1139101D02*
X1141921D01*
G02X1142124Y1618706I1J-202D01*
G01Y1618084D01*
G03X1142174Y1617952I200J0D01*
G02Y1615040I-1664J-1456D01*
G03X1142124Y1614908I150J-132D01*
G01Y1612966D01*
G03X1142174Y1612834I200J0D01*
G02Y1609922I-1664J-1456D01*
G03X1142124Y1609790I150J-132D01*
G01Y1609168D01*
G02X1141921Y1608966I-203J1D01*
G01X1139101D01*
G02X1138898Y1609168I-1J202D01*
G01Y1609790D01*
G03X1138848Y1609922I-200J0D01*
G02Y1612834I1664J1456D01*
G03X1138898Y1612966I-150J132D01*
G01Y1614908D01*
G03X1138848Y1615040I-200J0D01*
G02Y1617952I1664J1456D01*
G03X1138898Y1618084I-150J132D01*
G01Y1618706D01*
G02X1139101Y1618908I203J-1D01*
G37*
G36*
G01X1173747D02*
X1176567D01*
G02X1176770Y1618706I1J-202D01*
G01Y1618084D01*
G03X1176820Y1617952I200J0D01*
G02Y1615040I-1664J-1456D01*
G03X1176770Y1614908I150J-132D01*
G01Y1612966D01*
G03X1176820Y1612834I200J0D01*
G02Y1609922I-1664J-1456D01*
G03X1176770Y1609790I150J-132D01*
G01Y1609168D01*
G02X1176567Y1608966I-203J1D01*
G01X1173747D01*
G02X1173544Y1609168I-1J202D01*
G01Y1609790D01*
G03X1173494Y1609922I-200J0D01*
G02Y1612834I1664J1456D01*
G03X1173544Y1612966I-150J132D01*
G01Y1614908D01*
G03X1173494Y1615040I-200J0D01*
G02Y1617952I1664J1456D01*
G03X1173544Y1618084I-150J132D01*
G01Y1618706D01*
G02X1173747Y1618908I203J-1D01*
G37*
G36*
G01X1329653D02*
X1332473D01*
G02X1332676Y1618706I1J-202D01*
G01Y1618084D01*
G03X1332726Y1617952I200J0D01*
G02Y1615040I-1664J-1456D01*
G03X1332676Y1614908I150J-132D01*
G01Y1612966D01*
G03X1332726Y1612834I200J0D01*
G02Y1609922I-1664J-1456D01*
G03X1332676Y1609790I150J-132D01*
G01Y1609168D01*
G02X1332473Y1608966I-203J1D01*
G01X1329653D01*
G02X1329450Y1609168I-1J202D01*
G01Y1609790D01*
G03X1329400Y1609922I-200J0D01*
G02Y1612834I1664J1456D01*
G03X1329450Y1612966I-150J132D01*
G01Y1614908D01*
G03X1329400Y1615040I-200J0D01*
G02Y1617952I1664J1456D01*
G03X1329450Y1618084I-150J132D01*
G01Y1618706D01*
G02X1329653Y1618908I203J-1D01*
G37*
G36*
G01X1364299D02*
X1367119D01*
G02X1367322Y1618706I1J-202D01*
G01Y1618084D01*
G03X1367372Y1617952I200J0D01*
G02Y1615040I-1664J-1456D01*
G03X1367322Y1614908I150J-132D01*
G01Y1612966D01*
G03X1367372Y1612834I200J0D01*
G02Y1609922I-1664J-1456D01*
G03X1367322Y1609790I150J-132D01*
G01Y1609168D01*
G02X1367119Y1608966I-203J1D01*
G01X1364299D01*
G02X1364096Y1609168I-1J202D01*
G01Y1609790D01*
G03X1364046Y1609922I-200J0D01*
G02Y1612834I1664J1456D01*
G03X1364096Y1612966I-150J132D01*
G01Y1614908D01*
G03X1364046Y1615040I-200J0D01*
G02Y1617952I1664J1456D01*
G03X1364096Y1618084I-150J132D01*
G01Y1618706D01*
G02X1364299Y1618908I203J-1D01*
G37*
G36*
G01X1676109D02*
X1678929D01*
G02X1679132Y1618706I1J-202D01*
G01Y1618084D01*
G03X1679182Y1617952I200J0D01*
G02Y1615040I-1664J-1456D01*
G03X1679132Y1614908I150J-132D01*
G01Y1612966D01*
G03X1679182Y1612834I200J0D01*
G02Y1609922I-1664J-1456D01*
G03X1679132Y1609790I150J-132D01*
G01Y1609168D01*
G02X1678929Y1608966I-203J1D01*
G01X1676109D01*
G02X1675906Y1609168I-1J202D01*
G01Y1609790D01*
G03X1675856Y1609922I-200J0D01*
G02Y1612834I1664J1456D01*
G03X1675906Y1612966I-150J132D01*
G01Y1614908D01*
G03X1675856Y1615040I-200J0D01*
G02Y1617952I1664J1456D01*
G03X1675906Y1618084I-150J132D01*
G01Y1618706D01*
G02X1676109Y1618908I203J-1D01*
G37*
G36*
G01X1710755D02*
X1713575D01*
G02X1713778Y1618706I1J-202D01*
G01Y1618084D01*
G03X1713828Y1617952I200J0D01*
G02Y1615040I-1664J-1456D01*
G03X1713778Y1614908I150J-132D01*
G01Y1612966D01*
G03X1713828Y1612834I200J0D01*
G02Y1609922I-1664J-1456D01*
G03X1713778Y1609790I150J-132D01*
G01Y1609168D01*
G02X1713575Y1608966I-203J1D01*
G01X1710755D01*
G02X1710552Y1609168I-1J202D01*
G01Y1609790D01*
G03X1710502Y1609922I-200J0D01*
G02Y1612834I1664J1456D01*
G03X1710552Y1612966I-150J132D01*
G01Y1614908D01*
G03X1710502Y1615040I-200J0D01*
G02Y1617952I1664J1456D01*
G03X1710552Y1618084I-150J132D01*
G01Y1618706D01*
G02X1710755Y1618908I203J-1D01*
G37*
G36*
G01X1522570Y1409998D02*
X1525970D01*
G02Y1406992I0J-1503D01*
G01X1522570D01*
G02Y1409998I0J1503D01*
G37*
G36*
G01X1559290Y1349690D02*
X1562690D01*
G02Y1346684I0J-1503D01*
G01X1559290D01*
G02Y1349690I0J1503D01*
G37*
G36*
G01X1522570Y1385800D02*
X1525970D01*
G02Y1382794I0J-1503D01*
G01X1522570D01*
G02Y1385800I0J1503D01*
G37*
G36*
G01Y1373888D02*
X1525970D01*
G02Y1370882I0J-1503D01*
G01X1522570D01*
G02Y1373888I0J1503D01*
G37*
G36*
G01Y1398086D02*
X1525970D01*
G02Y1395080I0J-1503D01*
G01X1522570D01*
G02Y1398086I0J1503D01*
G37*
G36*
G01X1510330Y1373888D02*
X1513730D01*
G02Y1370882I0J-1503D01*
G01X1510330D01*
G02Y1373888I0J1503D01*
G37*
G36*
G01X1547050Y1361602D02*
X1550450D01*
G02Y1358596I0J-1503D01*
G01X1547050D01*
G02Y1361602I0J1503D01*
G37*
G36*
G01X1534810D02*
X1538210D01*
G02Y1358596I0J-1503D01*
G01X1534810D01*
G02Y1361602I0J1503D01*
G37*
G36*
G01X1547050Y1349690D02*
X1550450D01*
G02Y1346684I0J-1503D01*
G01X1547050D01*
G02Y1349690I0J1503D01*
G37*
G36*
G01X1534810D02*
X1538210D01*
G02Y1346684I0J-1503D01*
G01X1534810D01*
G02Y1349690I0J1503D01*
G37*
G36*
G01X241623Y1373888D02*
X245023D01*
G02Y1370882I0J-1503D01*
G01X241623D01*
G02Y1373888I0J1503D01*
G37*
G36*
G01Y1361602D02*
X245023D01*
G02Y1358596I0J-1503D01*
G01X241623D01*
G02Y1361602I0J1503D01*
G37*
G36*
G01X1485850Y1409998D02*
X1489250D01*
G02Y1406992I0J-1503D01*
G01X1485850D01*
G02Y1409998I0J1503D01*
G37*
G36*
G01X1510330Y1349690D02*
X1513730D01*
G02Y1346684I0J-1503D01*
G01X1510330D01*
G02Y1349690I0J1503D01*
G37*
G36*
G01X364023Y1398086D02*
X367423D01*
G02Y1395080I0J-1503D01*
G01X364023D01*
G02Y1398086I0J1503D01*
G37*
G36*
G01X1485850Y1385800D02*
X1489250D01*
G02Y1382794I0J-1503D01*
G01X1485850D01*
G02Y1385800I0J1503D01*
G37*
G36*
G01X1473610D02*
X1477010D01*
G02Y1382794I0J-1503D01*
G01X1473610D01*
G02Y1385800I0J1503D01*
G37*
G36*
G01Y1361602D02*
X1477010D01*
G02Y1358596I0J-1503D01*
G01X1473610D01*
G02Y1361602I0J1503D01*
G37*
G36*
G01Y1349690D02*
X1477010D01*
G02Y1346684I0J-1503D01*
G01X1473610D01*
G02Y1349690I0J1503D01*
G37*
G36*
G01X1461370Y1385800D02*
X1464770D01*
G02Y1382794I0J-1503D01*
G01X1461370D01*
G02Y1385800I0J1503D01*
G37*
G36*
G01Y1373888D02*
X1464770D01*
G02Y1370882I0J-1503D01*
G01X1461370D01*
G02Y1373888I0J1503D01*
G37*
G36*
G01Y1361602D02*
X1464770D01*
G02Y1358596I0J-1503D01*
G01X1461370D01*
G02Y1361602I0J1503D01*
G37*
G36*
G01Y1349690D02*
X1464770D01*
G02Y1346684I0J-1503D01*
G01X1461370D01*
G02Y1349690I0J1503D01*
G37*
G36*
G01X1485850Y1373888D02*
X1489250D01*
G02Y1370882I0J-1503D01*
G01X1485850D01*
G02Y1373888I0J1503D01*
G37*
G36*
G01X1498090Y1361602D02*
X1501490D01*
G02Y1358596I0J-1503D01*
G01X1498090D01*
G02Y1361602I0J1503D01*
G37*
G36*
G01X1485850D02*
X1489250D01*
G02Y1358596I0J-1503D01*
G01X1485850D01*
G02Y1361602I0J1503D01*
G37*
G36*
G01X253863Y1409998D02*
X257263D01*
G02Y1406992I0J-1503D01*
G01X253863D01*
G02Y1409998I0J1503D01*
G37*
G36*
G01X266103Y1373888D02*
X269503D01*
G02Y1370882I0J-1503D01*
G01X266103D01*
G02Y1373888I0J1503D01*
G37*
G36*
G01X290583Y1361602D02*
X293983D01*
G02Y1358596I0J-1503D01*
G01X290583D01*
G02Y1361602I0J1503D01*
G37*
G36*
G01X327303Y1349690D02*
X330703D01*
G02Y1346684I0J-1503D01*
G01X327303D01*
G02Y1349690I0J1503D01*
G37*
G36*
G01X290583Y1385800D02*
X293983D01*
G02Y1382794I0J-1503D01*
G01X290583D01*
G02Y1385800I0J1503D01*
G37*
G36*
G01Y1409998D02*
X293983D01*
G02Y1406992I0J-1503D01*
G01X290583D01*
G02Y1409998I0J1503D01*
G37*
G36*
G01X253863Y1398086D02*
X257263D01*
G02Y1395080I0J-1503D01*
G01X253863D01*
G02Y1398086I0J1503D01*
G37*
G36*
G01X364023Y1361602D02*
X367423D01*
G02Y1358596I0J-1503D01*
G01X364023D01*
G02Y1361602I0J1503D01*
G37*
G36*
G01X339543Y1349690D02*
X342943D01*
G02Y1346684I0J-1503D01*
G01X339543D01*
G02Y1349690I0J1503D01*
G37*
G36*
G01X241623D02*
X245023D01*
G02Y1346684I0J-1503D01*
G01X241623D01*
G02Y1349690I0J1503D01*
G37*
G36*
G01X339543Y1361602D02*
X342943D01*
G02Y1358596I0J-1503D01*
G01X339543D01*
G02Y1361602I0J1503D01*
G37*
G36*
G01X302823Y1409998D02*
X306223D01*
G02Y1406992I0J-1503D01*
G01X302823D01*
G02Y1409998I0J1503D01*
G37*
G36*
G01X364023Y1385800D02*
X367423D01*
G02Y1382794I0J-1503D01*
G01X364023D01*
G02Y1385800I0J1503D01*
G37*
G36*
G01X290583Y1398086D02*
X293983D01*
G02Y1395080I0J-1503D01*
G01X290583D01*
G02Y1398086I0J1503D01*
G37*
G36*
G01X112832D02*
X116232D01*
G02Y1395080I0J-1503D01*
G01X112832D01*
G02Y1398086I0J1503D01*
G37*
G36*
G01X364023Y1373888D02*
X367423D01*
G02Y1370882I0J-1503D01*
G01X364023D01*
G02Y1373888I0J1503D01*
G37*
G36*
G01X302823Y1361602D02*
X306223D01*
G02Y1358596I0J-1503D01*
G01X302823D01*
G02Y1361602I0J1503D01*
G37*
G36*
G01X1534810Y1409998D02*
X1538210D01*
G02Y1406992I0J-1503D01*
G01X1534810D01*
G02Y1409998I0J1503D01*
G37*
G36*
G01X1510330Y1385800D02*
X1513730D01*
G02Y1382794I0J-1503D01*
G01X1510330D01*
G02Y1385800I0J1503D01*
G37*
G36*
G01X1534810Y1398086D02*
X1538210D01*
G02Y1395080I0J-1503D01*
G01X1534810D01*
G02Y1398086I0J1503D01*
G37*
G36*
G01X302823Y1349690D02*
X306223D01*
G02Y1346684I0J-1503D01*
G01X302823D01*
G02Y1349690I0J1503D01*
G37*
G36*
G01X88352Y1373888D02*
X91752D01*
G02Y1370882I0J-1503D01*
G01X88352D01*
G02Y1373888I0J1503D01*
G37*
G36*
G01X339543Y1385800D02*
X342943D01*
G02Y1382794I0J-1503D01*
G01X339543D01*
G02Y1385800I0J1503D01*
G37*
G36*
G01X327303Y1373888D02*
X330703D01*
G02Y1370882I0J-1503D01*
G01X327303D01*
G02Y1373888I0J1503D01*
G37*
G36*
G01Y1409998D02*
X330703D01*
G02Y1406992I0J-1503D01*
G01X327303D01*
G02Y1409998I0J1503D01*
G37*
G36*
G01X278343Y1398086D02*
X281743D01*
G02Y1395080I0J-1503D01*
G01X278343D01*
G02Y1398086I0J1503D01*
G37*
G36*
G01X351783Y1349690D02*
X355183D01*
G02Y1346684I0J-1503D01*
G01X351783D01*
G02Y1349690I0J1503D01*
G37*
G36*
G01X186272Y1385800D02*
X189672D01*
G02Y1382794I0J-1503D01*
G01X186272D01*
G02Y1385800I0J1503D01*
G37*
G36*
G01Y1373888D02*
X189672D01*
G02Y1370882I0J-1503D01*
G01X186272D01*
G02Y1373888I0J1503D01*
G37*
G36*
G01X315063Y1361602D02*
X318463D01*
G02Y1358596I0J-1503D01*
G01X315063D01*
G02Y1361602I0J1503D01*
G37*
G36*
G01X327303D02*
X330703D01*
G02Y1358596I0J-1503D01*
G01X327303D01*
G02Y1361602I0J1503D01*
G37*
G36*
G01X315063Y1349690D02*
X318463D01*
G02Y1346684I0J-1503D01*
G01X315063D01*
G02Y1349690I0J1503D01*
G37*
G36*
G01X174032Y1398086D02*
X177432D01*
G02Y1395080I0J-1503D01*
G01X174032D01*
G02Y1398086I0J1503D01*
G37*
G36*
G01X266103Y1349690D02*
X269503D01*
G02Y1346684I0J-1503D01*
G01X266103D01*
G02Y1349690I0J1503D01*
G37*
G36*
G01X1054713Y1361602D02*
X1058113D01*
G02Y1358596I0J-1503D01*
G01X1054713D01*
G02Y1361602I0J1503D01*
G37*
G36*
G01Y1349690D02*
X1058113D01*
G02Y1346684I0J-1503D01*
G01X1054713D01*
G02Y1349690I0J1503D01*
G37*
G36*
G01Y1385800D02*
X1058113D01*
G02Y1382794I0J-1503D01*
G01X1054713D01*
G02Y1385800I0J1503D01*
G37*
G36*
G01Y1373888D02*
X1058113D01*
G02Y1370882I0J-1503D01*
G01X1054713D01*
G02Y1373888I0J1503D01*
G37*
G36*
G01X1177113Y1409998D02*
X1180513D01*
G02Y1406992I0J-1503D01*
G01X1177113D01*
G02Y1409998I0J1503D01*
G37*
G36*
G01Y1398086D02*
X1180513D01*
G02Y1395080I0J-1503D01*
G01X1177113D01*
G02Y1398086I0J1503D01*
G37*
G36*
G01Y1373888D02*
X1180513D01*
G02Y1370882I0J-1503D01*
G01X1177113D01*
G02Y1373888I0J1503D01*
G37*
G36*
G01Y1385800D02*
X1180513D01*
G02Y1382794I0J-1503D01*
G01X1177113D01*
G02Y1385800I0J1503D01*
G37*
G36*
G01Y1361602D02*
X1180513D01*
G02Y1358596I0J-1503D01*
G01X1177113D01*
G02Y1361602I0J1503D01*
G37*
G36*
G01Y1349690D02*
X1180513D01*
G02Y1346684I0J-1503D01*
G01X1177113D01*
G02Y1349690I0J1503D01*
G37*
G36*
G01X1164873Y1409998D02*
X1168273D01*
G02Y1406992I0J-1503D01*
G01X1164873D01*
G02Y1409998I0J1503D01*
G37*
G36*
G01Y1398086D02*
X1168273D01*
G02Y1395080I0J-1503D01*
G01X1164873D01*
G02Y1398086I0J1503D01*
G37*
G36*
G01Y1385800D02*
X1168273D01*
G02Y1382794I0J-1503D01*
G01X1164873D01*
G02Y1385800I0J1503D01*
G37*
G36*
G01Y1373888D02*
X1168273D01*
G02Y1370882I0J-1503D01*
G01X1164873D01*
G02Y1373888I0J1503D01*
G37*
G36*
G01Y1361602D02*
X1168273D01*
G02Y1358596I0J-1503D01*
G01X1164873D01*
G02Y1361602I0J1503D01*
G37*
G36*
G01Y1349690D02*
X1168273D01*
G02Y1346684I0J-1503D01*
G01X1164873D01*
G02Y1349690I0J1503D01*
G37*
G36*
G01X1152633Y1409998D02*
X1156033D01*
G02Y1406992I0J-1503D01*
G01X1152633D01*
G02Y1409998I0J1503D01*
G37*
G36*
G01Y1398086D02*
X1156033D01*
G02Y1395080I0J-1503D01*
G01X1152633D01*
G02Y1398086I0J1503D01*
G37*
G36*
G01Y1373888D02*
X1156033D01*
G02Y1370882I0J-1503D01*
G01X1152633D01*
G02Y1373888I0J1503D01*
G37*
G36*
G01Y1385800D02*
X1156033D01*
G02Y1382794I0J-1503D01*
G01X1152633D01*
G02Y1385800I0J1503D01*
G37*
G36*
G01Y1361602D02*
X1156033D01*
G02Y1358596I0J-1503D01*
G01X1152633D01*
G02Y1361602I0J1503D01*
G37*
G36*
G01Y1349690D02*
X1156033D01*
G02Y1346684I0J-1503D01*
G01X1152633D01*
G02Y1349690I0J1503D01*
G37*
G36*
G01X1128153Y1409998D02*
X1131553D01*
G02Y1406992I0J-1503D01*
G01X1128153D01*
G02Y1409998I0J1503D01*
G37*
G36*
G01X1140393D02*
X1143793D01*
G02Y1406992I0J-1503D01*
G01X1140393D01*
G02Y1409998I0J1503D01*
G37*
G36*
G01X1128153Y1398086D02*
X1131553D01*
G02Y1395080I0J-1503D01*
G01X1128153D01*
G02Y1398086I0J1503D01*
G37*
G36*
G01X1140393D02*
X1143793D01*
G02Y1395080I0J-1503D01*
G01X1140393D01*
G02Y1398086I0J1503D01*
G37*
G36*
G01X1128153Y1373888D02*
X1131553D01*
G02Y1370882I0J-1503D01*
G01X1128153D01*
G02Y1373888I0J1503D01*
G37*
G36*
G01Y1385800D02*
X1131553D01*
G02Y1382794I0J-1503D01*
G01X1128153D01*
G02Y1385800I0J1503D01*
G37*
G36*
G01X1140393D02*
X1143793D01*
G02Y1382794I0J-1503D01*
G01X1140393D01*
G02Y1385800I0J1503D01*
G37*
G36*
G01Y1373888D02*
X1143793D01*
G02Y1370882I0J-1503D01*
G01X1140393D01*
G02Y1373888I0J1503D01*
G37*
G36*
G01X1128153Y1361602D02*
X1131553D01*
G02Y1358596I0J-1503D01*
G01X1128153D01*
G02Y1361602I0J1503D01*
G37*
G36*
G01X1140393D02*
X1143793D01*
G02Y1358596I0J-1503D01*
G01X1140393D01*
G02Y1361602I0J1503D01*
G37*
G36*
G01X1128153Y1349690D02*
X1131553D01*
G02Y1346684I0J-1503D01*
G01X1128153D01*
G02Y1349690I0J1503D01*
G37*
G36*
G01X1140393D02*
X1143793D01*
G02Y1346684I0J-1503D01*
G01X1140393D01*
G02Y1349690I0J1503D01*
G37*
G36*
G01X1115913Y1409998D02*
X1119313D01*
G02Y1406992I0J-1503D01*
G01X1115913D01*
G02Y1409998I0J1503D01*
G37*
G36*
G01Y1398086D02*
X1119313D01*
G02Y1395080I0J-1503D01*
G01X1115913D01*
G02Y1398086I0J1503D01*
G37*
G36*
G01Y1373888D02*
X1119313D01*
G02Y1370882I0J-1503D01*
G01X1115913D01*
G02Y1373888I0J1503D01*
G37*
G36*
G01Y1385800D02*
X1119313D01*
G02Y1382794I0J-1503D01*
G01X1115913D01*
G02Y1385800I0J1503D01*
G37*
G36*
G01Y1361602D02*
X1119313D01*
G02Y1358596I0J-1503D01*
G01X1115913D01*
G02Y1361602I0J1503D01*
G37*
G36*
G01Y1349690D02*
X1119313D01*
G02Y1346684I0J-1503D01*
G01X1115913D01*
G02Y1349690I0J1503D01*
G37*
G36*
G01X1103673Y1409998D02*
X1107073D01*
G02Y1406992I0J-1503D01*
G01X1103673D01*
G02Y1409998I0J1503D01*
G37*
G36*
G01Y1398086D02*
X1107073D01*
G02Y1395080I0J-1503D01*
G01X1103673D01*
G02Y1398086I0J1503D01*
G37*
G36*
G01Y1385800D02*
X1107073D01*
G02Y1382794I0J-1503D01*
G01X1103673D01*
G02Y1385800I0J1503D01*
G37*
G36*
G01Y1373888D02*
X1107073D01*
G02Y1370882I0J-1503D01*
G01X1103673D01*
G02Y1373888I0J1503D01*
G37*
G36*
G01Y1361602D02*
X1107073D01*
G02Y1358596I0J-1503D01*
G01X1103673D01*
G02Y1361602I0J1503D01*
G37*
G36*
G01Y1349690D02*
X1107073D01*
G02Y1346684I0J-1503D01*
G01X1103673D01*
G02Y1349690I0J1503D01*
G37*
G36*
G01X1079193Y1409998D02*
X1082593D01*
G02Y1406992I0J-1503D01*
G01X1079193D01*
G02Y1409998I0J1503D01*
G37*
G36*
G01X1091433D02*
X1094833D01*
G02Y1406992I0J-1503D01*
G01X1091433D01*
G02Y1409998I0J1503D01*
G37*
G36*
G01X1079193Y1398086D02*
X1082593D01*
G02Y1395080I0J-1503D01*
G01X1079193D01*
G02Y1398086I0J1503D01*
G37*
G36*
G01X1091433D02*
X1094833D01*
G02Y1395080I0J-1503D01*
G01X1091433D01*
G02Y1398086I0J1503D01*
G37*
G36*
G01X1079193Y1385800D02*
X1082593D01*
G02Y1382794I0J-1503D01*
G01X1079193D01*
G02Y1385800I0J1503D01*
G37*
G36*
G01Y1373888D02*
X1082593D01*
G02Y1370882I0J-1503D01*
G01X1079193D01*
G02Y1373888I0J1503D01*
G37*
G36*
G01X1091433Y1385800D02*
X1094833D01*
G02Y1382794I0J-1503D01*
G01X1091433D01*
G02Y1385800I0J1503D01*
G37*
G36*
G01Y1373888D02*
X1094833D01*
G02Y1370882I0J-1503D01*
G01X1091433D01*
G02Y1373888I0J1503D01*
G37*
G36*
G01X1079193Y1361602D02*
X1082593D01*
G02Y1358596I0J-1503D01*
G01X1079193D01*
G02Y1361602I0J1503D01*
G37*
G36*
G01X1091433D02*
X1094833D01*
G02Y1358596I0J-1503D01*
G01X1091433D01*
G02Y1361602I0J1503D01*
G37*
G36*
G01X1079193Y1349690D02*
X1082593D01*
G02Y1346684I0J-1503D01*
G01X1079193D01*
G02Y1349690I0J1503D01*
G37*
G36*
G01X1091433D02*
X1094833D01*
G02Y1346684I0J-1503D01*
G01X1091433D01*
G02Y1349690I0J1503D01*
G37*
G36*
G01X1066953Y1409998D02*
X1070353D01*
G02Y1406992I0J-1503D01*
G01X1066953D01*
G02Y1409998I0J1503D01*
G37*
G36*
G01Y1398086D02*
X1070353D01*
G02Y1395080I0J-1503D01*
G01X1066953D01*
G02Y1398086I0J1503D01*
G37*
G36*
G01X290583Y1349690D02*
X293983D01*
G02Y1346684I0J-1503D01*
G01X290583D01*
G02Y1349690I0J1503D01*
G37*
G36*
G01X241623Y1385800D02*
X245023D01*
G02Y1382794I0J-1503D01*
G01X241623D01*
G02Y1385800I0J1503D01*
G37*
G36*
G01X253863Y1361602D02*
X257263D01*
G02Y1358596I0J-1503D01*
G01X253863D01*
G02Y1361602I0J1503D01*
G37*
G36*
G01Y1349690D02*
X257263D01*
G02Y1346684I0J-1503D01*
G01X253863D01*
G02Y1349690I0J1503D01*
G37*
G36*
G01X1547050Y1409998D02*
X1550450D01*
G02Y1406992I0J-1503D01*
G01X1547050D01*
G02Y1409998I0J1503D01*
G37*
G36*
G01X1559290Y1385800D02*
X1562690D01*
G02Y1382794I0J-1503D01*
G01X1559290D01*
G02Y1385800I0J1503D01*
G37*
G36*
G01X1230326Y1349690D02*
X1233726D01*
G02Y1346684I0J-1503D01*
G01X1230326D01*
G02Y1349690I0J1503D01*
G37*
G36*
G01Y1361602D02*
X1233726D01*
G02Y1358596I0J-1503D01*
G01X1230326D01*
G02Y1361602I0J1503D01*
G37*
G36*
G01Y1373888D02*
X1233726D01*
G02Y1370882I0J-1503D01*
G01X1230326D01*
G02Y1373888I0J1503D01*
G37*
G36*
G01Y1385800D02*
X1233726D01*
G02Y1382794I0J-1503D01*
G01X1230326D01*
G02Y1385800I0J1503D01*
G37*
G36*
G01X1242566Y1349690D02*
X1245966D01*
G02Y1346684I0J-1503D01*
G01X1242566D01*
G02Y1349690I0J1503D01*
G37*
G36*
G01Y1361602D02*
X1245966D01*
G02Y1358596I0J-1503D01*
G01X1242566D01*
G02Y1361602I0J1503D01*
G37*
G36*
G01Y1385800D02*
X1245966D01*
G02Y1382794I0J-1503D01*
G01X1242566D01*
G02Y1385800I0J1503D01*
G37*
G36*
G01Y1373888D02*
X1245966D01*
G02Y1370882I0J-1503D01*
G01X1242566D01*
G02Y1373888I0J1503D01*
G37*
G36*
G01Y1398086D02*
X1245966D01*
G02Y1395080I0J-1503D01*
G01X1242566D01*
G02Y1398086I0J1503D01*
G37*
G36*
G01Y1409998D02*
X1245966D01*
G02Y1406992I0J-1503D01*
G01X1242566D01*
G02Y1409998I0J1503D01*
G37*
G36*
G01X1267046Y1349690D02*
X1270446D01*
G02Y1346684I0J-1503D01*
G01X1267046D01*
G02Y1349690I0J1503D01*
G37*
G36*
G01X1254806D02*
X1258206D01*
G02Y1346684I0J-1503D01*
G01X1254806D01*
G02Y1349690I0J1503D01*
G37*
G36*
G01X1267046Y1361602D02*
X1270446D01*
G02Y1358596I0J-1503D01*
G01X1267046D01*
G02Y1361602I0J1503D01*
G37*
G36*
G01X1254806D02*
X1258206D01*
G02Y1358596I0J-1503D01*
G01X1254806D01*
G02Y1361602I0J1503D01*
G37*
G36*
G01X1267046Y1385800D02*
X1270446D01*
G02Y1382794I0J-1503D01*
G01X1267046D01*
G02Y1385800I0J1503D01*
G37*
G36*
G01Y1373888D02*
X1270446D01*
G02Y1370882I0J-1503D01*
G01X1267046D01*
G02Y1373888I0J1503D01*
G37*
G36*
G01X1254806D02*
X1258206D01*
G02Y1370882I0J-1503D01*
G01X1254806D01*
G02Y1373888I0J1503D01*
G37*
G36*
G01Y1385800D02*
X1258206D01*
G02Y1382794I0J-1503D01*
G01X1254806D01*
G02Y1385800I0J1503D01*
G37*
G36*
G01X1267046Y1398086D02*
X1270446D01*
G02Y1395080I0J-1503D01*
G01X1267046D01*
G02Y1398086I0J1503D01*
G37*
G36*
G01X1254806D02*
X1258206D01*
G02Y1395080I0J-1503D01*
G01X1254806D01*
G02Y1398086I0J1503D01*
G37*
G36*
G01X1267046Y1409998D02*
X1270446D01*
G02Y1406992I0J-1503D01*
G01X1267046D01*
G02Y1409998I0J1503D01*
G37*
G36*
G01X1254806D02*
X1258206D01*
G02Y1406992I0J-1503D01*
G01X1254806D01*
G02Y1409998I0J1503D01*
G37*
G36*
G01X1279286Y1349690D02*
X1282686D01*
G02Y1346684I0J-1503D01*
G01X1279286D01*
G02Y1349690I0J1503D01*
G37*
G36*
G01Y1361602D02*
X1282686D01*
G02Y1358596I0J-1503D01*
G01X1279286D01*
G02Y1361602I0J1503D01*
G37*
G36*
G01X1510330D02*
X1513730D01*
G02Y1358596I0J-1503D01*
G01X1510330D01*
G02Y1361602I0J1503D01*
G37*
G36*
G01X1279286Y1373888D02*
X1282686D01*
G02Y1370882I0J-1503D01*
G01X1279286D01*
G02Y1373888I0J1503D01*
G37*
G36*
G01Y1385800D02*
X1282686D01*
G02Y1382794I0J-1503D01*
G01X1279286D01*
G02Y1385800I0J1503D01*
G37*
G36*
G01X1648118Y1409998D02*
X1651518D01*
G02Y1406992I0J-1503D01*
G01X1648118D01*
G02Y1409998I0J1503D01*
G37*
G36*
G01X1279286Y1398086D02*
X1282686D01*
G02Y1395080I0J-1503D01*
G01X1279286D01*
G02Y1398086I0J1503D01*
G37*
G36*
G01Y1409998D02*
X1282686D01*
G02Y1406992I0J-1503D01*
G01X1279286D01*
G02Y1409998I0J1503D01*
G37*
G36*
G01X1291526Y1349690D02*
X1294926D01*
G02Y1346684I0J-1503D01*
G01X1291526D01*
G02Y1349690I0J1503D01*
G37*
G36*
G01X1559290Y1398086D02*
X1562690D01*
G02Y1395080I0J-1503D01*
G01X1559290D01*
G02Y1398086I0J1503D01*
G37*
G36*
G01X161792Y1409998D02*
X165192D01*
G02Y1406992I0J-1503D01*
G01X161792D01*
G02Y1409998I0J1503D01*
G37*
G36*
G01X186272Y1349690D02*
X189672D01*
G02Y1346684I0J-1503D01*
G01X186272D01*
G02Y1349690I0J1503D01*
G37*
G36*
G01X315063Y1409998D02*
X318463D01*
G02Y1406992I0J-1503D01*
G01X315063D01*
G02Y1409998I0J1503D01*
G37*
G36*
G01X1534810Y1373888D02*
X1538210D01*
G02Y1370882I0J-1503D01*
G01X1534810D01*
G02Y1373888I0J1503D01*
G37*
G36*
G01X1559290Y1409998D02*
X1562690D01*
G02Y1406992I0J-1503D01*
G01X1559290D01*
G02Y1409998I0J1503D01*
G37*
G36*
G01X351783Y1361602D02*
X355183D01*
G02Y1358596I0J-1503D01*
G01X351783D01*
G02Y1361602I0J1503D01*
G37*
G36*
G01X198512Y1385800D02*
X201912D01*
G02Y1382794I0J-1503D01*
G01X198512D01*
G02Y1385800I0J1503D01*
G37*
G36*
G01X1291526Y1361602D02*
X1294926D01*
G02Y1358596I0J-1503D01*
G01X1291526D01*
G02Y1361602I0J1503D01*
G37*
G36*
G01X1635878Y1349690D02*
X1639278D01*
G02Y1346684I0J-1503D01*
G01X1635878D01*
G02Y1349690I0J1503D01*
G37*
G36*
G01Y1361602D02*
X1639278D01*
G02Y1358596I0J-1503D01*
G01X1635878D01*
G02Y1361602I0J1503D01*
G37*
G36*
G01X1291526Y1385800D02*
X1294926D01*
G02Y1382794I0J-1503D01*
G01X1291526D01*
G02Y1385800I0J1503D01*
G37*
G36*
G01Y1373888D02*
X1294926D01*
G02Y1370882I0J-1503D01*
G01X1291526D01*
G02Y1373888I0J1503D01*
G37*
G36*
G01X1635878Y1385800D02*
X1639278D01*
G02Y1382794I0J-1503D01*
G01X1635878D01*
G02Y1385800I0J1503D01*
G37*
G36*
G01Y1373888D02*
X1639278D01*
G02Y1370882I0J-1503D01*
G01X1635878D01*
G02Y1373888I0J1503D01*
G37*
G36*
G01Y1398086D02*
X1639278D01*
G02Y1395080I0J-1503D01*
G01X1635878D01*
G02Y1398086I0J1503D01*
G37*
G36*
G01X1623638Y1349690D02*
X1627038D01*
G02Y1346684I0J-1503D01*
G01X1623638D01*
G02Y1349690I0J1503D01*
G37*
G36*
G01X1611398D02*
X1614798D01*
G02Y1346684I0J-1503D01*
G01X1611398D01*
G02Y1349690I0J1503D01*
G37*
G36*
G01X1623638Y1361602D02*
X1627038D01*
G02Y1358596I0J-1503D01*
G01X1623638D01*
G02Y1361602I0J1503D01*
G37*
G36*
G01X1291526Y1398086D02*
X1294926D01*
G02Y1395080I0J-1503D01*
G01X1291526D01*
G02Y1398086I0J1503D01*
G37*
G36*
G01Y1409998D02*
X1294926D01*
G02Y1406992I0J-1503D01*
G01X1291526D01*
G02Y1409998I0J1503D01*
G37*
G36*
G01X1316006Y1349690D02*
X1319406D01*
G02Y1346684I0J-1503D01*
G01X1316006D01*
G02Y1349690I0J1503D01*
G37*
G36*
G01X1303766D02*
X1307166D01*
G02Y1346684I0J-1503D01*
G01X1303766D01*
G02Y1349690I0J1503D01*
G37*
G36*
G01X1316006Y1361602D02*
X1319406D01*
G02Y1358596I0J-1503D01*
G01X1316006D01*
G02Y1361602I0J1503D01*
G37*
G36*
G01X1303766D02*
X1307166D01*
G02Y1358596I0J-1503D01*
G01X1303766D01*
G02Y1361602I0J1503D01*
G37*
G36*
G01X1316006Y1385800D02*
X1319406D01*
G02Y1382794I0J-1503D01*
G01X1316006D01*
G02Y1385800I0J1503D01*
G37*
G36*
G01X1611398Y1373888D02*
X1614798D01*
G02Y1370882I0J-1503D01*
G01X1611398D01*
G02Y1373888I0J1503D01*
G37*
G36*
G01Y1385800D02*
X1614798D01*
G02Y1382794I0J-1503D01*
G01X1611398D01*
G02Y1385800I0J1503D01*
G37*
G36*
G01X1623638Y1398086D02*
X1627038D01*
G02Y1395080I0J-1503D01*
G01X1623638D01*
G02Y1398086I0J1503D01*
G37*
G36*
G01X1316006Y1373888D02*
X1319406D01*
G02Y1370882I0J-1503D01*
G01X1316006D01*
G02Y1373888I0J1503D01*
G37*
G36*
G01X1303766D02*
X1307166D01*
G02Y1370882I0J-1503D01*
G01X1303766D01*
G02Y1373888I0J1503D01*
G37*
G36*
G01Y1385800D02*
X1307166D01*
G02Y1382794I0J-1503D01*
G01X1303766D01*
G02Y1385800I0J1503D01*
G37*
G36*
G01X1316006Y1398086D02*
X1319406D01*
G02Y1395080I0J-1503D01*
G01X1316006D01*
G02Y1398086I0J1503D01*
G37*
G36*
G01X1303766D02*
X1307166D01*
G02Y1395080I0J-1503D01*
G01X1303766D01*
G02Y1398086I0J1503D01*
G37*
G36*
G01X1316006Y1409998D02*
X1319406D01*
G02Y1406992I0J-1503D01*
G01X1316006D01*
G02Y1409998I0J1503D01*
G37*
G36*
G01X1303766D02*
X1307166D01*
G02Y1406992I0J-1503D01*
G01X1303766D01*
G02Y1409998I0J1503D01*
G37*
G36*
G01X1623638D02*
X1627038D01*
G02Y1406992I0J-1503D01*
G01X1623638D01*
G02Y1409998I0J1503D01*
G37*
G36*
G01X1328246Y1349690D02*
X1331646D01*
G02Y1346684I0J-1503D01*
G01X1328246D01*
G02Y1349690I0J1503D01*
G37*
G36*
G01Y1361602D02*
X1331646D01*
G02Y1358596I0J-1503D01*
G01X1328246D01*
G02Y1361602I0J1503D01*
G37*
G36*
G01X1648118Y1398086D02*
X1651518D01*
G02Y1395080I0J-1503D01*
G01X1648118D01*
G02Y1398086I0J1503D01*
G37*
G36*
G01Y1373888D02*
X1651518D01*
G02Y1370882I0J-1503D01*
G01X1648118D01*
G02Y1373888I0J1503D01*
G37*
G36*
G01Y1385800D02*
X1651518D01*
G02Y1382794I0J-1503D01*
G01X1648118D01*
G02Y1385800I0J1503D01*
G37*
G36*
G01X1328246Y1373888D02*
X1331646D01*
G02Y1370882I0J-1503D01*
G01X1328246D01*
G02Y1373888I0J1503D01*
G37*
G36*
G01X1648118Y1361602D02*
X1651518D01*
G02Y1358596I0J-1503D01*
G01X1648118D01*
G02Y1361602I0J1503D01*
G37*
G36*
G01Y1349690D02*
X1651518D01*
G02Y1346684I0J-1503D01*
G01X1648118D01*
G02Y1349690I0J1503D01*
G37*
G36*
G01X1635878Y1409998D02*
X1639278D01*
G02Y1406992I0J-1503D01*
G01X1635878D01*
G02Y1409998I0J1503D01*
G37*
G36*
G01X1660358D02*
X1663758D01*
G02Y1406992I0J-1503D01*
G01X1660358D01*
G02Y1409998I0J1503D01*
G37*
G36*
G01X1672598D02*
X1675998D01*
G02Y1406992I0J-1503D01*
G01X1672598D01*
G02Y1409998I0J1503D01*
G37*
G36*
G01X1660358Y1398086D02*
X1663758D01*
G02Y1395080I0J-1503D01*
G01X1660358D01*
G02Y1398086I0J1503D01*
G37*
G36*
G01X1672598D02*
X1675998D01*
G02Y1395080I0J-1503D01*
G01X1672598D01*
G02Y1398086I0J1503D01*
G37*
G36*
G01X1660358Y1373888D02*
X1663758D01*
G02Y1370882I0J-1503D01*
G01X1660358D01*
G02Y1373888I0J1503D01*
G37*
G36*
G01Y1385800D02*
X1663758D01*
G02Y1382794I0J-1503D01*
G01X1660358D01*
G02Y1385800I0J1503D01*
G37*
G36*
G01X1672598Y1373888D02*
X1675998D01*
G02Y1370882I0J-1503D01*
G01X1672598D01*
G02Y1373888I0J1503D01*
G37*
G36*
G01X1328246Y1385800D02*
X1331646D01*
G02Y1382794I0J-1503D01*
G01X1328246D01*
G02Y1385800I0J1503D01*
G37*
G36*
G01X1672598D02*
X1675998D01*
G02Y1382794I0J-1503D01*
G01X1672598D01*
G02Y1385800I0J1503D01*
G37*
G36*
G01X174032Y1409998D02*
X177432D01*
G02Y1406992I0J-1503D01*
G01X174032D01*
G02Y1409998I0J1503D01*
G37*
G36*
G01X266103Y1385800D02*
X269503D01*
G02Y1382794I0J-1503D01*
G01X266103D01*
G02Y1385800I0J1503D01*
G37*
G36*
G01X315063D02*
X318463D01*
G02Y1382794I0J-1503D01*
G01X315063D01*
G02Y1385800I0J1503D01*
G37*
G36*
G01X278343Y1409998D02*
X281743D01*
G02Y1406992I0J-1503D01*
G01X278343D01*
G02Y1409998I0J1503D01*
G37*
G36*
G01X1328246Y1398086D02*
X1331646D01*
G02Y1395080I0J-1503D01*
G01X1328246D01*
G02Y1398086I0J1503D01*
G37*
G36*
G01X364023Y1409998D02*
X367423D01*
G02Y1406992I0J-1503D01*
G01X364023D01*
G02Y1409998I0J1503D01*
G37*
G36*
G01X266103D02*
X269503D01*
G02Y1406992I0J-1503D01*
G01X266103D01*
G02Y1409998I0J1503D01*
G37*
G36*
G01X1733798Y1385800D02*
X1737198D01*
G02Y1382794I0J-1503D01*
G01X1733798D01*
G02Y1385800I0J1503D01*
G37*
G36*
G01Y1373888D02*
X1737198D01*
G02Y1370882I0J-1503D01*
G01X1733798D01*
G02Y1373888I0J1503D01*
G37*
G36*
G01Y1398086D02*
X1737198D01*
G02Y1395080I0J-1503D01*
G01X1733798D01*
G02Y1398086I0J1503D01*
G37*
G36*
G01X1721558Y1373888D02*
X1724958D01*
G02Y1370882I0J-1503D01*
G01X1721558D01*
G02Y1373888I0J1503D01*
G37*
G36*
G01X290583D02*
X293983D01*
G02Y1370882I0J-1503D01*
G01X290583D01*
G02Y1373888I0J1503D01*
G37*
G36*
G01X1328246Y1409998D02*
X1331646D01*
G02Y1406992I0J-1503D01*
G01X1328246D01*
G02Y1409998I0J1503D01*
G37*
G36*
G01X1340486Y1349690D02*
X1343886D01*
G02Y1346684I0J-1503D01*
G01X1340486D01*
G02Y1349690I0J1503D01*
G37*
G36*
G01X1583770Y1373888D02*
X1587170D01*
G02Y1370882I0J-1503D01*
G01X1583770D01*
G02Y1373888I0J1503D01*
G37*
G36*
G01X1485850Y1349690D02*
X1489250D01*
G02Y1346684I0J-1503D01*
G01X1485850D01*
G02Y1349690I0J1503D01*
G37*
G36*
G01X1340486Y1361602D02*
X1343886D01*
G02Y1358596I0J-1503D01*
G01X1340486D01*
G02Y1361602I0J1503D01*
G37*
G36*
G01X1733798Y1409998D02*
X1737198D01*
G02Y1406992I0J-1503D01*
G01X1733798D01*
G02Y1409998I0J1503D01*
G37*
G36*
G01X278343Y1373888D02*
X281743D01*
G02Y1370882I0J-1503D01*
G01X278343D01*
G02Y1373888I0J1503D01*
G37*
G36*
G01X266103Y1398086D02*
X269503D01*
G02Y1395080I0J-1503D01*
G01X266103D01*
G02Y1398086I0J1503D01*
G37*
G36*
G01X1733798Y1349690D02*
X1737198D01*
G02Y1346684I0J-1503D01*
G01X1733798D01*
G02Y1349690I0J1503D01*
G37*
G36*
G01X137312Y1385800D02*
X140712D01*
G02Y1382794I0J-1503D01*
G01X137312D01*
G02Y1385800I0J1503D01*
G37*
G36*
G01X1721558Y1398086D02*
X1724958D01*
G02Y1395080I0J-1503D01*
G01X1721558D01*
G02Y1398086I0J1503D01*
G37*
G36*
G01X1340486Y1385800D02*
X1343886D01*
G02Y1382794I0J-1503D01*
G01X1340486D01*
G02Y1385800I0J1503D01*
G37*
G36*
G01Y1373888D02*
X1343886D01*
G02Y1370882I0J-1503D01*
G01X1340486D01*
G02Y1373888I0J1503D01*
G37*
G36*
G01X1721558Y1385800D02*
X1724958D01*
G02Y1382794I0J-1503D01*
G01X1721558D01*
G02Y1385800I0J1503D01*
G37*
G36*
G01X339543Y1398086D02*
X342943D01*
G02Y1395080I0J-1503D01*
G01X339543D01*
G02Y1398086I0J1503D01*
G37*
G36*
G01X327303Y1385800D02*
X330703D01*
G02Y1382794I0J-1503D01*
G01X327303D01*
G02Y1385800I0J1503D01*
G37*
G36*
G01X315063Y1373888D02*
X318463D01*
G02Y1370882I0J-1503D01*
G01X315063D01*
G02Y1373888I0J1503D01*
G37*
G36*
G01X339543D02*
X342943D01*
G02Y1370882I0J-1503D01*
G01X339543D01*
G02Y1373888I0J1503D01*
G37*
G36*
G01X351783Y1385800D02*
X355183D01*
G02Y1382794I0J-1503D01*
G01X351783D01*
G02Y1385800I0J1503D01*
G37*
G36*
G01Y1373888D02*
X355183D01*
G02Y1370882I0J-1503D01*
G01X351783D01*
G02Y1373888I0J1503D01*
G37*
G36*
G01Y1398086D02*
X355183D01*
G02Y1395080I0J-1503D01*
G01X351783D01*
G02Y1398086I0J1503D01*
G37*
G36*
G01Y1409998D02*
X355183D01*
G02Y1406992I0J-1503D01*
G01X351783D01*
G02Y1409998I0J1503D01*
G37*
G36*
G01X315063Y1398086D02*
X318463D01*
G02Y1395080I0J-1503D01*
G01X315063D01*
G02Y1398086I0J1503D01*
G37*
G36*
G01X278343Y1361602D02*
X281743D01*
G02Y1358596I0J-1503D01*
G01X278343D01*
G02Y1361602I0J1503D01*
G37*
G36*
G01X1498090Y1349690D02*
X1501490D01*
G02Y1346684I0J-1503D01*
G01X1498090D01*
G02Y1349690I0J1503D01*
G37*
G36*
G01X266103Y1361602D02*
X269503D01*
G02Y1358596I0J-1503D01*
G01X266103D01*
G02Y1361602I0J1503D01*
G37*
G36*
G01X35825Y1466648D02*
X39225D01*
G02Y1463044I0J-1802D01*
G01X35825D01*
G02Y1466648I0J1802D01*
G37*
G36*
G01X942699Y344560D02*
X939299D01*
G02Y348166I0J1803D01*
G01X942699D01*
G02Y344560I0J-1803D01*
G37*
G36*
G01X942730Y322242D02*
X939330D01*
G02Y325846I0J1802D01*
G01X942730D01*
G02Y322242I0J-1802D01*
G37*
G36*
G01X927963Y342238D02*
X924563D01*
G02Y345844I0J1803D01*
G01X927963D01*
G02Y342238I0J-1803D01*
G37*
G36*
G01X919353Y342348D02*
X915953D01*
G02Y345952I0J1802D01*
G01X919353D01*
G02Y342348I0J-1802D01*
G37*
G36*
G01X302823Y1398086D02*
X306223D01*
G02Y1395080I0J-1503D01*
G01X302823D01*
G02Y1398086I0J1503D01*
G37*
G36*
G01X389015Y794228D02*
X392415D01*
G02Y791222I0J-1503D01*
G01X389015D01*
G02Y794228I0J1503D01*
G37*
G36*
G01X302823Y1373888D02*
X306223D01*
G02Y1370882I0J-1503D01*
G01X302823D01*
G02Y1373888I0J1503D01*
G37*
G36*
G01X1534810Y1385800D02*
X1538210D01*
G02Y1382794I0J-1503D01*
G01X1534810D01*
G02Y1385800I0J1503D01*
G37*
G36*
G01X327303Y1398086D02*
X330703D01*
G02Y1395080I0J-1503D01*
G01X327303D01*
G02Y1398086I0J1503D01*
G37*
G36*
G01X339543Y1409998D02*
X342943D01*
G02Y1406992I0J-1503D01*
G01X339543D01*
G02Y1409998I0J1503D01*
G37*
G36*
G01X302823Y1385800D02*
X306223D01*
G02Y1382794I0J-1503D01*
G01X302823D01*
G02Y1385800I0J1503D01*
G37*
G36*
G01X278343D02*
X281743D01*
G02Y1382794I0J-1503D01*
G01X278343D01*
G02Y1385800I0J1503D01*
G37*
G36*
G01X1340486Y1398086D02*
X1343886D01*
G02Y1395080I0J-1503D01*
G01X1340486D01*
G02Y1398086I0J1503D01*
G37*
G36*
G01Y1409998D02*
X1343886D01*
G02Y1406992I0J-1503D01*
G01X1340486D01*
G02Y1409998I0J1503D01*
G37*
G36*
G01X1583770Y1385800D02*
X1587170D01*
G02Y1382794I0J-1503D01*
G01X1583770D01*
G02Y1385800I0J1503D01*
G37*
G36*
G01X1571530Y1349690D02*
X1574930D01*
G02Y1346684I0J-1503D01*
G01X1571530D01*
G02Y1349690I0J1503D01*
G37*
G36*
G01Y1373888D02*
X1574930D01*
G02Y1370882I0J-1503D01*
G01X1571530D01*
G02Y1373888I0J1503D01*
G37*
G36*
G01Y1385800D02*
X1574930D01*
G02Y1382794I0J-1503D01*
G01X1571530D01*
G02Y1385800I0J1503D01*
G37*
G36*
G01X1473610Y1398086D02*
X1477010D01*
G02Y1395080I0J-1503D01*
G01X1473610D01*
G02Y1398086I0J1503D01*
G37*
G36*
G01Y1409998D02*
X1477010D01*
G02Y1406992I0J-1503D01*
G01X1473610D01*
G02Y1409998I0J1503D01*
G37*
G36*
G01X1583770Y1398086D02*
X1587170D01*
G02Y1395080I0J-1503D01*
G01X1583770D01*
G02Y1398086I0J1503D01*
G37*
G36*
G01Y1409998D02*
X1587170D01*
G02Y1406992I0J-1503D01*
G01X1583770D01*
G02Y1409998I0J1503D01*
G37*
G36*
G01X1485850Y1398086D02*
X1489250D01*
G02Y1395080I0J-1503D01*
G01X1485850D01*
G02Y1398086I0J1503D01*
G37*
G36*
G01X1498090Y1373888D02*
X1501490D01*
G02Y1370882I0J-1503D01*
G01X1498090D01*
G02Y1373888I0J1503D01*
G37*
G36*
G01X1522570Y1361602D02*
X1525970D01*
G02Y1358596I0J-1503D01*
G01X1522570D01*
G02Y1361602I0J1503D01*
G37*
G36*
G01X1498090Y1409998D02*
X1501490D01*
G02Y1406992I0J-1503D01*
G01X1498090D01*
G02Y1409998I0J1503D01*
G37*
G36*
G01X1352726Y1349690D02*
X1356126D01*
G02Y1346684I0J-1503D01*
G01X1352726D01*
G02Y1349690I0J1503D01*
G37*
G36*
G01X1510330Y1398086D02*
X1513730D01*
G02Y1395080I0J-1503D01*
G01X1510330D01*
G02Y1398086I0J1503D01*
G37*
G36*
G01X1611398Y1361602D02*
X1614798D01*
G02Y1358596I0J-1503D01*
G01X1611398D01*
G02Y1361602I0J1503D01*
G37*
G36*
G01X1623638Y1373888D02*
X1627038D01*
G02Y1370882I0J-1503D01*
G01X1623638D01*
G02Y1373888I0J1503D01*
G37*
G36*
G01X1547050D02*
X1550450D01*
G02Y1370882I0J-1503D01*
G01X1547050D01*
G02Y1373888I0J1503D01*
G37*
G36*
G01X1352726Y1361602D02*
X1356126D01*
G02Y1358596I0J-1503D01*
G01X1352726D01*
G02Y1361602I0J1503D01*
G37*
G36*
G01Y1385800D02*
X1356126D01*
G02Y1382794I0J-1503D01*
G01X1352726D01*
G02Y1385800I0J1503D01*
G37*
G36*
G01Y1373888D02*
X1356126D01*
G02Y1370882I0J-1503D01*
G01X1352726D01*
G02Y1373888I0J1503D01*
G37*
G36*
G01X1684838Y1409998D02*
X1688238D01*
G02Y1406992I0J-1503D01*
G01X1684838D01*
G02Y1409998I0J1503D01*
G37*
G36*
G01X1709318Y1373888D02*
X1712718D01*
G02Y1370882I0J-1503D01*
G01X1709318D01*
G02Y1373888I0J1503D01*
G37*
G36*
G01Y1385800D02*
X1712718D01*
G02Y1382794I0J-1503D01*
G01X1709318D01*
G02Y1385800I0J1503D01*
G37*
G36*
G01X1733798Y1361602D02*
X1737198D01*
G02Y1358596I0J-1503D01*
G01X1733798D01*
G02Y1361602I0J1503D01*
G37*
G36*
G01X1697078Y1373888D02*
X1700478D01*
G02Y1370882I0J-1503D01*
G01X1697078D01*
G02Y1373888I0J1503D01*
G37*
G36*
G01X1709318Y1409998D02*
X1712718D01*
G02Y1406992I0J-1503D01*
G01X1709318D01*
G02Y1409998I0J1503D01*
G37*
G36*
G01X1697078Y1398086D02*
X1700478D01*
G02Y1395080I0J-1503D01*
G01X1697078D01*
G02Y1398086I0J1503D01*
G37*
G36*
G01X1709318D02*
X1712718D01*
G02Y1395080I0J-1503D01*
G01X1709318D01*
G02Y1398086I0J1503D01*
G37*
G36*
G01X1721558Y1349690D02*
X1724958D01*
G02Y1346684I0J-1503D01*
G01X1721558D01*
G02Y1349690I0J1503D01*
G37*
G36*
G01Y1361602D02*
X1724958D01*
G02Y1358596I0J-1503D01*
G01X1721558D01*
G02Y1361602I0J1503D01*
G37*
G36*
G01Y1409998D02*
X1724958D01*
G02Y1406992I0J-1503D01*
G01X1721558D01*
G02Y1409998I0J1503D01*
G37*
G36*
G01X1352726Y1398086D02*
X1356126D01*
G02Y1395080I0J-1503D01*
G01X1352726D01*
G02Y1398086I0J1503D01*
G37*
G36*
G01X174032Y1361602D02*
X177432D01*
G02Y1358596I0J-1503D01*
G01X174032D01*
G02Y1361602I0J1503D01*
G37*
G36*
G01X198512Y1349690D02*
X201912D01*
G02Y1346684I0J-1503D01*
G01X198512D01*
G02Y1349690I0J1503D01*
G37*
G36*
G01Y1398086D02*
X201912D01*
G02Y1395080I0J-1503D01*
G01X198512D01*
G02Y1398086I0J1503D01*
G37*
G36*
G01X186272D02*
X189672D01*
G02Y1395080I0J-1503D01*
G01X186272D01*
G02Y1398086I0J1503D01*
G37*
G36*
G01X161792Y1349690D02*
X165192D01*
G02Y1346684I0J-1503D01*
G01X161792D01*
G02Y1349690I0J1503D01*
G37*
G36*
G01X186272Y1361602D02*
X189672D01*
G02Y1358596I0J-1503D01*
G01X186272D01*
G02Y1361602I0J1503D01*
G37*
G36*
G01X100592Y1349690D02*
X103992D01*
G02Y1346684I0J-1503D01*
G01X100592D01*
G02Y1349690I0J1503D01*
G37*
G36*
G01X112832D02*
X116232D01*
G02Y1346684I0J-1503D01*
G01X112832D01*
G02Y1349690I0J1503D01*
G37*
G36*
G01X149552Y1398086D02*
X152952D01*
G02Y1395080I0J-1503D01*
G01X149552D01*
G02Y1398086I0J1503D01*
G37*
G36*
G01X161792D02*
X165192D01*
G02Y1395080I0J-1503D01*
G01X161792D01*
G02Y1398086I0J1503D01*
G37*
G36*
G01Y1373888D02*
X165192D01*
G02Y1370882I0J-1503D01*
G01X161792D01*
G02Y1373888I0J1503D01*
G37*
G36*
G01Y1385800D02*
X165192D01*
G02Y1382794I0J-1503D01*
G01X161792D01*
G02Y1385800I0J1503D01*
G37*
G36*
G01X198512Y1361602D02*
X201912D01*
G02Y1358596I0J-1503D01*
G01X198512D01*
G02Y1361602I0J1503D01*
G37*
G36*
G01X137312D02*
X140712D01*
G02Y1358596I0J-1503D01*
G01X137312D01*
G02Y1361602I0J1503D01*
G37*
G36*
G01X161792D02*
X165192D01*
G02Y1358596I0J-1503D01*
G01X161792D01*
G02Y1361602I0J1503D01*
G37*
G36*
G01X149552Y1349690D02*
X152952D01*
G02Y1346684I0J-1503D01*
G01X149552D01*
G02Y1349690I0J1503D01*
G37*
G36*
G01X137312D02*
X140712D01*
G02Y1346684I0J-1503D01*
G01X137312D01*
G02Y1349690I0J1503D01*
G37*
G36*
G01X76112Y1361602D02*
X79512D01*
G02Y1358596I0J-1503D01*
G01X76112D01*
G02Y1361602I0J1503D01*
G37*
G36*
G01X174032Y1385800D02*
X177432D01*
G02Y1382794I0J-1503D01*
G01X174032D01*
G02Y1385800I0J1503D01*
G37*
G36*
G01X125072Y1409998D02*
X128472D01*
G02Y1406992I0J-1503D01*
G01X125072D01*
G02Y1409998I0J1503D01*
G37*
G36*
G01Y1398086D02*
X128472D01*
G02Y1395080I0J-1503D01*
G01X125072D01*
G02Y1398086I0J1503D01*
G37*
G36*
G01Y1373888D02*
X128472D01*
G02Y1370882I0J-1503D01*
G01X125072D01*
G02Y1373888I0J1503D01*
G37*
G36*
G01Y1385800D02*
X128472D01*
G02Y1382794I0J-1503D01*
G01X125072D01*
G02Y1385800I0J1503D01*
G37*
G36*
G01X1571530Y1361602D02*
X1574930D01*
G02Y1358596I0J-1503D01*
G01X1571530D01*
G02Y1361602I0J1503D01*
G37*
G36*
G01X100592Y1385800D02*
X103992D01*
G02Y1382794I0J-1503D01*
G01X100592D01*
G02Y1385800I0J1503D01*
G37*
G36*
G01X76112Y1373888D02*
X79512D01*
G02Y1370882I0J-1503D01*
G01X76112D01*
G02Y1373888I0J1503D01*
G37*
G36*
G01X88352Y1409998D02*
X91752D01*
G02Y1406992I0J-1503D01*
G01X88352D01*
G02Y1409998I0J1503D01*
G37*
G36*
G01X149552D02*
X152952D01*
G02Y1406992I0J-1503D01*
G01X149552D01*
G02Y1409998I0J1503D01*
G37*
G36*
G01X137312Y1373888D02*
X140712D01*
G02Y1370882I0J-1503D01*
G01X137312D01*
G02Y1373888I0J1503D01*
G37*
G36*
G01X253863Y1385800D02*
X257263D01*
G02Y1382794I0J-1503D01*
G01X253863D01*
G02Y1385800I0J1503D01*
G37*
G36*
G01X186272Y1409998D02*
X189672D01*
G02Y1406992I0J-1503D01*
G01X186272D01*
G02Y1409998I0J1503D01*
G37*
G36*
G01X125072Y1361602D02*
X128472D01*
G02Y1358596I0J-1503D01*
G01X125072D01*
G02Y1361602I0J1503D01*
G37*
G36*
G01Y1349690D02*
X128472D01*
G02Y1346684I0J-1503D01*
G01X125072D01*
G02Y1349690I0J1503D01*
G37*
G36*
G01X149552Y1373888D02*
X152952D01*
G02Y1370882I0J-1503D01*
G01X149552D01*
G02Y1373888I0J1503D01*
G37*
G36*
G01X174032Y1349690D02*
X177432D01*
G02Y1346684I0J-1503D01*
G01X174032D01*
G02Y1349690I0J1503D01*
G37*
G36*
G01Y1373888D02*
X177432D01*
G02Y1370882I0J-1503D01*
G01X174032D01*
G02Y1373888I0J1503D01*
G37*
G36*
G01X76112Y1385800D02*
X79512D01*
G02Y1382794I0J-1503D01*
G01X76112D01*
G02Y1385800I0J1503D01*
G37*
G36*
G01X1583770Y1349690D02*
X1587170D01*
G02Y1346684I0J-1503D01*
G01X1583770D01*
G02Y1349690I0J1503D01*
G37*
G36*
G01X1697078Y1385800D02*
X1700478D01*
G02Y1382794I0J-1503D01*
G01X1697078D01*
G02Y1385800I0J1503D01*
G37*
G36*
G01X88352Y1361602D02*
X91752D01*
G02Y1358596I0J-1503D01*
G01X88352D01*
G02Y1361602I0J1503D01*
G37*
G36*
G01Y1349690D02*
X91752D01*
G02Y1346684I0J-1503D01*
G01X88352D01*
G02Y1349690I0J1503D01*
G37*
G36*
G01X1697078Y1409998D02*
X1700478D01*
G02Y1406992I0J-1503D01*
G01X1697078D01*
G02Y1409998I0J1503D01*
G37*
G36*
G01X112832Y1373888D02*
X116232D01*
G02Y1370882I0J-1503D01*
G01X112832D01*
G02Y1373888I0J1503D01*
G37*
G36*
G01Y1409998D02*
X116232D01*
G02Y1406992I0J-1503D01*
G01X112832D01*
G02Y1409998I0J1503D01*
G37*
G36*
G01X100592D02*
X103992D01*
G02Y1406992I0J-1503D01*
G01X100592D01*
G02Y1409998I0J1503D01*
G37*
G36*
G01X724208Y1385800D02*
X727608D01*
G02Y1382794I0J-1503D01*
G01X724208D01*
G02Y1385800I0J1503D01*
G37*
G36*
G01X88352D02*
X91752D01*
G02Y1382794I0J-1503D01*
G01X88352D01*
G02Y1385800I0J1503D01*
G37*
G36*
G01X760928Y1361602D02*
X764328D01*
G02Y1358596I0J-1503D01*
G01X760928D01*
G02Y1361602I0J1503D01*
G37*
G36*
G01X100592Y1373888D02*
X103992D01*
G02Y1370882I0J-1503D01*
G01X100592D01*
G02Y1373888I0J1503D01*
G37*
G36*
G01X137312Y1398086D02*
X140712D01*
G02Y1395080I0J-1503D01*
G01X137312D01*
G02Y1398086I0J1503D01*
G37*
G36*
G01Y1409998D02*
X140712D01*
G02Y1406992I0J-1503D01*
G01X137312D01*
G02Y1409998I0J1503D01*
G37*
G36*
G01X112832Y1385800D02*
X116232D01*
G02Y1382794I0J-1503D01*
G01X112832D01*
G02Y1385800I0J1503D01*
G37*
G36*
G01X663008Y1361602D02*
X666408D01*
G02Y1358596I0J-1503D01*
G01X663008D01*
G02Y1361602I0J1503D01*
G37*
G36*
G01X100592Y1398086D02*
X103992D01*
G02Y1395080I0J-1503D01*
G01X100592D01*
G02Y1398086I0J1503D01*
G37*
G36*
G01X748688Y1385800D02*
X752088D01*
G02Y1382794I0J-1503D01*
G01X748688D01*
G02Y1385800I0J1503D01*
G37*
G36*
G01X1352726Y1409998D02*
X1356126D01*
G02Y1406992I0J-1503D01*
G01X1352726D01*
G02Y1409998I0J1503D01*
G37*
G36*
G01X100592Y1361602D02*
X103992D01*
G02Y1358596I0J-1503D01*
G01X100592D01*
G02Y1361602I0J1503D01*
G37*
G36*
G01X112832D02*
X116232D01*
G02Y1358596I0J-1503D01*
G01X112832D01*
G02Y1361602I0J1503D01*
G37*
G36*
G01X88352Y1398086D02*
X91752D01*
G02Y1395080I0J-1503D01*
G01X88352D01*
G02Y1398086I0J1503D01*
G37*
G36*
G01X1660358Y1361602D02*
X1663758D01*
G02Y1358596I0J-1503D01*
G01X1660358D01*
G02Y1361602I0J1503D01*
G37*
G36*
G01X1066953Y1349690D02*
X1070353D01*
G02Y1346684I0J-1503D01*
G01X1066953D01*
G02Y1349690I0J1503D01*
G37*
G36*
G01X663008D02*
X666408D01*
G02Y1346684I0J-1503D01*
G01X663008D01*
G02Y1349690I0J1503D01*
G37*
G36*
G01X1583770Y1361602D02*
X1587170D01*
G02Y1358596I0J-1503D01*
G01X1583770D01*
G02Y1361602I0J1503D01*
G37*
G36*
G01X1571530Y1398086D02*
X1574930D01*
G02Y1395080I0J-1503D01*
G01X1571530D01*
G02Y1398086I0J1503D01*
G37*
G36*
G01X1559290Y1361602D02*
X1562690D01*
G02Y1358596I0J-1503D01*
G01X1559290D01*
G02Y1361602I0J1503D01*
G37*
G36*
G01Y1373888D02*
X1562690D01*
G02Y1370882I0J-1503D01*
G01X1559290D01*
G02Y1373888I0J1503D01*
G37*
G36*
G01X1623638Y1385800D02*
X1627038D01*
G02Y1382794I0J-1503D01*
G01X1623638D01*
G02Y1385800I0J1503D01*
G37*
G36*
G01X76112Y1349690D02*
X79512D01*
G02Y1346684I0J-1503D01*
G01X76112D01*
G02Y1349690I0J1503D01*
G37*
G36*
G01X1066953Y1361602D02*
X1070353D01*
G02Y1358596I0J-1503D01*
G01X1066953D01*
G02Y1361602I0J1503D01*
G37*
G36*
G01X1547050Y1385800D02*
X1550450D01*
G02Y1382794I0J-1503D01*
G01X1547050D01*
G02Y1385800I0J1503D01*
G37*
G36*
G01X1672598Y1349690D02*
X1675998D01*
G02Y1346684I0J-1503D01*
G01X1672598D01*
G02Y1349690I0J1503D01*
G37*
G36*
G01X1660358D02*
X1663758D01*
G02Y1346684I0J-1503D01*
G01X1660358D01*
G02Y1349690I0J1503D01*
G37*
G36*
G01X1672598Y1361602D02*
X1675998D01*
G02Y1358596I0J-1503D01*
G01X1672598D01*
G02Y1361602I0J1503D01*
G37*
G36*
G01X1709318Y1349690D02*
X1712718D01*
G02Y1346684I0J-1503D01*
G01X1709318D01*
G02Y1349690I0J1503D01*
G37*
G36*
G01X1697078D02*
X1700478D01*
G02Y1346684I0J-1503D01*
G01X1697078D01*
G02Y1349690I0J1503D01*
G37*
G36*
G01X1684838Y1385800D02*
X1688238D01*
G02Y1382794I0J-1503D01*
G01X1684838D01*
G02Y1385800I0J1503D01*
G37*
G36*
G01X1709318Y1361602D02*
X1712718D01*
G02Y1358596I0J-1503D01*
G01X1709318D01*
G02Y1361602I0J1503D01*
G37*
G36*
G01X1697078D02*
X1700478D01*
G02Y1358596I0J-1503D01*
G01X1697078D01*
G02Y1361602I0J1503D01*
G37*
G36*
G01X1684838D02*
X1688238D01*
G02Y1358596I0J-1503D01*
G01X1684838D01*
G02Y1361602I0J1503D01*
G37*
G36*
G01Y1373888D02*
X1688238D01*
G02Y1370882I0J-1503D01*
G01X1684838D01*
G02Y1373888I0J1503D01*
G37*
G36*
G01Y1398086D02*
X1688238D01*
G02Y1395080I0J-1503D01*
G01X1684838D01*
G02Y1398086I0J1503D01*
G37*
G36*
G01X1066953Y1373888D02*
X1070353D01*
G02Y1370882I0J-1503D01*
G01X1066953D01*
G02Y1373888I0J1503D01*
G37*
G36*
G01Y1385800D02*
X1070353D01*
G02Y1382794I0J-1503D01*
G01X1066953D01*
G02Y1385800I0J1503D01*
G37*
G36*
G01X1547050Y1398086D02*
X1550450D01*
G02Y1395080I0J-1503D01*
G01X1547050D01*
G02Y1398086I0J1503D01*
G37*
G36*
G01X549168Y783102D02*
G02Y780098I0J-1502D01*
G01X545813D01*
X545808D01*
G02X545944Y783092I-38J1502D01*
G01X545956Y783090D01*
X548978D01*
X548990Y783092D01*
G02X549168Y783102I173J-1492D01*
G37*
G36*
G01X278343Y1349690D02*
X281743D01*
G02Y1346684I0J-1503D01*
G01X278343D01*
G02Y1349690I0J1503D01*
G37*
G36*
G01X945982Y888540D02*
X949382D01*
G02Y884936I0J-1802D01*
G01X945982D01*
G02Y888540I0J1802D01*
G37*
G36*
G01X1684838Y1349690D02*
X1688238D01*
G02Y1346684I0J-1503D01*
G01X1684838D01*
G02Y1349690I0J1503D01*
G37*
G36*
G01X1571530Y1409998D02*
X1574930D01*
G02Y1406992I0J-1503D01*
G01X1571530D01*
G02Y1409998I0J1503D01*
G37*
G36*
G01X1473610Y1373888D02*
X1477010D01*
G02Y1370882I0J-1503D01*
G01X1473610D01*
G02Y1373888I0J1503D01*
G37*
G36*
G01X1498090Y1398086D02*
X1501490D01*
G02Y1395080I0J-1503D01*
G01X1498090D01*
G02Y1398086I0J1503D01*
G37*
G36*
G01Y1385800D02*
X1501490D01*
G02Y1382794I0J-1503D01*
G01X1498090D01*
G02Y1385800I0J1503D01*
G37*
G36*
G01X1510330Y1409998D02*
X1513730D01*
G02Y1406992I0J-1503D01*
G01X1510330D01*
G02Y1409998I0J1503D01*
G37*
G36*
G01X1522570Y1349690D02*
X1525970D01*
G02Y1346684I0J-1503D01*
G01X1522570D01*
G02Y1349690I0J1503D01*
G37*
G36*
G01X146948Y1135604D02*
X143208D01*
G02Y1138210I0J1303D01*
G01X146948D01*
G02Y1135604I0J-1303D01*
G37*
G36*
G01X165649Y1131864D02*
X161909D01*
G02Y1134470I0J1303D01*
G01X165649D01*
G02Y1131864I0J-1303D01*
G37*
G36*
G01X154429D02*
X150689D01*
G02Y1134470I0J1303D01*
G01X154429D01*
G02Y1131864I0J-1303D01*
G37*
G36*
G01X173129Y1135604D02*
X169389D01*
G02Y1138210I0J1303D01*
G01X173129D01*
G02Y1135604I0J-1303D01*
G37*
G36*
G01X440402Y1361602D02*
X443802D01*
G02Y1358596I0J-1503D01*
G01X440402D01*
G02Y1361602I0J1503D01*
G37*
G36*
G01Y1349690D02*
X443802D01*
G02Y1346684I0J-1503D01*
G01X440402D01*
G02Y1349690I0J1503D01*
G37*
G36*
G01X452642Y1361602D02*
X456042D01*
G02Y1358596I0J-1503D01*
G01X452642D01*
G02Y1361602I0J1503D01*
G37*
G36*
G01Y1349690D02*
X456042D01*
G02Y1346684I0J-1503D01*
G01X452642D01*
G02Y1349690I0J1503D01*
G37*
G36*
G01X501602Y1385800D02*
X505002D01*
G02Y1382794I0J-1503D01*
G01X501602D01*
G02Y1385800I0J1503D01*
G37*
G36*
G01X513842D02*
X517242D01*
G02Y1382794I0J-1503D01*
G01X513842D01*
G02Y1385800I0J1503D01*
G37*
G36*
G01Y1373888D02*
X517242D01*
G02Y1370882I0J-1503D01*
G01X513842D01*
G02Y1373888I0J1503D01*
G37*
G36*
G01X501602D02*
X505002D01*
G02Y1370882I0J-1503D01*
G01X501602D01*
G02Y1373888I0J1503D01*
G37*
G36*
G01X464882Y1349690D02*
X468282D01*
G02Y1346684I0J-1503D01*
G01X464882D01*
G02Y1349690I0J1503D01*
G37*
G36*
G01X477122D02*
X480522D01*
G02Y1346684I0J-1503D01*
G01X477122D01*
G02Y1349690I0J1503D01*
G37*
G36*
G01X526082Y1385800D02*
X529482D01*
G02Y1382794I0J-1503D01*
G01X526082D01*
G02Y1385800I0J1503D01*
G37*
G36*
G01X538322D02*
X541722D01*
G02Y1382794I0J-1503D01*
G01X538322D01*
G02Y1385800I0J1503D01*
G37*
G36*
G01X526082Y1373888D02*
X529482D01*
G02Y1370882I0J-1503D01*
G01X526082D01*
G02Y1373888I0J1503D01*
G37*
G36*
G01X538322D02*
X541722D01*
G02Y1370882I0J-1503D01*
G01X538322D01*
G02Y1373888I0J1503D01*
G37*
G36*
G01X464882Y1361602D02*
X468282D01*
G02Y1358596I0J-1503D01*
G01X464882D01*
G02Y1361602I0J1503D01*
G37*
G36*
G01X477122D02*
X480522D01*
G02Y1358596I0J-1503D01*
G01X477122D01*
G02Y1361602I0J1503D01*
G37*
G36*
G01X489362Y1349690D02*
X492762D01*
G02Y1346684I0J-1503D01*
G01X489362D01*
G02Y1349690I0J1503D01*
G37*
G36*
G01X440402Y1373888D02*
X443802D01*
G02Y1370882I0J-1503D01*
G01X440402D01*
G02Y1373888I0J1503D01*
G37*
G36*
G01X550562Y1385800D02*
X553962D01*
G02Y1382794I0J-1503D01*
G01X550562D01*
G02Y1385800I0J1503D01*
G37*
G36*
G01Y1373888D02*
X553962D01*
G02Y1370882I0J-1503D01*
G01X550562D01*
G02Y1373888I0J1503D01*
G37*
G36*
G01X489362Y1361602D02*
X492762D01*
G02Y1358596I0J-1503D01*
G01X489362D01*
G02Y1361602I0J1503D01*
G37*
G36*
G01X440402Y1385800D02*
X443802D01*
G02Y1382794I0J-1503D01*
G01X440402D01*
G02Y1385800I0J1503D01*
G37*
G36*
G01X452642Y1373888D02*
X456042D01*
G02Y1370882I0J-1503D01*
G01X452642D01*
G02Y1373888I0J1503D01*
G37*
G36*
G01X562802Y1385800D02*
X566202D01*
G02Y1382794I0J-1503D01*
G01X562802D01*
G02Y1385800I0J1503D01*
G37*
G36*
G01X452642Y1409998D02*
X456042D01*
G02Y1406992I0J-1503D01*
G01X452642D01*
G02Y1409998I0J1503D01*
G37*
G36*
G01Y1398086D02*
X456042D01*
G02Y1395080I0J-1503D01*
G01X452642D01*
G02Y1398086I0J1503D01*
G37*
G36*
G01X562802Y1373888D02*
X566202D01*
G02Y1370882I0J-1503D01*
G01X562802D01*
G02Y1373888I0J1503D01*
G37*
G36*
G01X452642Y1385800D02*
X456042D01*
G02Y1382794I0J-1503D01*
G01X452642D01*
G02Y1385800I0J1503D01*
G37*
G36*
G01X464882Y1409998D02*
X468282D01*
G02Y1406992I0J-1503D01*
G01X464882D01*
G02Y1409998I0J1503D01*
G37*
G36*
G01Y1398086D02*
X468282D01*
G02Y1395080I0J-1503D01*
G01X464882D01*
G02Y1398086I0J1503D01*
G37*
G36*
G01Y1385800D02*
X468282D01*
G02Y1382794I0J-1503D01*
G01X464882D01*
G02Y1385800I0J1503D01*
G37*
G36*
G01X477122D02*
X480522D01*
G02Y1382794I0J-1503D01*
G01X477122D01*
G02Y1385800I0J1503D01*
G37*
G36*
G01Y1373888D02*
X480522D01*
G02Y1370882I0J-1503D01*
G01X477122D01*
G02Y1373888I0J1503D01*
G37*
G36*
G01X464882D02*
X468282D01*
G02Y1370882I0J-1503D01*
G01X464882D01*
G02Y1373888I0J1503D01*
G37*
G36*
G01X489362D02*
X492762D01*
G02Y1370882I0J-1503D01*
G01X489362D01*
G02Y1373888I0J1503D01*
G37*
G36*
G01Y1409998D02*
X492762D01*
G02Y1406992I0J-1503D01*
G01X489362D01*
G02Y1409998I0J1503D01*
G37*
G36*
G01Y1398086D02*
X492762D01*
G02Y1395080I0J-1503D01*
G01X489362D01*
G02Y1398086I0J1503D01*
G37*
G36*
G01X477122Y1409998D02*
X480522D01*
G02Y1406992I0J-1503D01*
G01X477122D01*
G02Y1409998I0J1503D01*
G37*
G36*
G01Y1398086D02*
X480522D01*
G02Y1395080I0J-1503D01*
G01X477122D01*
G02Y1398086I0J1503D01*
G37*
G36*
G01X489362Y1385800D02*
X492762D01*
G02Y1382794I0J-1503D01*
G01X489362D01*
G02Y1385800I0J1503D01*
G37*
G36*
G01X501602Y1361602D02*
X505002D01*
G02Y1358596I0J-1503D01*
G01X501602D01*
G02Y1361602I0J1503D01*
G37*
G36*
G01X513842D02*
X517242D01*
G02Y1358596I0J-1503D01*
G01X513842D01*
G02Y1361602I0J1503D01*
G37*
G36*
G01X501602Y1349690D02*
X505002D01*
G02Y1346684I0J-1503D01*
G01X501602D01*
G02Y1349690I0J1503D01*
G37*
G36*
G01X513842D02*
X517242D01*
G02Y1346684I0J-1503D01*
G01X513842D01*
G02Y1349690I0J1503D01*
G37*
G36*
G01X501602Y1398086D02*
X505002D01*
G02Y1395080I0J-1503D01*
G01X501602D01*
G02Y1398086I0J1503D01*
G37*
G36*
G01Y1409998D02*
X505002D01*
G02Y1406992I0J-1503D01*
G01X501602D01*
G02Y1409998I0J1503D01*
G37*
G36*
G01X526082Y1361602D02*
X529482D01*
G02Y1358596I0J-1503D01*
G01X526082D01*
G02Y1361602I0J1503D01*
G37*
G36*
G01Y1349690D02*
X529482D01*
G02Y1346684I0J-1503D01*
G01X526082D01*
G02Y1349690I0J1503D01*
G37*
G36*
G01X513842Y1398086D02*
X517242D01*
G02Y1395080I0J-1503D01*
G01X513842D01*
G02Y1398086I0J1503D01*
G37*
G36*
G01X526082Y1409998D02*
X529482D01*
G02Y1406992I0J-1503D01*
G01X526082D01*
G02Y1409998I0J1503D01*
G37*
G36*
G01X513842D02*
X517242D01*
G02Y1406992I0J-1503D01*
G01X513842D01*
G02Y1409998I0J1503D01*
G37*
G36*
G01X526082Y1398086D02*
X529482D01*
G02Y1395080I0J-1503D01*
G01X526082D01*
G02Y1398086I0J1503D01*
G37*
G36*
G01X538322Y1361602D02*
X541722D01*
G02Y1358596I0J-1503D01*
G01X538322D01*
G02Y1361602I0J1503D01*
G37*
G36*
G01X550562D02*
X553962D01*
G02Y1358596I0J-1503D01*
G01X550562D01*
G02Y1361602I0J1503D01*
G37*
G36*
G01X538322Y1349690D02*
X541722D01*
G02Y1346684I0J-1503D01*
G01X538322D01*
G02Y1349690I0J1503D01*
G37*
G36*
G01X550562D02*
X553962D01*
G02Y1346684I0J-1503D01*
G01X550562D01*
G02Y1349690I0J1503D01*
G37*
G36*
G01X538322Y1398086D02*
X541722D01*
G02Y1395080I0J-1503D01*
G01X538322D01*
G02Y1398086I0J1503D01*
G37*
G36*
G01Y1409998D02*
X541722D01*
G02Y1406992I0J-1503D01*
G01X538322D01*
G02Y1409998I0J1503D01*
G37*
G36*
G01X562802Y1361602D02*
X566202D01*
G02Y1358596I0J-1503D01*
G01X562802D01*
G02Y1361602I0J1503D01*
G37*
G36*
G01Y1349690D02*
X566202D01*
G02Y1346684I0J-1503D01*
G01X562802D01*
G02Y1349690I0J1503D01*
G37*
G36*
G01X550562Y1398086D02*
X553962D01*
G02Y1395080I0J-1503D01*
G01X550562D01*
G02Y1398086I0J1503D01*
G37*
G36*
G01X562802D02*
X566202D01*
G02Y1395080I0J-1503D01*
G01X562802D01*
G02Y1398086I0J1503D01*
G37*
G36*
G01X550562Y1409998D02*
X553962D01*
G02Y1406992I0J-1503D01*
G01X550562D01*
G02Y1409998I0J1503D01*
G37*
G36*
G01X562802D02*
X566202D01*
G02Y1406992I0J-1503D01*
G01X562802D01*
G02Y1409998I0J1503D01*
G37*
G36*
G01X650768Y1361602D02*
X654168D01*
G02Y1358596I0J-1503D01*
G01X650768D01*
G02Y1361602I0J1503D01*
G37*
G36*
G01Y1349690D02*
X654168D01*
G02Y1346684I0J-1503D01*
G01X650768D01*
G02Y1349690I0J1503D01*
G37*
G36*
G01X626288Y1409998D02*
X629688D01*
G02Y1406992I0J-1503D01*
G01X626288D01*
G02Y1409998I0J1503D01*
G37*
G36*
G01X638528Y1385800D02*
X641928D01*
G02Y1382794I0J-1503D01*
G01X638528D01*
G02Y1385800I0J1503D01*
G37*
G36*
G01Y1373888D02*
X641928D01*
G02Y1370882I0J-1503D01*
G01X638528D01*
G02Y1373888I0J1503D01*
G37*
G36*
G01X626288Y1398086D02*
X629688D01*
G02Y1395080I0J-1503D01*
G01X626288D01*
G02Y1398086I0J1503D01*
G37*
G36*
G01X675248Y1361602D02*
X678648D01*
G02Y1358596I0J-1503D01*
G01X675248D01*
G02Y1361602I0J1503D01*
G37*
G36*
G01X650768Y1385800D02*
X654168D01*
G02Y1382794I0J-1503D01*
G01X650768D01*
G02Y1385800I0J1503D01*
G37*
G36*
G01X675248Y1349690D02*
X678648D01*
G02Y1346684I0J-1503D01*
G01X675248D01*
G02Y1349690I0J1503D01*
G37*
G36*
G01X650768Y1373888D02*
X654168D01*
G02Y1370882I0J-1503D01*
G01X650768D01*
G02Y1373888I0J1503D01*
G37*
G36*
G01X638528Y1409998D02*
X641928D01*
G02Y1406992I0J-1503D01*
G01X638528D01*
G02Y1409998I0J1503D01*
G37*
G36*
G01Y1398086D02*
X641928D01*
G02Y1395080I0J-1503D01*
G01X638528D01*
G02Y1398086I0J1503D01*
G37*
G36*
G01X687488Y1361602D02*
X690888D01*
G02Y1358596I0J-1503D01*
G01X687488D01*
G02Y1361602I0J1503D01*
G37*
G36*
G01Y1349690D02*
X690888D01*
G02Y1346684I0J-1503D01*
G01X687488D01*
G02Y1349690I0J1503D01*
G37*
G36*
G01X663008Y1385800D02*
X666408D01*
G02Y1382794I0J-1503D01*
G01X663008D01*
G02Y1385800I0J1503D01*
G37*
G36*
G01X650768Y1409998D02*
X654168D01*
G02Y1406992I0J-1503D01*
G01X650768D01*
G02Y1409998I0J1503D01*
G37*
G36*
G01X663008Y1373888D02*
X666408D01*
G02Y1370882I0J-1503D01*
G01X663008D01*
G02Y1373888I0J1503D01*
G37*
G36*
G01X650768Y1398086D02*
X654168D01*
G02Y1395080I0J-1503D01*
G01X650768D01*
G02Y1398086I0J1503D01*
G37*
G36*
G01X699728Y1361602D02*
X703128D01*
G02Y1358596I0J-1503D01*
G01X699728D01*
G02Y1361602I0J1503D01*
G37*
G36*
G01X687488Y1385800D02*
X690888D01*
G02Y1382794I0J-1503D01*
G01X687488D01*
G02Y1385800I0J1503D01*
G37*
G36*
G01X699728Y1349690D02*
X703128D01*
G02Y1346684I0J-1503D01*
G01X699728D01*
G02Y1349690I0J1503D01*
G37*
G36*
G01X687488Y1373888D02*
X690888D01*
G02Y1370882I0J-1503D01*
G01X687488D01*
G02Y1373888I0J1503D01*
G37*
G36*
G01X675248Y1385800D02*
X678648D01*
G02Y1382794I0J-1503D01*
G01X675248D01*
G02Y1385800I0J1503D01*
G37*
G36*
G01Y1373888D02*
X678648D01*
G02Y1370882I0J-1503D01*
G01X675248D01*
G02Y1373888I0J1503D01*
G37*
G36*
G01X711968Y1349690D02*
X715368D01*
G02Y1346684I0J-1503D01*
G01X711968D01*
G02Y1349690I0J1503D01*
G37*
G36*
G01Y1361602D02*
X715368D01*
G02Y1358596I0J-1503D01*
G01X711968D01*
G02Y1361602I0J1503D01*
G37*
G36*
G01X663008Y1409998D02*
X666408D01*
G02Y1406992I0J-1503D01*
G01X663008D01*
G02Y1409998I0J1503D01*
G37*
G36*
G01X699728Y1385800D02*
X703128D01*
G02Y1382794I0J-1503D01*
G01X699728D01*
G02Y1385800I0J1503D01*
G37*
G36*
G01Y1373888D02*
X703128D01*
G02Y1370882I0J-1503D01*
G01X699728D01*
G02Y1373888I0J1503D01*
G37*
G36*
G01X663008Y1398086D02*
X666408D01*
G02Y1395080I0J-1503D01*
G01X663008D01*
G02Y1398086I0J1503D01*
G37*
G36*
G01X724208Y1397992D02*
X727608D01*
G02Y1394986I0J-1503D01*
G01X724208D01*
G02Y1397992I0J1503D01*
G37*
G36*
G01Y1349690D02*
X727608D01*
G02Y1346684I0J-1503D01*
G01X724208D01*
G02Y1349690I0J1503D01*
G37*
G36*
G01X675248Y1409998D02*
X678648D01*
G02Y1406992I0J-1503D01*
G01X675248D01*
G02Y1409998I0J1503D01*
G37*
G36*
G01Y1398086D02*
X678648D01*
G02Y1395080I0J-1503D01*
G01X675248D01*
G02Y1398086I0J1503D01*
G37*
G36*
G01X724208Y1361602D02*
X727608D01*
G02Y1358596I0J-1503D01*
G01X724208D01*
G02Y1361602I0J1503D01*
G37*
G36*
G01Y1409904D02*
X727608D01*
G02Y1406898I0J-1503D01*
G01X724208D01*
G02Y1409904I0J1503D01*
G37*
G36*
G01X736448Y1349690D02*
X739848D01*
G02Y1346684I0J-1503D01*
G01X736448D01*
G02Y1349690I0J1503D01*
G37*
G36*
G01X711968Y1373888D02*
X715368D01*
G02Y1370882I0J-1503D01*
G01X711968D01*
G02Y1373888I0J1503D01*
G37*
G36*
G01X736448Y1361602D02*
X739848D01*
G02Y1358596I0J-1503D01*
G01X736448D01*
G02Y1361602I0J1503D01*
G37*
G36*
G01X711968Y1385800D02*
X715368D01*
G02Y1382794I0J-1503D01*
G01X711968D01*
G02Y1385800I0J1503D01*
G37*
G36*
G01X687488Y1409998D02*
X690888D01*
G02Y1406992I0J-1503D01*
G01X687488D01*
G02Y1409998I0J1503D01*
G37*
G36*
G01Y1398086D02*
X690888D01*
G02Y1395080I0J-1503D01*
G01X687488D01*
G02Y1398086I0J1503D01*
G37*
G36*
G01X736448Y1373888D02*
X739848D01*
G02Y1370882I0J-1503D01*
G01X736448D01*
G02Y1373888I0J1503D01*
G37*
G36*
G01X748688Y1349690D02*
X752088D01*
G02Y1346684I0J-1503D01*
G01X748688D01*
G02Y1349690I0J1503D01*
G37*
G36*
G01X724208Y1373888D02*
X727608D01*
G02Y1370882I0J-1503D01*
G01X724208D01*
G02Y1373888I0J1503D01*
G37*
G36*
G01X736448Y1385800D02*
X739848D01*
G02Y1382794I0J-1503D01*
G01X736448D01*
G02Y1385800I0J1503D01*
G37*
G36*
G01X748688Y1361602D02*
X752088D01*
G02Y1358596I0J-1503D01*
G01X748688D01*
G02Y1361602I0J1503D01*
G37*
G36*
G01X736448Y1409904D02*
X739848D01*
G02Y1406898I0J-1503D01*
G01X736448D01*
G02Y1409904I0J1503D01*
G37*
G36*
G01Y1397992D02*
X739848D01*
G02Y1394986I0J-1503D01*
G01X736448D01*
G02Y1397992I0J1503D01*
G37*
G36*
G01X699728Y1409998D02*
X703128D01*
G02Y1406992I0J-1503D01*
G01X699728D01*
G02Y1409998I0J1503D01*
G37*
G36*
G01Y1398086D02*
X703128D01*
G02Y1395080I0J-1503D01*
G01X699728D01*
G02Y1398086I0J1503D01*
G37*
G36*
G01X748688Y1373888D02*
X752088D01*
G02Y1370882I0J-1503D01*
G01X748688D01*
G02Y1373888I0J1503D01*
G37*
G36*
G01X773168Y1349690D02*
X776568D01*
G02Y1346684I0J-1503D01*
G01X773168D01*
G02Y1349690I0J1503D01*
G37*
G36*
G01X760928D02*
X764328D01*
G02Y1346684I0J-1503D01*
G01X760928D01*
G02Y1349690I0J1503D01*
G37*
G36*
G01X711968Y1409998D02*
X715368D01*
G02Y1406992I0J-1503D01*
G01X711968D01*
G02Y1409998I0J1503D01*
G37*
G36*
G01Y1398086D02*
X715368D01*
G02Y1395080I0J-1503D01*
G01X711968D01*
G02Y1398086I0J1503D01*
G37*
G36*
G01X773168Y1361602D02*
X776568D01*
G02Y1358596I0J-1503D01*
G01X773168D01*
G02Y1361602I0J1503D01*
G37*
G36*
G01X760928Y1373888D02*
X764328D01*
G02Y1370882I0J-1503D01*
G01X760928D01*
G02Y1373888I0J1503D01*
G37*
G36*
G01Y1385800D02*
X764328D01*
G02Y1382794I0J-1503D01*
G01X760928D01*
G02Y1385800I0J1503D01*
G37*
G36*
G01X149552D02*
X152952D01*
G02Y1382794I0J-1503D01*
G01X149552D01*
G02Y1385800I0J1503D01*
G37*
G36*
G01Y1361602D02*
X152952D01*
G02Y1358596I0J-1503D01*
G01X149552D01*
G02Y1361602I0J1503D01*
G37*
G36*
G01X253863Y1373888D02*
X257263D01*
G02Y1370882I0J-1503D01*
G01X253863D01*
G02Y1373888I0J1503D01*
G37*
G36*
G01X198512D02*
X201912D01*
G02Y1370882I0J-1503D01*
G01X198512D01*
G02Y1373888I0J1503D01*
G37*
G36*
G01Y1409998D02*
X201912D01*
G02Y1406992I0J-1503D01*
G01X198512D01*
G02Y1409998I0J1503D01*
G37*
G36*
G01X364023Y1349690D02*
X367423D01*
G02Y1346684I0J-1503D01*
G01X364023D01*
G02Y1349690I0J1503D01*
G37*
G54D76*
X978614Y1210568D03*
Y1214838D03*
X914637Y1210568D03*
Y1214838D03*
X70947Y1201565D03*
Y1205835D03*
X1822594Y1211054D03*
Y1215324D03*
G54D80*
X970071Y1409152D03*
Y1365652D03*
G54D73*
X743337Y374862D03*
G54D66*
X1819042Y-27188D03*
Y-37188D03*
Y-47188D03*
X1753686Y-85978D03*
Y-75978D03*
Y-65978D03*
X1564906Y-27086D03*
Y-47086D03*
Y-37086D03*
X1574906Y-66006D03*
Y-86006D03*
Y-76006D03*
X1534542Y-27058D03*
Y-37058D03*
Y-47058D03*
X1499186Y-65978D03*
Y-75978D03*
Y-85978D03*
X1280406Y-26956D03*
Y-46956D03*
Y-36956D03*
X1320406Y-86006D03*
Y-66006D03*
Y-76006D03*
X1248042Y-26928D03*
X1242686Y-65978D03*
Y-75978D03*
Y-85978D03*
X993906Y-26826D03*
Y-46826D03*
Y-36826D03*
X1063906Y-66006D03*
Y-86006D03*
Y-76006D03*
X964542Y-26798D03*
Y-36798D03*
X939542D03*
Y-26798D03*
X989386Y-65978D03*
Y-75978D03*
X964386D03*
Y-65978D03*
X710406Y-26826D03*
Y-36826D03*
X735406D03*
Y-26826D03*
X830406Y-66006D03*
Y-76006D03*
X855406D03*
Y-66006D03*
X1248042Y-36928D03*
Y-46928D03*
X1018906Y-36826D03*
Y-46826D03*
X1217686Y-65978D03*
Y-75978D03*
X1305406Y-36956D03*
Y-46956D03*
Y-26956D03*
X1018906Y-26826D03*
X1217686Y-85978D03*
X1223042Y-26928D03*
Y-36928D03*
X1088906Y-76006D03*
Y-86006D03*
X1345406D03*
Y-76006D03*
Y-66006D03*
X1088906D03*
X1223042Y-46928D03*
X1474186Y-65978D03*
Y-75978D03*
Y-85978D03*
X1509542Y-27058D03*
Y-37058D03*
Y-47058D03*
X1794042Y-27188D03*
Y-37188D03*
Y-47188D03*
X1728686Y-65978D03*
Y-75978D03*
Y-85978D03*
X1589906Y-37086D03*
Y-47086D03*
Y-27086D03*
X1599906Y-76006D03*
Y-86006D03*
Y-66006D03*
G54D79*
X909360Y230906D03*
Y274606D03*
G54D74*
X1729390Y144095D03*
X1627028D03*
X1169941D03*
X1067579D03*
X965217D03*
X815217D03*
G54D72*
X640522Y630650D03*
X1657510Y374862D03*
X1554695Y630650D03*
X1200423Y374862D03*
X1097608Y630650D03*
X286250Y374862D03*
X183435Y630650D03*
G54D78*
X51043Y144095D03*
X57933Y66811D03*
X153405Y144095D03*
X160295Y66811D03*
X255767Y144095D03*
X262657Y66811D03*
X358129Y144095D03*
X365019Y66811D03*
X508130Y144095D03*
X515020Y66811D03*
X610492Y144095D03*
X617382Y66811D03*
X712854Y144095D03*
X719744Y66811D03*
X822106D03*
X972106D03*
X1074468D03*
X1176830D03*
X1272302Y144095D03*
X1279192Y66811D03*
X1422303Y144095D03*
X1429193Y66811D03*
X1524665Y144095D03*
X1531555Y66811D03*
X1633917D03*
X1736279D03*
G54D71*
X736447Y630650D03*
X1650620D03*
X1561585Y374862D03*
X1193533Y630650D03*
X1104498Y374862D03*
X279360Y630650D03*
X190325Y374862D03*
G54D70*
X1817323Y56693D03*
G54D69*
X924650Y1326119D03*
X370202Y1313064D03*
X559070Y686509D03*
X561570Y694509D03*
X559070Y702509D03*
X561570Y710509D03*
X559070Y718509D03*
X460950Y326485D03*
X463950Y334359D03*
X460950Y342233D03*
X463950Y350107D03*
X937000Y313983D03*
X66856Y105949D03*
X169218D03*
X271580D03*
X373942D03*
X893284Y235040D03*
X899352Y310261D03*
X1079748Y321042D03*
X1209184Y461917D03*
X1302896Y342096D03*
X1438116Y105949D03*
X1540478D03*
X1642840D03*
X1745202D03*
X1089096Y543562D03*
X1754906Y822634D03*
X917882Y326517D03*
X212980Y485254D03*
X205680Y478168D03*
X138290Y485260D03*
X148692Y478199D03*
X788482Y476118D03*
X778080Y483179D03*
X721092Y483210D03*
X713792Y476124D03*
X1245568Y476118D03*
X1235166Y483179D03*
X1178178Y483210D03*
X1170878Y476124D03*
X1584240Y485254D03*
X1576940Y478168D03*
X1519952Y478199D03*
X1509550Y485260D03*
X35688Y127128D03*
X28388Y120042D03*
Y134215D03*
X35688Y112955D03*
X130750Y120042D03*
Y134215D03*
X148692Y421047D03*
X138290Y413987D03*
X140690Y399813D03*
X148692Y406874D03*
Y392701D03*
X138050Y127128D03*
Y112955D03*
X138290Y471087D03*
Y442333D03*
Y428160D03*
X148692Y435221D03*
X205680Y399782D03*
X212980Y406868D03*
Y392695D03*
Y471081D03*
Y435215D03*
X205680Y442302D03*
Y428128D03*
Y413955D03*
X212980Y421041D03*
X233112Y134215D03*
Y120042D03*
X240412Y127128D03*
Y112955D03*
X342774Y127128D03*
X335474Y134215D03*
Y120042D03*
X342774Y112955D03*
X533092Y127096D03*
Y112923D03*
X543494Y134209D03*
Y120035D03*
X635454Y127096D03*
Y112923D03*
X645856Y134209D03*
Y120035D03*
X748218Y134209D03*
X737816Y127096D03*
X748218Y120035D03*
X737816Y112923D03*
X721092Y469037D03*
X778080Y469006D03*
X840178Y127096D03*
Y112923D03*
X850580Y134209D03*
Y120035D03*
X990178Y127096D03*
Y112923D03*
X1000580Y134209D03*
Y120035D03*
X1092540Y127096D03*
Y112923D03*
X1102942Y134209D03*
Y120035D03*
X1178178Y469037D03*
X1205304Y134209D03*
X1194902Y127096D03*
X1205304Y120035D03*
X1194902Y112923D03*
X1235166Y469006D03*
X1297264Y127096D03*
Y112923D03*
X1307666Y134209D03*
Y120035D03*
X1399648Y120042D03*
Y134215D03*
X1406948Y127128D03*
Y112955D03*
X1509310D03*
X1509550Y428160D03*
Y413987D03*
X1511950Y399813D03*
X1502010Y134215D03*
X1509310Y127128D03*
X1502010Y120042D03*
X1519952Y421047D03*
Y406874D03*
Y392701D03*
X1509550Y471087D03*
Y442333D03*
X1519952Y435221D03*
X1576940Y442302D03*
Y428128D03*
Y413955D03*
Y399782D03*
X1584240Y421041D03*
Y406868D03*
Y392695D03*
X1604372Y134215D03*
X1611672Y127128D03*
X1604372Y120042D03*
X1611672Y112955D03*
X1584240Y471081D03*
Y435215D03*
X1706734Y134215D03*
Y120042D03*
X1714034Y127128D03*
Y112955D03*
X148692Y536506D03*
Y522333D03*
X138290Y515221D03*
X148692Y492373D03*
X138290Y529394D03*
X205680Y492341D03*
Y536475D03*
X212980Y529388D03*
Y515215D03*
X205680Y522302D03*
X713792Y612817D03*
Y598644D03*
Y584471D03*
Y570297D03*
Y534431D03*
Y520258D03*
Y490297D03*
X721092Y591557D03*
Y577384D03*
Y563210D03*
Y527344D03*
Y513171D03*
Y605730D03*
X778080Y563179D03*
Y527313D03*
Y513139D03*
Y591525D03*
Y605699D03*
Y577352D03*
X788482Y570291D03*
Y534425D03*
Y520252D03*
Y490291D03*
Y612811D03*
Y598638D03*
Y584465D03*
X1170878Y612817D03*
Y598644D03*
Y584471D03*
Y570297D03*
Y534431D03*
Y520258D03*
Y490297D03*
X1178178Y563210D03*
Y527344D03*
Y513171D03*
Y605730D03*
Y591557D03*
Y577384D03*
X1235166Y527313D03*
Y513139D03*
Y605699D03*
Y591525D03*
Y577352D03*
Y563179D03*
X1245568Y570291D03*
Y534425D03*
Y520252D03*
Y490291D03*
Y612811D03*
Y598638D03*
Y584465D03*
X1509550Y529394D03*
Y515221D03*
X1519952Y536506D03*
Y522333D03*
Y492373D03*
X1576940Y536475D03*
Y522302D03*
Y492341D03*
X1584240Y529388D03*
Y515215D03*
X7982Y1527335D03*
G54D67*
X1592187Y-71006D03*
X1582187Y-32086D03*
X1736405Y-70978D03*
X1801761Y-32188D03*
X1517261Y-32058D03*
X1481905Y-70978D03*
X1081187Y-71006D03*
X1337687D03*
X1230761Y-31928D03*
X1011187Y-31826D03*
X1297687Y-31956D03*
X1225405Y-70978D03*
X213969Y1460153D03*
Y1449153D03*
X227249Y1460153D03*
Y1449153D03*
G54D81*
X1817323Y1567323D03*
G54D68*
X1009333Y1344993D03*
X1015659Y681354D03*
X933725Y587636D03*
X933741Y596387D03*
X486837Y703006D03*
X394883Y340077D03*
X217907Y1428752D03*
X415203Y1497818D03*
X397267Y1516347D03*
X295011Y461917D03*
X523943Y105949D03*
X626305D03*
X728667D03*
X752097Y461917D03*
X831029Y105949D03*
X981029D03*
X1083391D03*
X1080351Y329955D03*
X1185753Y105949D03*
X1288115D03*
X1366535Y353200D03*
Y337452D03*
X1363535Y345326D03*
Y329578D03*
X1666271Y461919D03*
X174923Y543562D03*
X632009D03*
X1546183Y543564D03*
X385091Y1299153D03*
X454385Y1303545D03*
X940997Y333613D03*
X256705Y476124D03*
X264005Y483210D03*
X605779Y478199D03*
X595377Y485260D03*
X331395Y476118D03*
X320993Y483179D03*
X670067Y485254D03*
X662767Y478168D03*
X1127153Y485254D03*
X1119853Y478168D03*
X1062865Y478199D03*
X1052463Y485260D03*
X1702655Y476118D03*
X1692253Y483179D03*
X1635265Y483210D03*
X1627965Y476124D03*
X76005Y127096D03*
Y112923D03*
X86407Y120035D03*
Y134209D03*
X178367Y127096D03*
Y112923D03*
X188769Y134209D03*
Y120035D03*
X264005Y469037D03*
X291131Y134209D03*
Y120035D03*
X280729Y127096D03*
Y112923D03*
X320993Y469005D03*
X393493Y134209D03*
X383091Y127096D03*
X393493Y120035D03*
X383091Y112923D03*
X485475Y134215D03*
Y120042D03*
X492775Y127128D03*
Y112955D03*
X587837Y134215D03*
Y120042D03*
X597777Y399813D03*
X595137Y127128D03*
Y112955D03*
X595377Y471087D03*
Y442333D03*
Y428160D03*
Y413987D03*
X605779Y435221D03*
Y421047D03*
Y406874D03*
Y392701D03*
X670067Y435215D03*
X662767Y442302D03*
Y428128D03*
Y413955D03*
X670067Y421041D03*
X662767Y399782D03*
X670067Y406868D03*
Y392695D03*
Y471081D03*
X690199Y120042D03*
X697499Y127128D03*
X690199Y134215D03*
X697499Y112955D03*
X799861D03*
Y127128D03*
X792561Y120042D03*
Y134215D03*
X949861Y112955D03*
X942561Y120042D03*
Y134215D03*
X949861Y127128D03*
X1044923Y134215D03*
X1052223Y127128D03*
X1044923Y120042D03*
X1052223Y112955D03*
X1052463Y471087D03*
Y442333D03*
Y428160D03*
Y413987D03*
X1054863Y399813D03*
X1062865Y435221D03*
Y421047D03*
Y406874D03*
Y392701D03*
X1119853Y399782D03*
Y442302D03*
Y428128D03*
Y413955D03*
X1154585Y112955D03*
X1127153Y471081D03*
Y435215D03*
Y421041D03*
Y406868D03*
Y392695D03*
X1154585Y127128D03*
X1147285Y134215D03*
Y120042D03*
X1249647Y134215D03*
Y120042D03*
X1256947Y127128D03*
Y112955D03*
X1447265Y127096D03*
Y112923D03*
X1457667Y134209D03*
Y120035D03*
X1560029Y134209D03*
X1549627Y127096D03*
X1560029Y120035D03*
X1549627Y112923D03*
X1651989Y127096D03*
Y112923D03*
X1635265Y469037D03*
X1662391Y134209D03*
Y120035D03*
X1692253Y469006D03*
X1754351Y127096D03*
Y112923D03*
X1764753Y134209D03*
Y120035D03*
X264005Y513171D03*
X256705Y520258D03*
Y490297D03*
Y612817D03*
X264005Y591557D03*
Y605730D03*
X256705Y598644D03*
X264005Y577384D03*
X256705Y584471D03*
Y570297D03*
X264005Y563210D03*
X256705Y534431D03*
X264005Y527344D03*
X320993Y513139D03*
Y591525D03*
Y605699D03*
Y577352D03*
Y563179D03*
Y527313D03*
X331395Y490291D03*
Y612811D03*
Y598638D03*
Y584465D03*
Y570291D03*
Y534425D03*
Y520252D03*
X595377Y529394D03*
Y515221D03*
X605779Y536506D03*
Y522333D03*
Y492373D03*
X670067Y529388D03*
X662767Y536475D03*
Y522302D03*
X670067Y515215D03*
X662767Y492341D03*
X1052463Y529394D03*
Y515221D03*
X1062865Y536506D03*
Y522333D03*
Y492373D03*
X1119853Y536475D03*
Y522302D03*
Y492341D03*
X1127153Y529388D03*
Y515215D03*
X1627965Y584471D03*
Y570297D03*
Y534431D03*
Y520258D03*
Y490297D03*
Y612817D03*
Y598644D03*
X1635265Y527344D03*
Y513171D03*
Y605730D03*
Y591557D03*
Y577384D03*
Y563210D03*
X1692253Y605699D03*
Y591525D03*
Y577352D03*
Y563179D03*
Y527313D03*
Y513139D03*
X1702655Y534425D03*
Y520252D03*
Y490291D03*
Y612811D03*
Y598638D03*
Y584465D03*
Y570291D03*
G54D77*
X770472Y1490945D03*
X820079Y388583D03*
X1020866D03*
X1070472Y1490945D03*
G54D65*
X19685Y-83298D03*
X1821260D03*
X26789Y1373669D03*
X1796847Y1517889D03*
X1809883Y120792D03*
X184851Y334492D03*
X19685Y1801195D03*
X1821260D03*
G54D75*
X1030905Y1066535D03*
Y1263386D03*
X810038Y1066535D03*
Y1263386D03*
X573818Y1066535D03*
Y1263386D03*
X352952Y1066535D03*
Y1263386D03*
X116731Y1066535D03*
Y1263386D03*
X1724212Y1066535D03*
Y1263386D03*
X1487991Y1066535D03*
Y1263386D03*
X1267125Y1066535D03*
Y1263386D03*
%LPC*%
G75*
G36*
G01X940026Y1577634D02*
G03X940910Y1577268I884J885D01*
G01X956342D01*
G02X956484Y1577209I0J-200D01*
G01X959830Y1573863D01*
G02X959889Y1573721I-141J-142D01*
G01Y1543680D01*
G03X960255Y1542796I1251J0D01*
G01X964295Y1538756D01*
G03X965179Y1538390I884J885D01*
G01X1019906D01*
G02X1020048Y1538331I0J-200D01*
G01X1031515Y1526864D01*
G02X1031574Y1526722I-141J-142D01*
G01Y1492904D01*
G02X1031515Y1492762I-200J0D01*
G01X1031368Y1492615D01*
G02X1031226Y1492556I-142J141D01*
G01X947183D01*
G02X947041Y1492615I0J200D01*
G01X944876Y1494780D01*
G03X943992Y1495146I-884J-885D01*
G01X933579D01*
G03X932695Y1494780I0J-1251D01*
G01X917141Y1479226D01*
G03X916775Y1478342I885J-884D01*
G01Y1465020D01*
G02X916716Y1464878I-200J0D01*
G01X914188Y1462350D01*
G03X913822Y1461466I885J-884D01*
G01Y1460928D01*
G02X913763Y1460786I-200J0D01*
G01X913527Y1460550D01*
G03X913161Y1459666I885J-884D01*
G01Y1446448D01*
G02X913102Y1446306I-200J0D01*
G01X912955Y1446159D01*
G02X912813Y1446100I-142J141D01*
G01X900559D01*
G02X900417Y1446159I0J200D01*
G01X900270Y1446306D01*
G02X900211Y1446448I141J142D01*
G01Y1459640D01*
G03X899845Y1460524I-1251J0D01*
G01X899532Y1460837D01*
G02X899473Y1460979I141J142D01*
G01Y1462024D01*
G03X899107Y1462908I-1251J0D01*
G01X894403Y1467612D01*
G02X894344Y1467754I141J142D01*
G01Y1473096D01*
G03X893978Y1473980I-1251J0D01*
G01X888953Y1479005D01*
G03X888069Y1479371I-884J-885D01*
G01X880504D01*
G03X879620Y1479005I0J-1251D01*
G01X872265Y1471650D01*
G03X871899Y1470766I885J-884D01*
G01Y1460991D01*
G02X871840Y1460849I-200J0D01*
G01X871502Y1460511D01*
G03X871136Y1459627I885J-884D01*
G01Y1446423D01*
G02X871077Y1446281I-200J0D01*
G01X870968Y1446172D01*
G02X870826Y1446113I-142J141D01*
G01X858702D01*
G02X858560Y1446172I0J200D01*
G01X858139Y1446593D01*
G02X858080Y1446735I141J142D01*
G01Y1459524D01*
G03X857714Y1460408I-1251J0D01*
G01X853660Y1464462D01*
G03X852776Y1464828I-884J-885D01*
G01X828441D01*
G03X827557Y1464462I0J-1251D01*
G01X827039Y1463944D01*
G03X826673Y1463060I885J-884D01*
G01Y1461847D01*
G02X826614Y1461705I-200J0D01*
G01X826571Y1461662D01*
G02X826429Y1461603I-142J141D01*
G01X825036D01*
G03X824152Y1461237I0J-1251D01*
G01X821533Y1458618D01*
G02X821391Y1458559I-142J141D01*
G01X820451D01*
G03X819567Y1458193I0J-1251D01*
G01X819360Y1457986D01*
G03X818994Y1457102I885J-884D01*
G01Y1446462D01*
G02X818935Y1446320I-200J0D01*
G01X818826Y1446211D01*
G02X818684Y1446152I-142J141D01*
G01X806393D01*
G02X806251Y1446211I0J200D01*
G01X806063Y1446399D01*
G02X806004Y1446541I141J142D01*
G01Y1459828D01*
G02X806063Y1459970I200J0D01*
G01X806195Y1460102D01*
G03X806561Y1460986I-885J884D01*
G01Y1474310D01*
G02X806615Y1474447I200J0D01*
G03X806950Y1475299I-916J852D01*
G01Y1523715D01*
G02X807009Y1523857I200J0D01*
G01X816830Y1533678D01*
G03X817196Y1534562I-885J884D01*
G01Y1620853D01*
G02X817255Y1620995I200J0D01*
G01X822528Y1626268D01*
G02X822670Y1626327I142J-141D01*
G01X927565D01*
G02X927707Y1626268I0J-200D01*
G01X932114Y1621861D01*
G02X932173Y1621719I-141J-142D01*
G01Y1586005D01*
G03X932539Y1585121I1251J0D01*
G01X940026Y1577634D01*
G37*
G36*
G01X953110Y1480583D02*
G03X953130Y1480563I894J874D01*
G02X953192Y1480419I-138J-145D01*
G01Y1451442D01*
G02X953133Y1451300I-200J0D01*
G01X952668Y1450835D01*
G02X952526Y1450776I-142J141D01*
G01X930592D01*
G02X930450Y1450835I0J200D01*
G01X929621Y1451664D01*
G02X929562Y1451806I141J142D01*
G01Y1480891D01*
G02X929621Y1481033I200J0D01*
G01X930418Y1481830D01*
G02X930560Y1481889I142J-141D01*
G01X951737D01*
G02X951894Y1481812I-1J-200D01*
G03X951995Y1481698I984J770D01*
G01X953110Y1480583D01*
G37*
G36*
G01X955751Y1485453D02*
X957168Y1486870D01*
G02X957310Y1486929I142J-141D01*
G01X1045732D01*
G02X1045874Y1486870I0J-200D01*
G01X1046659Y1486085D01*
G02X1046718Y1485943I-141J-142D01*
G01Y1452303D01*
G02X1046659Y1452161I-200J0D01*
G01X1045333Y1450835D01*
G02X1045191Y1450776I-142J141D01*
G01X956304D01*
G02X956162Y1450835I0J200D01*
G01X955751Y1451246D01*
G02X955692Y1451388I141J142D01*
G01Y1485311D01*
G02X955751Y1485453I200J0D01*
G37*
%LPD*%
G75*
G54D15*
X7271Y70981D03*
X11011Y79720D03*
X8786Y88425D03*
X14264Y94236D03*
X10292D03*
X12786Y87903D03*
X18000Y90000D03*
X18298Y102141D03*
X8000Y102500D03*
X10131Y115473D03*
X15143Y115581D03*
X14996Y133034D03*
X11442Y132719D03*
X19855Y133000D03*
X9082Y135789D03*
X19855Y141362D03*
X11999Y141415D03*
X15948Y141267D03*
X10966Y162073D03*
Y159073D03*
X16909Y153263D03*
X12247Y166341D03*
X17313Y166937D03*
X21909Y153263D03*
X22335Y166721D03*
X16709Y175943D03*
X19572Y219470D03*
Y221970D03*
X10259Y218085D03*
X13059D03*
X19638Y226320D03*
X16859Y216385D03*
X19572Y216970D03*
X22599Y228646D03*
X18206Y244571D03*
X15586Y249108D03*
X13715Y259381D03*
X8970Y254871D03*
X18206Y264571D03*
X7036Y272371D03*
X8335Y280663D03*
X14807Y282181D03*
X15586Y269108D03*
X15499Y288542D03*
X17033Y1006819D03*
X14357Y1009906D03*
X20216Y1009748D03*
X14197Y1014205D03*
Y1017759D03*
X20197Y1014205D03*
Y1017759D03*
X12599Y1438143D03*
X16304Y1468196D03*
X15889Y1494254D03*
X10089D03*
X6489Y1501334D03*
X19745Y1508846D03*
X19735Y1530499D03*
X19859Y1520657D03*
X6951Y1538547D03*
X18879Y1534334D03*
X10367Y1553080D03*
X32350Y67562D03*
X28442Y55340D03*
X32350Y59562D03*
Y63562D03*
X26588Y97667D03*
X35442D03*
X35048Y103411D03*
X22439Y102495D03*
X35207Y106561D03*
X22935Y162073D03*
Y159073D03*
X26565Y177448D03*
X32507Y180517D03*
X30567Y195176D03*
X28067D03*
X25567D03*
X33067D03*
X29585Y199248D03*
X32585D03*
X29921Y206806D03*
X32585Y202048D03*
X25648Y210509D03*
X28148D03*
X29585Y201748D03*
X27421Y206806D03*
X27340Y230556D03*
X36185Y230117D03*
X31595Y227824D03*
X32201Y238714D03*
X23844Y239299D03*
X21556Y232971D03*
X31682Y246874D03*
X33902Y244297D03*
X26325Y262078D03*
X25549Y256394D03*
X31682Y266874D03*
X29116Y281129D03*
X37117Y279991D03*
X25549Y276394D03*
X34845Y291756D03*
X26629Y295619D03*
X35650Y491982D03*
Y495982D03*
X30177Y534211D03*
X34359Y541135D03*
X34732Y534909D03*
X25819Y527726D03*
Y548726D03*
X34425Y546553D03*
X34448Y552726D03*
X25819Y544726D03*
X30123Y611071D03*
X27686Y621311D03*
X36494Y616905D03*
X36306Y622285D03*
X27686Y629311D03*
Y625311D03*
X36692Y633724D03*
X36575Y627713D03*
X35293Y662952D03*
X35250Y671508D03*
X34565Y699082D03*
X36529Y1006321D03*
X30479Y1006509D03*
X24456Y1006401D03*
X32093Y1009748D03*
X26155Y1009985D03*
X29197Y1014205D03*
X32197Y1017759D03*
X26197D03*
X35197Y1014205D03*
X21196Y1065529D03*
Y1063029D03*
X36089Y1062601D03*
Y1065101D03*
X35925Y1075663D03*
X33425D03*
X28996Y1065529D03*
X23796D03*
X26396D03*
Y1063029D03*
X23796D03*
X28996D03*
X28606Y1082678D03*
X23406D03*
X26006D03*
Y1080178D03*
X23406D03*
X28606D03*
X20806Y1082678D03*
Y1080178D03*
X21321Y1098769D03*
X26521D03*
X29121D03*
X23921D03*
Y1101335D03*
X29121D03*
X26521D03*
X21321D03*
X32574Y1111633D03*
X29874D03*
X27274D03*
X24674D03*
Y1121333D03*
X27274D03*
X29874D03*
X32574D03*
X24674Y1130333D03*
X21974D03*
X21209Y1138705D03*
X23709D03*
X31631Y1198651D03*
X29860Y1438552D03*
X23603Y1449735D03*
X29880Y1441702D03*
X33189Y1501373D03*
X22381Y1554152D03*
X26231Y1554167D03*
X45988Y90512D03*
X51550Y90615D03*
X48476Y180812D03*
X48643Y442919D03*
X48596Y451419D03*
X45643Y472905D03*
X41643Y473419D03*
X49643Y472905D03*
Y464419D03*
X41643Y464919D03*
X48390Y485128D03*
X51239Y485138D03*
X40009Y481467D03*
X43948Y492108D03*
X44563Y482165D03*
X39801Y504825D03*
X42301D03*
X44801D03*
X43804Y500202D03*
X45256Y495993D03*
X45293Y522569D03*
X39742Y517401D03*
X42242D03*
X44742D03*
X46993Y529169D03*
X41408Y531882D03*
X43908D03*
X45293Y525369D03*
X46408Y531882D03*
X38358Y531948D03*
X52869Y537958D03*
X46643Y555194D03*
X52869Y540458D03*
X43843Y555194D03*
X46643Y571194D03*
X43843D03*
Y563194D03*
X46643D03*
X51000Y581222D03*
X45400D03*
X48200D03*
X51000Y591215D03*
X45400D03*
X48200D03*
X51172Y607762D03*
X48372D03*
X45572D03*
Y610562D03*
X48372D03*
X51172D03*
X40362Y610548D03*
X54192Y633473D03*
X42172Y633716D03*
X49192Y628078D03*
X47179Y633736D03*
X37847Y662910D03*
X39549Y682108D03*
X36910D03*
X37804Y671508D03*
X40165Y699082D03*
X37365D03*
X49249Y837718D03*
X52349D03*
X46049D03*
X53549Y843118D03*
X52077Y905295D03*
X48429Y916430D03*
X47264Y919649D03*
X48683Y1006510D03*
X42470Y1006738D03*
X50541Y1009589D03*
X44999Y1009510D03*
X38823Y1009273D03*
X47197Y1014205D03*
X41197D03*
X44197Y1017759D03*
X38197D03*
X48704Y1017982D03*
X43889Y1062601D03*
X38689D03*
X41289D03*
Y1065101D03*
X38689D03*
X43889D03*
X47314Y1072228D03*
X41172Y1079064D03*
X46166Y1093757D03*
X39659Y1105100D03*
X42259D03*
X44859D03*
X47559D03*
X48585Y1123867D03*
X47559Y1114800D03*
X44859D03*
X42259D03*
X39659D03*
X48547Y1133688D03*
X51047D03*
X55188Y1205179D03*
X51023Y1201416D03*
X48842Y1211109D03*
X53479Y1216256D03*
X43198Y1254055D03*
X45698D03*
X48198D03*
X45698Y1251555D03*
X43198D03*
X48198D03*
X47621Y1343672D03*
X48089Y1501387D03*
X39095Y1501361D03*
X47074Y1555923D03*
X40951Y1555932D03*
X64785Y79993D03*
Y82593D03*
Y85193D03*
Y74793D03*
Y77393D03*
X64829Y92874D03*
X55871Y99961D03*
X55921Y95236D03*
X66856Y104249D03*
Y107649D03*
X66478Y162368D03*
X63878D03*
X69261Y211695D03*
Y208695D03*
X65189Y210713D03*
Y213213D03*
Y208213D03*
X54733Y212978D03*
Y215478D03*
Y207978D03*
Y210478D03*
X65189Y215713D03*
X57987Y258880D03*
X60562Y264180D03*
X58062D03*
X66956Y267526D03*
Y270026D03*
X54167Y457339D03*
X56667D03*
X65737Y445603D03*
X57857Y446071D03*
X56667Y459839D03*
X54167D03*
Y462339D03*
X56667D03*
X62224Y473045D03*
X67670Y464818D03*
X58224Y465004D03*
X63154Y462371D03*
X55124Y478625D03*
X53739Y485138D03*
X56239D03*
X56824Y482425D03*
X55124Y475825D03*
X62700Y491214D03*
X66403Y495487D03*
X62700Y493714D03*
X66403Y492987D03*
X68202Y537877D03*
X56572Y539731D03*
X68202Y542877D03*
Y545377D03*
Y540377D03*
X61330Y544895D03*
X56572Y542231D03*
X64130Y541895D03*
Y544895D03*
X61630Y541895D03*
X68188Y548358D03*
X64408Y582747D03*
X63859Y590801D03*
X67684Y597232D03*
X63684Y597130D03*
X67684Y605637D03*
X61854Y617853D03*
Y620653D03*
X53972Y607762D03*
Y610562D03*
X59684Y605443D03*
X63684D03*
X66530Y625013D03*
X58181Y627908D03*
X64692Y642184D03*
X56049Y827218D03*
X68649D03*
X69049Y847718D03*
X65549Y850718D03*
X68598Y859415D03*
X68778Y873821D03*
X63969Y869475D03*
X63930Y874694D03*
X68100Y910122D03*
X71528Y913190D03*
X64632Y901500D03*
X59962Y910251D03*
X53197Y1014205D03*
Y1017759D03*
X55699Y1072761D03*
X61588Y1074481D03*
X62109Y1087656D03*
Y1084656D03*
Y1079656D03*
Y1091656D03*
X60269Y1198820D03*
X63094Y1207604D03*
X55596Y1210466D03*
X68245Y1212054D03*
X58443Y1272257D03*
X54843Y1501625D03*
X60227Y1514751D03*
X60277Y1528395D03*
X55862Y1541791D03*
X65478Y1541980D03*
X60303Y1534436D03*
X60747Y1555890D03*
X64747D03*
X60864Y1583484D03*
X58064D03*
X55264D03*
X69816Y1592527D03*
X60554Y1615152D03*
X73110Y98551D03*
X77804Y95879D03*
X76660Y103783D03*
X75194Y141247D03*
X71422Y147540D03*
X82661Y143740D03*
X80041Y148277D03*
X73578Y165393D03*
Y162793D03*
Y170493D03*
Y167993D03*
X80502Y177616D03*
X81083Y172190D03*
X72575Y181426D03*
X75786Y181366D03*
X78581Y181009D03*
X83756Y168697D03*
X84844Y191941D03*
X75400Y184012D03*
X72783Y184221D03*
X72061Y208695D03*
X71761Y211695D03*
X76819Y213859D03*
Y211359D03*
X80522Y213132D03*
Y215632D03*
X80766Y256303D03*
X75438Y265701D03*
X85541Y266114D03*
X80525Y265896D03*
X72256Y267526D03*
X69756D03*
Y270026D03*
X72256D03*
X83014Y281982D03*
X77073Y281716D03*
X71130Y462152D03*
Y459652D03*
Y464652D03*
X73630Y459652D03*
Y462152D03*
Y464652D03*
X78033Y491133D03*
X71461Y498151D03*
Y495151D03*
X73961D03*
X78033Y498633D03*
Y496133D03*
Y493633D03*
X73961Y498151D03*
X78133Y553297D03*
Y555897D03*
X75688Y548358D03*
X73188D03*
X70688D03*
X78133Y558497D03*
Y566597D03*
Y563697D03*
Y561097D03*
X72128Y570686D03*
X74923Y570478D03*
X75340Y576484D03*
X74983Y573689D03*
X72337Y573303D03*
X78733Y578405D03*
X84159Y578986D03*
X83684Y596729D03*
X72515Y596089D03*
X77734Y596782D03*
X81740Y619758D03*
Y616958D03*
Y614158D03*
X69670Y619513D03*
Y616713D03*
Y613913D03*
X79684Y605443D03*
X82648Y670679D03*
X73914Y660107D03*
X79043Y667391D03*
X84845Y659857D03*
X84314Y686107D03*
X82562Y680037D03*
X78735Y683426D03*
X72149Y827318D03*
X74349Y824718D03*
Y821918D03*
X74700Y842890D03*
X84367Y878286D03*
X76528Y878533D03*
X74028Y889065D03*
X83079Y888515D03*
X72035Y898346D03*
X80339Y897943D03*
X76203Y897910D03*
X80593Y946082D03*
X78167Y949261D03*
X76332Y953421D03*
X87632Y1007522D03*
X70059Y1075656D03*
X70302Y1067656D03*
X77734Y1095676D03*
X70947Y1201565D03*
Y1205835D03*
X71006Y1228684D03*
X71020Y1224323D03*
X74909Y1593009D03*
X71910Y1625009D03*
X78291Y1625743D03*
X83689Y1624736D03*
X82291Y1633801D03*
X78291D03*
X70291D03*
X91224Y141247D03*
X92337Y144172D03*
X95711Y143518D03*
X94811Y152373D03*
X97961Y152562D03*
X103456Y157370D03*
X98826Y172665D03*
X98763Y178560D03*
X98653Y183834D03*
X99639Y186629D03*
X98943Y200864D03*
X92898Y192490D03*
X98173Y190185D03*
X89353Y206767D03*
X86853D03*
X91853D03*
X98966Y207037D03*
X99032Y212455D03*
X89483Y221708D03*
X86983D03*
X86398Y224421D03*
X88098Y231021D03*
Y228221D03*
X96333Y221642D03*
X91983Y221708D03*
X103841Y228631D03*
X93649Y236189D03*
X91149D03*
X88649D03*
X91090Y248765D03*
X88590D03*
X93590D03*
X97747Y265897D03*
X100247D03*
X94087Y270695D03*
X91287D03*
X88787D03*
Y268195D03*
X91287D03*
X94087D03*
X98255Y374510D03*
X100120Y377898D03*
X100066Y381976D03*
X86788Y581659D03*
X87684Y605443D03*
X95973Y655660D03*
X92897Y658359D03*
X95917Y658374D03*
X95539Y664443D03*
X86289Y822088D03*
X86367Y848086D03*
X90000Y871389D03*
X103770Y868206D03*
X103692Y900295D03*
X91387Y905295D03*
X100058Y977651D03*
X99836Y980330D03*
X103836Y988813D03*
X100200Y988800D03*
X95836Y988813D03*
X85706Y998507D03*
X94398Y1006648D03*
X101025Y1009655D03*
X94586Y1023900D03*
X91765Y1018307D03*
X88007Y1013678D03*
X88479Y1023731D03*
X88287Y1026537D03*
X97609Y1018469D03*
X90450Y1033542D03*
X93496Y1547768D03*
X107364Y116594D03*
X118307Y110784D03*
X113307D03*
X107364Y119594D03*
X117886Y124663D03*
X112864Y124879D03*
X107798Y124283D03*
X119230Y138838D03*
X106205Y161306D03*
X107540Y176665D03*
Y168665D03*
Y196665D03*
Y192665D03*
X107653Y186778D03*
X107572Y204864D03*
Y208864D03*
X112621Y218085D03*
X115421D03*
X103213Y219379D03*
X117948Y249108D03*
X109329Y248371D03*
X111993Y710102D03*
X120250Y758841D03*
X113505Y796856D03*
X109591Y796905D03*
X102355Y874267D03*
X102947Y877196D03*
X102320Y891043D03*
X110887Y884000D03*
X103972Y977609D03*
X103836Y980330D03*
X111836Y988813D03*
X119836D03*
X115836D03*
X107836D03*
X103825Y1009655D03*
X105971Y1025745D03*
X114770Y1016827D03*
X110409Y1024094D03*
X114770Y1029427D03*
X110970Y1030672D03*
X101970D03*
X104970D03*
X107970D03*
X102761Y1096233D03*
X108971Y1109564D03*
X103124D03*
Y1122164D03*
X108971D03*
X103124Y1134764D03*
X108971D03*
X103124Y1147364D03*
X108971D03*
X103124Y1172564D03*
X108971D03*
X103124Y1159964D03*
X108971D03*
X103861Y1182703D03*
X118533Y1207737D03*
X112048Y1214372D03*
X107803Y1218169D03*
X128950Y97667D03*
X133200Y95111D03*
X124606Y102495D03*
X119333Y116594D03*
Y119594D03*
X122867Y125107D03*
X124340Y142862D03*
X131481Y143762D03*
X125381Y148717D03*
X131947Y199248D03*
X127929Y195176D03*
X130429D03*
X132929D03*
X134947Y199248D03*
X128010Y210509D03*
X130510D03*
X132283Y206806D03*
X129783D03*
X131947Y201748D03*
X122000Y226320D03*
X119221Y216385D03*
X121934Y216970D03*
Y219470D03*
Y221970D03*
X129702Y230556D03*
X133957Y227824D03*
X124961Y228646D03*
X128687Y242078D03*
X123918Y232971D03*
X134044Y246874D03*
X120568Y244571D03*
X127911Y256394D03*
X126131Y359511D03*
X125753Y365856D03*
X119099Y755052D03*
X118467Y796785D03*
X122437Y860775D03*
X125698Y857515D03*
X122432Y857540D03*
X129666Y857514D03*
X133424Y857303D03*
X122887Y888000D03*
X123387Y892000D03*
X135836Y988813D03*
X131836D03*
X123836D03*
X127836D03*
X120617Y1029427D03*
Y1016827D03*
X133579Y1097469D03*
X124925Y1102091D03*
X130380Y1105091D03*
X124880D03*
X124925Y1114691D03*
Y1127291D03*
X124880Y1117691D03*
X130380D03*
X124925Y1139891D03*
X124880Y1130291D03*
X130380D03*
X130434Y1144964D03*
X124474Y1142997D03*
X130380Y1155491D03*
X124880D03*
X124925Y1152491D03*
X124474Y1168197D03*
X130434Y1170164D03*
X124925Y1165091D03*
Y1177691D03*
X131000Y1180266D03*
X124765Y1180691D03*
X135757Y1221407D03*
X135448Y1229402D03*
Y1234921D03*
X126433Y1230407D03*
X129250Y1227650D03*
X137410Y103411D03*
X137804Y97667D03*
X148600Y90650D03*
X148350Y95236D03*
X137569Y106561D03*
X135429Y195176D03*
X134947Y202048D03*
X138547Y230117D03*
X134563Y238714D03*
X138664Y241699D03*
X148061Y378600D03*
Y382600D03*
X148176Y458711D03*
X148940Y455921D03*
X145376Y458711D03*
X147520Y463600D03*
X142024Y552466D03*
X147925Y603600D03*
Y619600D03*
Y623600D03*
X149469Y634190D03*
X152658Y645389D03*
X136862Y857244D03*
X147836Y988813D03*
X139836D03*
X151836D03*
X143836D03*
X142026Y1012354D03*
X136571Y1009354D03*
X136526Y1012354D03*
X136571Y1021954D03*
X142026Y1024954D03*
X136526D03*
X144640Y1039439D03*
X150952Y1040115D03*
X146595Y1053457D03*
X136432Y1224472D03*
X167191Y92874D03*
X153912Y90615D03*
X158283Y95236D03*
X158233Y99961D03*
X166240Y162368D03*
X157095Y210478D03*
Y207978D03*
Y215478D03*
Y212978D03*
X160424Y264180D03*
X162924D03*
X160349Y258880D03*
X164496Y309405D03*
X150703Y453682D03*
X159836Y988813D03*
X155836Y997860D03*
X160733Y1056594D03*
X153693Y1051037D03*
X160547Y1049283D03*
X160627Y1053561D03*
X160807Y1043955D03*
X166188Y1066551D03*
X163191Y1065313D03*
X159228Y1065613D03*
X165649Y1159350D03*
Y1151870D03*
X167147Y77393D03*
Y74793D03*
Y85193D03*
Y82593D03*
Y79993D03*
X175472Y98551D03*
X179022Y103783D03*
X169218Y107649D03*
Y104249D03*
X173784Y147540D03*
X177556Y141247D03*
X185023Y143740D03*
X182403Y148277D03*
X175940Y162793D03*
Y165393D03*
X168840Y162368D03*
X175940Y167993D03*
Y170493D03*
X178148Y181366D03*
X180943Y181009D03*
X174937Y181426D03*
X182864Y177616D03*
X183445Y172190D03*
X175145Y184221D03*
X177762Y184012D03*
X171623Y211695D03*
X182884Y213132D03*
X179181Y211359D03*
Y213859D03*
X174123Y211695D03*
X167551Y208213D03*
Y213213D03*
Y210713D03*
X171623Y208695D03*
X174423D03*
X167551Y215713D03*
X182884Y215632D03*
X177800Y265701D03*
X182887Y265896D03*
X174618Y267526D03*
Y270026D03*
X169318Y267526D03*
X172118D03*
Y270026D03*
X169318D03*
X179435Y281716D03*
X170215Y311671D03*
X175615Y550907D03*
X173115D03*
X175615Y553407D03*
X173115D03*
X174923Y545263D03*
Y541863D03*
X177385Y566929D03*
X171339Y572070D03*
X172686Y569928D03*
X175033Y570962D03*
X174776Y568475D03*
X177099Y569426D03*
X169389Y1155610D03*
X191568Y76587D03*
Y72615D03*
X193007Y100625D03*
X186026Y97475D03*
X185957Y106186D03*
X197380Y112083D03*
X193586Y141247D03*
X198073Y143518D03*
X197173Y152373D03*
X201015Y183834D03*
X201125Y178560D03*
X186118Y168697D03*
X201188Y172665D03*
X187206Y191941D03*
X195260Y192490D03*
X200535Y190185D03*
X201305Y200864D03*
X189215Y206767D03*
X191715D03*
X194215D03*
X201394Y212455D03*
X201328Y207037D03*
X194345Y221708D03*
X198695Y221642D03*
X190460Y228221D03*
Y231021D03*
X191845Y221708D03*
X188760Y224421D03*
X189345Y221708D03*
X191011Y236189D03*
X193511D03*
X196011D03*
X190952Y248765D03*
X193452D03*
X195952D03*
X183128Y256303D03*
X187903Y266114D03*
X196449Y268195D03*
X193649D03*
X196449Y270695D03*
X193649D03*
X191149D03*
Y268195D03*
X185376Y281982D03*
X185328Y545528D03*
X194063Y577716D03*
X191125Y610400D03*
X203248Y55513D03*
X199473Y68581D03*
X205848Y60513D03*
X208645Y60369D03*
X199486Y80581D03*
X214389Y86012D03*
X203616Y88801D03*
X214389Y94374D03*
X206533Y94351D03*
X210482Y94279D03*
X209530Y86046D03*
X205976Y85731D03*
X209726Y116594D03*
X201669Y103621D03*
X215669Y110784D03*
X209726Y119594D03*
X210160Y124283D03*
X215226Y124879D03*
X208567Y161306D03*
X200323Y152562D03*
X205818Y157370D03*
X209902Y176665D03*
Y168665D03*
X202001Y186629D03*
X209902Y196665D03*
Y192665D03*
X210015Y186778D03*
X209934Y204864D03*
Y208864D03*
X214983Y218085D03*
X205575Y219379D03*
X206203Y228631D03*
X211691Y248371D03*
X200109Y265897D03*
X202609D03*
X204675Y382109D03*
X204674Y551683D03*
Y558917D03*
Y561420D03*
X200495Y577937D03*
X208500Y595500D03*
X203500Y606929D03*
X208000Y604567D03*
X203460Y618400D03*
X203741Y612592D03*
X209158Y610072D03*
X209094Y616317D03*
X208540Y621591D03*
X205941Y668934D03*
X201115Y695581D03*
X203046Y693716D03*
X231312Y97667D03*
X221695Y116594D03*
X226968Y102495D03*
X220669Y110784D03*
X221695Y119594D03*
X225229Y125107D03*
X220248Y124663D03*
X226702Y142862D03*
X227743Y148717D03*
X221592Y138838D03*
X230291Y195176D03*
X230372Y210509D03*
X224362Y226320D03*
X224296Y216970D03*
Y219470D03*
Y221970D03*
X221583Y216385D03*
X217783Y218085D03*
X232064Y230556D03*
X227323Y228646D03*
X231049Y242078D03*
X226280Y232971D03*
X220310Y249108D03*
X222930Y244571D03*
X233417Y253198D03*
X230842Y313888D03*
X233258Y359186D03*
X228267Y396718D03*
X221375Y455024D03*
X220349Y465622D03*
X225500Y530000D03*
X225000Y540500D03*
X224000Y547075D03*
X224200Y549800D03*
X223500Y568000D03*
X224104Y562800D03*
X224040Y558800D03*
X221693Y594982D03*
X222289Y590895D03*
X220333Y617930D03*
X220255Y629749D03*
X217906Y1430452D03*
Y1427052D03*
X219525Y1440028D03*
X216125D03*
X224780Y1478149D03*
X217985Y1483055D03*
X225765Y1471985D03*
X233313Y1476699D03*
X221899Y1488800D03*
X218021Y1494724D03*
X222843Y1498442D03*
X217614Y1489671D03*
X233180Y1486442D03*
X233166Y1491454D03*
X226135Y1502442D03*
X230758Y1505046D03*
X226971Y1514578D03*
X227552Y1530675D03*
X232622Y1531104D03*
X226971Y1522578D03*
X219981Y1530797D03*
X223322Y1518578D03*
X222119Y1539941D03*
X227882Y1540816D03*
X233753Y1539752D03*
X239772Y103411D03*
X240166Y97667D03*
X235562Y95111D03*
X239931Y106561D03*
X233843Y143762D03*
X232791Y195176D03*
X235291D03*
X237309Y199248D03*
X234309D03*
X237791Y195176D03*
X237309Y202048D03*
X232872Y210509D03*
X234645Y206806D03*
X232145D03*
X234309Y201748D03*
X240909Y230117D03*
X236319Y227824D03*
X236925Y238714D03*
X236406Y246874D03*
X238626Y244297D03*
X234986Y336161D03*
X236264Y342494D03*
X245362Y546712D03*
Y542712D03*
X247536Y602689D03*
X247278Y618288D03*
X243278D03*
X240194Y643113D03*
X242102Y656321D03*
X250102D03*
X246102D03*
X245000Y678462D03*
X244267Y696911D03*
X235790Y754332D03*
X241204Y814841D03*
X237591Y815266D03*
X248556Y824003D03*
X246311Y819000D03*
X238400Y836900D03*
X234976Y1481676D03*
X243535Y1511473D03*
X245500Y1517033D03*
X237633Y1511909D03*
X244600Y1531700D03*
X240808Y1519942D03*
X235687Y1522578D03*
X237580Y1528604D03*
X245937Y1524237D03*
X239949Y1541327D03*
X244912Y1539389D03*
X250962Y90650D03*
X256274Y90615D03*
X260595Y99961D03*
X260645Y95236D03*
X250712D03*
X259457Y210478D03*
Y207978D03*
Y215478D03*
Y212978D03*
X262786Y264180D03*
X262711Y258880D03*
X257993Y307994D03*
X256475Y422088D03*
X252695Y442956D03*
X254512Y438323D03*
X261965Y458455D03*
X250336Y456386D03*
X254678Y445873D03*
X263301Y444232D03*
X262526Y451108D03*
X249125Y465874D03*
X252688Y636364D03*
X248690Y678519D03*
X248090Y691114D03*
X254634Y698241D03*
X248506Y812042D03*
X256303Y812254D03*
X250700Y819900D03*
X254058Y819851D03*
X255289Y824340D03*
X252305Y831018D03*
X252100Y836800D03*
X250876Y1532782D03*
X255909Y1542043D03*
X250790Y1539759D03*
X269509Y77393D03*
Y74793D03*
Y85193D03*
Y82593D03*
Y79993D03*
X277834Y98551D03*
X269553Y92874D03*
X271580Y107649D03*
Y104249D03*
X276146Y147540D03*
X279918Y141247D03*
X268602Y162368D03*
X271202D03*
X278302Y162793D03*
Y165393D03*
Y167993D03*
Y170493D03*
X277299Y181426D03*
X280124Y184012D03*
X277507Y184221D03*
X269913Y210713D03*
X273985Y208695D03*
X276785D03*
X273985Y211695D03*
X276485D03*
X269913Y208213D03*
Y213213D03*
Y215713D03*
X265286Y264180D03*
X280162Y265701D03*
X276980Y267526D03*
Y270026D03*
X271680Y267526D03*
X274480D03*
Y270026D03*
X271680D03*
X281797Y281716D03*
X277575Y395084D03*
X274425Y381500D03*
X278784Y435158D03*
X278529Y440489D03*
X274949Y442606D03*
X278827Y444841D03*
X282230Y458572D03*
X265011Y453881D03*
X280220Y448493D03*
X274866Y446606D03*
X265011Y446595D03*
X275873Y463479D03*
X276344Y467367D03*
X274096Y820725D03*
X274697Y830951D03*
X275123Y847874D03*
X269700Y853100D03*
X275400Y864400D03*
X278400Y890839D03*
X275400Y899400D03*
X279261Y926339D03*
X278739Y936439D03*
X289797Y36735D03*
X290113Y23188D03*
X284666Y34068D03*
X289631Y28281D03*
X293930Y76587D03*
Y72615D03*
X295369Y100625D03*
X288388Y97475D03*
X281384Y103783D03*
X288319Y106186D03*
X295948Y141247D03*
X287385Y143740D03*
X284765Y148277D03*
X285807Y172190D03*
X280510Y181366D03*
X283305Y181009D03*
X288480Y168697D03*
X285226Y177616D03*
X289568Y191941D03*
X297622Y192490D03*
X291577Y206767D03*
X294077D03*
X296577D03*
X285246Y213132D03*
X281543Y211359D03*
Y213859D03*
X296707Y221708D03*
X292822Y228221D03*
Y231021D03*
X294207Y221708D03*
X291122Y224421D03*
X291707Y221708D03*
X285246Y215632D03*
X293373Y236189D03*
X295873D03*
X293314Y248765D03*
X295814D03*
X285490Y256303D03*
X290265Y266114D03*
X285249Y265896D03*
X296011Y270695D03*
X293511D03*
Y268195D03*
X296011D03*
X287738Y281982D03*
X286940Y315039D03*
X297719Y339559D03*
X291396Y350223D03*
X292520Y384410D03*
X292358Y393858D03*
X298000Y391496D03*
X295699Y382047D03*
X296000Y403500D03*
X298000Y409000D03*
X294000Y398583D03*
X295253Y440869D03*
Y438269D03*
X292453D03*
Y440869D03*
Y435669D03*
Y430469D03*
Y433069D03*
X295253D03*
Y430469D03*
Y435669D03*
X293307Y451677D03*
X295807D03*
X293307Y454177D03*
X295807D03*
X295011Y460218D03*
Y463618D03*
X281980Y953926D03*
X312256Y37543D03*
X305610Y55513D03*
X301835Y68581D03*
X310817Y60393D03*
X307916Y60529D03*
X301848Y80581D03*
X305978Y88801D03*
X312844Y94279D03*
X308895Y94351D03*
X308338Y85731D03*
X311892Y86046D03*
X312088Y116594D03*
X299742Y112083D03*
X304031Y103621D03*
X312088Y119594D03*
X312522Y124283D03*
X300435Y143518D03*
X299535Y152373D03*
X310929Y161306D03*
X302685Y152562D03*
X308180Y157370D03*
X312264Y176665D03*
Y168665D03*
X303377Y183834D03*
X303550Y172665D03*
X303487Y178560D03*
X304363Y186629D03*
X302897Y190185D03*
X312264Y196665D03*
Y192665D03*
X303667Y200864D03*
X312377Y186778D03*
X300814Y192859D03*
X312296Y204864D03*
Y208864D03*
X303756Y212455D03*
X303690Y207037D03*
X301057Y221642D03*
X307937Y219379D03*
X308565Y228631D03*
X298373Y236189D03*
X298314Y248765D03*
X302471Y265897D03*
X304971D03*
X298811Y270695D03*
Y268195D03*
X315079Y314890D03*
X312263Y324518D03*
X301943Y328867D03*
X308952Y356875D03*
X312316Y356747D03*
X299000Y377912D03*
Y386500D03*
X299088Y397912D03*
X322847Y19806D03*
X321840Y14408D03*
X322113Y26187D03*
X316751Y86012D03*
Y94374D03*
X324057Y116594D03*
X318031Y110784D03*
X323031D03*
X324057Y119594D03*
X327591Y125107D03*
X322610Y124663D03*
X317588Y124879D03*
X329064Y142862D03*
X330105Y148717D03*
X323954Y138838D03*
X317345Y218085D03*
X320145D03*
X323945Y216385D03*
X326658Y216970D03*
Y219470D03*
X326724Y226320D03*
X326658Y221970D03*
X329685Y228646D03*
X328642Y232971D03*
X322672Y249108D03*
X325292Y244571D03*
X314053Y248371D03*
X327032Y303962D03*
X314855Y311740D03*
X318508Y324322D03*
X315944Y332584D03*
X316067Y347937D03*
X321416Y348015D03*
X317333Y353470D03*
X318500Y356519D03*
X315310Y356712D03*
X318660Y539315D03*
X320785Y553287D03*
X327456Y550065D03*
X321119Y622912D03*
X330905Y15806D03*
Y19806D03*
Y27806D03*
X333674Y97667D03*
X342134Y103411D03*
X342528Y97667D03*
X337924Y95111D03*
X329330Y102495D03*
X342293Y106561D03*
X336205Y143762D03*
X335153Y195176D03*
X332653D03*
X336671Y199248D03*
X337653Y195176D03*
X340153D03*
X339671Y199248D03*
X336671Y201748D03*
X334507Y206806D03*
X337007D03*
X335234Y210509D03*
X332734D03*
X339671Y202048D03*
X343271Y230117D03*
X338681Y227824D03*
X334426Y230556D03*
X339287Y238714D03*
X333411Y242078D03*
X338768Y246874D03*
X340988Y244297D03*
X332635Y256394D03*
X347058Y399918D03*
X339072Y416888D03*
Y419488D03*
Y422088D03*
X345050Y454334D03*
X337078Y551381D03*
X335399Y544718D03*
X333985Y1017945D03*
X341077Y1018056D03*
X339251Y1138130D03*
X336755Y1143489D03*
X340500Y1147500D03*
X335190Y1173065D03*
X341266Y1171956D03*
X330800Y1174500D03*
X343121Y1188412D03*
X342009Y1176100D03*
X339776Y1187962D03*
X335502Y1188222D03*
X339540Y1196894D03*
X358636Y90615D03*
X353324Y90650D03*
X362957Y99961D03*
X353074Y95236D03*
X359376Y290592D03*
X348351Y319372D03*
X348806Y315427D03*
X351132Y322202D03*
X349120Y336100D03*
X351136Y372334D03*
X350486Y377173D03*
X358491D03*
X347591Y391533D03*
X359486Y385123D03*
X349311Y385644D03*
X354486Y385123D03*
X357655Y405889D03*
Y408489D03*
X358248Y403300D03*
X353894Y406060D03*
X354155Y421489D03*
Y418889D03*
Y416289D03*
X350163Y412106D03*
X357655Y413689D03*
Y416289D03*
Y421489D03*
Y418889D03*
Y424089D03*
Y411089D03*
X358042Y432718D03*
X357655Y426689D03*
X358042Y435518D03*
X358754Y450091D03*
X356241Y447001D03*
X359241D03*
X353320Y454214D03*
X353663Y449045D03*
X353367Y459330D03*
X358754Y462060D03*
X353670Y473571D03*
Y481071D03*
Y478571D03*
Y476071D03*
X360242Y477053D03*
X357742D03*
X358207Y836462D03*
X346366Y1134729D03*
X361621D03*
X349748D03*
X357748D03*
X353748D03*
X352545Y1142666D03*
X360877Y1157404D03*
X354420Y1157544D03*
X352931Y1167768D03*
X357950D03*
X357057Y1179542D03*
X357796Y1188058D03*
X357083Y1185205D03*
X361792Y1187310D03*
X348432Y1187215D03*
X348125Y1180175D03*
X358368Y1201043D03*
X354398D03*
X350402D03*
X346387Y1199256D03*
X360523Y1192282D03*
X349276Y1217228D03*
X351940Y1219895D03*
X362332Y1230265D03*
X355215Y1223170D03*
X360273Y1228226D03*
X358062Y1226016D03*
X371871Y85193D03*
Y82593D03*
Y79993D03*
Y77393D03*
Y74793D03*
X371915Y92874D03*
X363007Y95236D03*
X373942Y104249D03*
Y107649D03*
X370964Y162368D03*
X373564D03*
X372275Y208213D03*
X379147Y208695D03*
X376347D03*
Y211695D03*
X372275Y210713D03*
Y213213D03*
X361819Y207978D03*
Y212978D03*
Y215478D03*
Y210478D03*
X372275Y215713D03*
X367648Y264180D03*
X365148D03*
X365073Y258880D03*
X374042Y270026D03*
X376842D03*
X374042Y267526D03*
X376842D03*
X371417Y353820D03*
X365559Y354300D03*
X377237Y371060D03*
X373264Y379429D03*
X378875Y379088D03*
X366526Y377173D03*
X370486D03*
X362486Y385123D03*
X366486D03*
X370160Y391569D03*
X368587Y401066D03*
X378927Y406739D03*
X367919Y439318D03*
X375919Y442118D03*
Y439318D03*
X367919Y442118D03*
X361754Y450091D03*
X367564Y456034D03*
Y461034D03*
X373546Y470001D03*
X376046D03*
X361754Y462060D03*
X373971Y489036D03*
X371832Y485580D03*
X374332D03*
X376832D03*
X366420Y479986D03*
Y477486D03*
X363686Y478668D03*
Y476168D03*
X376207Y492836D03*
Y495636D03*
X376881Y518564D03*
X363015Y710365D03*
X365887Y710329D03*
X372400Y746300D03*
X372300Y750000D03*
X373500Y767300D03*
X376300D03*
X370415Y766108D03*
X373703Y782555D03*
X365850Y773950D03*
X371436Y791188D03*
X365691Y815127D03*
X371507Y815303D03*
X362042Y814772D03*
X368067Y925136D03*
X370214Y943812D03*
X368626Y931346D03*
X368964Y937738D03*
X372858Y935136D03*
X366761Y934550D03*
X363893Y946863D03*
X379928Y949774D03*
X379245Y956643D03*
X378875Y961862D03*
X370214Y947812D03*
X370101Y953699D03*
X370214Y963812D03*
Y971812D03*
X378928Y967812D03*
X372501Y1123695D03*
X365748Y1134325D03*
X368657Y1150087D03*
X366133Y1170767D03*
X366429Y1185238D03*
X366222Y1180235D03*
X362402Y1201039D03*
X366402Y1200969D03*
X366521Y1208993D03*
X370202Y1314764D03*
Y1311364D03*
X383612Y33768D03*
X388612Y31168D03*
X387948Y27288D03*
X380196Y98551D03*
X390750Y97475D03*
X383746Y103783D03*
X390681Y106186D03*
X380664Y165393D03*
Y162793D03*
Y167993D03*
Y170493D03*
X387588Y177616D03*
X382872Y181366D03*
X379661Y181426D03*
X385667Y181009D03*
X390842Y168697D03*
X388169Y172190D03*
X391930Y191941D03*
X382486Y184012D03*
X379869Y184221D03*
X393939Y206767D03*
X383905Y211359D03*
X387608Y213132D03*
X378847Y211695D03*
X383905Y213859D03*
X394069Y221708D03*
X393484Y224421D03*
X387608Y215632D03*
X387852Y256303D03*
X387611Y265896D03*
X382524Y265701D03*
X392627Y266114D03*
X379342Y270026D03*
Y267526D03*
X384159Y281716D03*
X390100Y281982D03*
X391737Y377581D03*
X384173Y379028D03*
X381237Y371076D03*
X394237Y379591D03*
X391940Y383817D03*
Y388817D03*
Y386317D03*
X385864Y398278D03*
X383364D03*
X378927Y409539D03*
X381927D03*
Y407039D03*
X381591Y401981D03*
X384091D03*
X378210Y424067D03*
X380710D03*
X385710D03*
X383210D03*
X378445Y413611D03*
X380945D03*
X385945D03*
X383445D03*
X385584Y438293D03*
Y441093D03*
Y443893D03*
X393646Y474382D03*
X385634Y472020D03*
X393662Y470382D03*
X385694Y477318D03*
X385293Y466409D03*
X387141Y484882D03*
X385131Y487382D03*
X391470Y732865D03*
X380963Y731000D03*
X381875Y740341D03*
X379800Y769200D03*
X380331Y782627D03*
X380607Y786932D03*
X387958Y813700D03*
X381631Y814147D03*
X384666Y814103D03*
X383391Y804000D03*
X386589Y864408D03*
X383462Y860535D03*
X392584Y875845D03*
X382675Y870151D03*
X391614Y930676D03*
X384856Y947987D03*
X378119Y953696D03*
X392910Y948536D03*
X393998Y971780D03*
X378790Y1001083D03*
X380280Y1006071D03*
X383710Y1007283D03*
X382465Y1012430D03*
X378410Y1131573D03*
X380261Y1129692D03*
X385091Y1297453D03*
Y1300853D03*
X386415Y1321645D03*
X391691Y1326715D03*
X392234Y1369579D03*
Y1364501D03*
X391757Y1383480D03*
X391852Y1389931D03*
X393951Y1447455D03*
X381900Y1544800D03*
X389700Y1536900D03*
X391740Y1545629D03*
Y1540529D03*
X382017Y1559700D03*
X395296Y1561024D03*
X391740Y1550729D03*
Y1555829D03*
X410789Y22627D03*
X408680Y37530D03*
X396680Y37543D03*
X400714Y45448D03*
X404686D03*
X397731Y100625D03*
X402104Y112083D03*
X406393Y103621D03*
X405912Y172665D03*
X405739Y183834D03*
X405849Y178560D03*
X406725Y186629D03*
X399984Y192490D03*
X405259Y190185D03*
X406029Y200864D03*
X395942Y192300D03*
X398939Y206767D03*
X396439D03*
X406118Y212455D03*
X406052Y207037D03*
X395184Y228221D03*
X399069Y221708D03*
X396569D03*
X403419Y221642D03*
X395184Y231021D03*
X410299Y219379D03*
X410927Y228631D03*
X400735Y236189D03*
X398235D03*
X395735D03*
X400676Y248765D03*
X398176D03*
X395676D03*
X407333Y265897D03*
X404833D03*
X401173Y268195D03*
Y270695D03*
X398373Y268195D03*
X395873D03*
Y270695D03*
X398373D03*
X405843Y315158D03*
X403343D03*
X394883Y341777D03*
Y338377D03*
X410086Y336795D03*
X409655Y331589D03*
X410688Y344736D03*
X400993Y331589D03*
Y335589D03*
X400728Y353152D03*
X411007Y356743D03*
X406421Y387151D03*
Y382151D03*
Y384651D03*
X398453Y387702D03*
X401253D03*
X394653Y389402D03*
X395577Y438293D03*
Y441093D03*
Y443893D03*
X397315Y471560D03*
X405801Y475560D03*
X405301Y467560D03*
X397315Y475560D03*
X406200Y741300D03*
X397223Y796792D03*
X400023D03*
X397900Y789000D03*
X407000Y784700D03*
X404468Y864407D03*
X396306Y864409D03*
X406770Y869767D03*
X405466Y881299D03*
X397431Y870654D03*
X401108Y878487D03*
X401121Y929686D03*
X409121D03*
X401121Y932186D03*
X409121D03*
X405179Y959051D03*
X404971Y956256D03*
X402354Y956465D03*
X401968Y959111D03*
X399173Y959468D03*
X397252Y962861D03*
X404176Y977684D03*
Y975084D03*
Y969984D03*
Y972484D03*
X396671Y968287D03*
X406954Y982970D03*
X409554D03*
X404354D03*
X407547Y1058097D03*
X410047D03*
X405047D03*
X407547Y1060697D03*
X410047D03*
X405047D03*
X408989Y1082501D03*
X409015Y1087705D03*
Y1085205D03*
X408847Y1090956D03*
Y1093956D03*
X406895Y1107997D03*
X402695D03*
Y1110897D03*
X407780Y1113648D03*
X409231Y1118801D03*
X406995Y1110597D03*
X404895Y1112397D03*
X404795Y1109397D03*
X402695Y1113797D03*
X408961Y1162384D03*
Y1164884D03*
Y1167384D03*
Y1169884D03*
Y1172384D03*
X403263Y1160834D03*
X408961Y1174884D03*
X406319Y1186709D03*
Y1184209D03*
Y1181709D03*
Y1179209D03*
X404004Y1192621D03*
Y1190121D03*
X397063Y1221428D03*
X401063D03*
X405063D03*
X409063D03*
X397063Y1233428D03*
Y1229428D03*
Y1225428D03*
X401063Y1237428D03*
Y1233428D03*
Y1229428D03*
Y1225428D03*
X405063Y1237428D03*
Y1233428D03*
Y1229428D03*
Y1225428D03*
X409063Y1237428D03*
Y1233428D03*
Y1229428D03*
Y1225428D03*
X401063Y1241428D03*
X405063Y1245428D03*
Y1241428D03*
X409063Y1245428D03*
Y1241428D03*
X404324Y1271889D03*
Y1275889D03*
X407767Y1292198D03*
X403678Y1295426D03*
X398584Y1313443D03*
X401011Y1307258D03*
X402967Y1319815D03*
X409220Y1315516D03*
X404583Y1316131D03*
X404921Y1321819D03*
X408787Y1321795D03*
X399959Y1352153D03*
X408159Y1349072D03*
X404759D03*
X395112Y1395690D03*
X398340Y1399779D03*
X395770Y1389817D03*
X410172Y1402446D03*
X402489Y1417275D03*
X405889D03*
X407970Y1449751D03*
X404500Y1452500D03*
X395888Y1450022D03*
X395199Y1482223D03*
X395380Y1485778D03*
X397266Y1514647D03*
X398747Y1500959D03*
X395370Y1501022D03*
X397266Y1518047D03*
X408964Y1531149D03*
X394391Y1537786D03*
Y1535286D03*
X399373Y1555855D03*
X405496Y1561024D03*
X400396D03*
X410596D03*
X397461Y1569560D03*
X401461D03*
X416900Y33400D03*
X422473Y22627D03*
X422450Y30483D03*
X422378Y26534D03*
X414145Y27486D03*
X413904Y32569D03*
X426147Y147540D03*
X414626Y176665D03*
Y168665D03*
Y196665D03*
Y192665D03*
X414739Y186778D03*
X414658Y204864D03*
Y208864D03*
X423651Y307470D03*
X419177Y304470D03*
X415777D03*
X422988Y323627D03*
X415129Y325181D03*
X412671Y333418D03*
X412812Y330617D03*
X426830Y359026D03*
X426138Y355079D03*
X416574Y357528D03*
X421413Y359053D03*
X412318Y367903D03*
X420422Y367859D03*
X418997Y382210D03*
Y384710D03*
Y387210D03*
X422215Y424939D03*
Y427439D03*
X414924Y435321D03*
Y438121D03*
X412124Y435321D03*
Y438121D03*
X414924Y440921D03*
X412124D03*
X414924Y443721D03*
X412124D03*
X426647Y452987D03*
X421267Y452799D03*
X414910Y448931D03*
X415433Y459170D03*
X425673Y461607D03*
X424876Y471334D03*
X418801Y474513D03*
X414275Y492469D03*
X424731Y492704D03*
X414275Y497469D03*
Y499969D03*
X427693Y498943D03*
X424731Y497704D03*
Y495204D03*
Y500204D03*
X414275Y494969D03*
X419340Y549990D03*
X419140Y547390D03*
Y544790D03*
X419340Y552590D03*
Y555190D03*
X423963Y625778D03*
X426607Y712360D03*
Y709760D03*
X424993Y728291D03*
X423700Y795500D03*
X426300Y797400D03*
X421200Y786400D03*
X411267Y829193D03*
Y831693D03*
X416267D03*
X413767D03*
Y829193D03*
X416267D03*
X425062Y883981D03*
X417121Y929686D03*
X425121D03*
X417121Y932186D03*
X425121D03*
X411960Y962261D03*
X414560D03*
X417160D03*
X411276Y978109D03*
X416476D03*
X413876D03*
X415047Y1058097D03*
X412547D03*
X415047Y1060697D03*
X412547D03*
X411989Y1082501D03*
X412015Y1085205D03*
X414989Y1082501D03*
X415015Y1085205D03*
Y1088205D03*
X412015D03*
X412297Y1091227D03*
X425060Y1101917D03*
X420782Y1105552D03*
X423340Y1104335D03*
X424995Y1106897D03*
X416988Y1104792D03*
X418495Y1106867D03*
X414580Y1113648D03*
X412080D03*
X411461Y1162384D03*
Y1164884D03*
Y1167384D03*
Y1169884D03*
Y1172384D03*
X420619Y1179421D03*
Y1181921D03*
Y1184421D03*
Y1186921D03*
X411461Y1174884D03*
X422934Y1192621D03*
Y1190121D03*
X417469Y1192621D03*
Y1190121D03*
X413063Y1221428D03*
X417063D03*
X421063D03*
X425063D03*
X413063Y1237428D03*
Y1233428D03*
Y1229428D03*
Y1225428D03*
X417063Y1237428D03*
Y1233428D03*
Y1229428D03*
Y1225428D03*
X421063Y1237428D03*
Y1233428D03*
Y1229428D03*
Y1225428D03*
X425063Y1237428D03*
Y1233428D03*
Y1229428D03*
Y1225428D03*
X413063Y1245428D03*
Y1241428D03*
X417063Y1245428D03*
Y1241428D03*
X421063Y1245428D03*
Y1241428D03*
X425063Y1245428D03*
Y1241428D03*
X425702Y1257160D03*
X422702Y1260160D03*
Y1257160D03*
X425702Y1260160D03*
X419702Y1257160D03*
Y1260160D03*
X413526Y1288938D03*
X419977Y1288843D03*
X413640Y1292856D03*
X419545Y1317722D03*
X413127Y1318011D03*
X425283Y1364023D03*
X417305Y1359169D03*
X425855Y1360495D03*
X425912Y1357141D03*
X416029Y1371572D03*
X420636Y1383912D03*
X418610Y1371590D03*
X423400Y1394500D03*
X423200Y1397500D03*
X418430Y1394237D03*
X422729Y1400490D03*
X420925Y1390330D03*
X419045Y1398874D03*
X421300Y1415400D03*
X419100Y1402200D03*
X421200Y1417900D03*
X411000Y1463500D03*
Y1460500D03*
Y1457500D03*
Y1454500D03*
Y1451000D03*
X413934Y1477101D03*
X417334D03*
X415202Y1496118D03*
Y1499518D03*
X417153Y1516886D03*
X413753D03*
X419619Y1539978D03*
X421454Y1544625D03*
X422539Y1534361D03*
X426701Y1541947D03*
X418151Y1552470D03*
X417461Y1569584D03*
X429919Y141247D03*
X437386Y143740D03*
X434766Y148277D03*
X431525Y304470D03*
X434925D03*
X427051Y307470D03*
X441296Y325061D03*
X436666Y322583D03*
X427713Y321965D03*
X430361Y323187D03*
X443424Y332988D03*
X440538Y355372D03*
X428420Y353578D03*
X435886Y353867D03*
X431524Y370309D03*
X434924D03*
X428637Y408104D03*
X431437D03*
X434237D03*
X428354Y420375D03*
X431154D03*
X433954D03*
X438098Y442114D03*
X437835Y435101D03*
X432270Y431112D03*
X432440Y440101D03*
X432075Y452718D03*
X438086Y452601D03*
X438078Y447121D03*
X433673Y461607D03*
X429673D03*
X435789Y501525D03*
X427568Y502003D03*
X435831Y498923D03*
X438644Y500461D03*
X428740Y549990D03*
X442804Y546990D03*
Y544390D03*
X428740Y546990D03*
Y544390D03*
Y555190D03*
Y552590D03*
X431384D03*
Y555190D03*
Y544390D03*
Y546990D03*
Y549990D03*
X443144Y628667D03*
X441162Y638313D03*
X439290Y712399D03*
X436790D03*
X439290Y709799D03*
X436790D03*
X434290Y712399D03*
Y709799D03*
X429290D03*
X431790Y712399D03*
X429290D03*
X431790Y709799D03*
X429253Y759847D03*
X432303Y785067D03*
X434100Y797400D03*
X430600D03*
X443091Y1026266D03*
X432678Y1016186D03*
X429878D03*
X427078D03*
X427052Y1019384D03*
X429852D03*
X432652D03*
X433378Y1091816D03*
Y1089316D03*
X430878Y1084316D03*
Y1086816D03*
X433378D03*
Y1084316D03*
X436244Y1090288D03*
X433378Y1081816D03*
X430878D03*
X429677Y1106955D03*
X439023Y1107997D03*
X436244Y1093088D03*
X434823Y1107997D03*
X431476Y1115896D03*
X427810Y1110092D03*
X439908Y1113648D03*
X441359Y1116101D03*
Y1118801D03*
X439123Y1110597D03*
X434823Y1113797D03*
Y1110897D03*
X437023Y1112397D03*
X436923Y1109397D03*
X431476Y1118396D03*
X429348Y1129092D03*
X432838Y1128821D03*
X436789Y1167384D03*
Y1164884D03*
Y1162384D03*
Y1172384D03*
Y1169884D03*
X439289Y1167384D03*
Y1164884D03*
Y1162384D03*
X427231D03*
X429731D03*
Y1164884D03*
Y1167384D03*
Y1169884D03*
Y1172384D03*
X427231D03*
Y1169884D03*
Y1167384D03*
Y1164884D03*
X439289Y1172384D03*
Y1169884D03*
X437132Y1158266D03*
X433249Y1186709D03*
Y1184209D03*
Y1181709D03*
Y1179209D03*
X429731Y1174884D03*
X427231D03*
X436789D03*
X439289D03*
X430934Y1190121D03*
Y1192621D03*
X429063Y1221428D03*
X433063D03*
X429063Y1237428D03*
Y1233428D03*
Y1229428D03*
Y1225428D03*
X433063Y1237428D03*
Y1233428D03*
Y1229428D03*
Y1225428D03*
X429063Y1245428D03*
Y1241428D03*
X433063Y1245428D03*
Y1241428D03*
X440702Y1260160D03*
Y1257160D03*
X437702Y1260160D03*
Y1257160D03*
X428702D03*
X431702Y1260160D03*
Y1257160D03*
X434702Y1260160D03*
Y1257160D03*
X428702Y1260160D03*
X434424Y1286274D03*
X430527Y1289198D03*
X440906D03*
X431867Y1315696D03*
X431885Y1313115D03*
X439434Y1322369D03*
X429530Y1325051D03*
X445949Y141247D03*
X450436Y143518D03*
X449536Y152373D03*
X452686Y152562D03*
X458181Y157370D03*
X443508Y337713D03*
X446566Y337917D03*
X443480Y344014D03*
X450852Y372054D03*
X455885Y367702D03*
X448391Y382641D03*
X448323Y379643D03*
X451144Y468809D03*
X459414Y468689D03*
X459757Y463520D03*
X459461Y473805D03*
X459929Y491669D03*
X450942Y506449D03*
X448442D03*
X445942D03*
X460537Y501905D03*
X459952Y496842D03*
X459645Y509486D03*
X446025Y511512D03*
X448525D03*
X446025Y519699D03*
X448525D03*
X452404Y549790D03*
X443004Y549890D03*
X452404Y546990D03*
Y544390D03*
X443004Y555090D03*
X452404Y552390D03*
Y554990D03*
X443004Y552490D03*
X455009Y554912D03*
Y552312D03*
Y544312D03*
Y546912D03*
Y549712D03*
X447279Y637031D03*
X447921Y630789D03*
X453552Y631779D03*
X446987Y643360D03*
X456469Y638302D03*
X460498Y870334D03*
X458120Y974701D03*
X451460Y974695D03*
X450591Y1004766D03*
X453270Y1003763D03*
X459360Y1012325D03*
X443591Y1019766D03*
X459885Y1018860D03*
X451140Y1021793D03*
X447091Y1019766D03*
X450875Y1028416D03*
X443091Y1034266D03*
X452091Y1039880D03*
X459700Y1032266D03*
X455468Y1104335D03*
X457188Y1101917D03*
X452910Y1105552D03*
X457123Y1106897D03*
X449116Y1104792D03*
X450623Y1106867D03*
X444208Y1113648D03*
X446708D03*
X457559Y1169884D03*
Y1167384D03*
Y1164884D03*
Y1162384D03*
X455059D03*
Y1164884D03*
Y1167384D03*
Y1169884D03*
Y1172384D03*
X457559D03*
X455059Y1174884D03*
X457559D03*
X447549Y1179421D03*
Y1181921D03*
Y1184421D03*
Y1186921D03*
X449864Y1190121D03*
Y1192621D03*
X449702Y1260160D03*
Y1257160D03*
X443702Y1260160D03*
X446702D03*
Y1257160D03*
X443702D03*
X451304Y1297045D03*
X454385Y1301845D03*
Y1305245D03*
X444288Y1314391D03*
X462089Y116594D03*
X474058D03*
X473032Y110784D03*
X468032D03*
X462089Y119594D03*
X474058D03*
X477592Y125107D03*
X462523Y124283D03*
X467589Y124879D03*
X472611Y124663D03*
X473955Y138838D03*
X460930Y161306D03*
X467346Y218085D03*
X470146D03*
X473946Y216385D03*
X475293Y244571D03*
X472673Y249108D03*
X464054Y248371D03*
X460950Y328185D03*
Y324785D03*
X463950Y332659D03*
Y336059D03*
X460950Y343933D03*
Y340533D03*
X472810Y347995D03*
X472913Y360089D03*
X472608Y352495D03*
X467335Y359944D03*
X463950Y351807D03*
Y348407D03*
X472913Y369089D03*
Y373589D03*
X469530Y366754D03*
X472913Y387089D03*
Y391589D03*
Y382589D03*
Y378089D03*
X470796Y394592D03*
X464848Y464566D03*
X467848D03*
X465126Y460435D03*
X462126D03*
X473658Y470509D03*
Y475509D03*
X467848Y476535D03*
X464848D03*
X468558Y495669D03*
Y499669D03*
Y516609D03*
X464199Y510184D03*
X468850Y545586D03*
X469300Y799500D03*
X459245Y807152D03*
X473654Y821234D03*
X472399Y839566D03*
X463404Y846870D03*
X465492Y861970D03*
X471726Y883705D03*
X474540Y927341D03*
X471110Y921577D03*
X471876Y937236D03*
X471068Y930235D03*
X473992Y952546D03*
X475018Y992568D03*
X467345Y996480D03*
X459360Y1004680D03*
X464795Y1000647D03*
X462185Y1016825D03*
X459860Y1015825D03*
X464385Y1038534D03*
X471558Y1029482D03*
X471755Y1038665D03*
X470610Y1033783D03*
X475588Y1043055D03*
X473639Y1030952D03*
X459700Y1035716D03*
X470978Y1046591D03*
X474348Y1090171D03*
X462913Y1106365D03*
X474277Y1093048D03*
X472482Y1107997D03*
X468282D03*
X459938Y1110092D03*
X463604Y1115896D03*
X473367Y1113648D03*
X474818Y1116101D03*
Y1118801D03*
X472582Y1110597D03*
X470482Y1112397D03*
X468282Y1110897D03*
Y1113797D03*
X470382Y1109397D03*
X463604Y1118396D03*
X462687Y1160834D03*
X474548Y1172384D03*
Y1169884D03*
Y1167384D03*
Y1164884D03*
Y1162384D03*
X468850Y1160834D03*
X474548Y1174884D03*
X465785Y1197471D03*
X461285Y1193471D03*
Y1197471D03*
X465785Y1193471D03*
X474647Y1260160D03*
Y1257160D03*
X471647D03*
Y1260160D03*
X459290Y1297035D03*
X463290D03*
X492135Y103411D03*
X492529Y97667D03*
X483675D03*
X487925Y95111D03*
X479331Y102495D03*
X479065Y142862D03*
X486206Y143762D03*
X480106Y148717D03*
X487654Y195176D03*
X489672Y199248D03*
X485154Y195176D03*
X482654D03*
X486672Y199248D03*
X490154Y195176D03*
X485235Y210509D03*
X482735D03*
X489672Y202048D03*
X486672Y201748D03*
X484508Y206806D03*
X487008D03*
X476659Y216970D03*
Y219470D03*
X476725Y226320D03*
X476659Y221970D03*
X493272Y230117D03*
X484427Y230556D03*
X488682Y227824D03*
X479686Y228646D03*
X483412Y242078D03*
X478643Y232971D03*
X488769Y246874D03*
X489288Y238714D03*
X490989Y244297D03*
X482636Y256394D03*
X492817Y357111D03*
X491843Y351089D03*
X481724Y373589D03*
Y369089D03*
X490885Y373589D03*
X491053Y365423D03*
X491289Y391589D03*
X481724Y382589D03*
Y378089D03*
X490885Y382570D03*
X490985Y412342D03*
X488438Y418417D03*
X485485Y439903D03*
X489485D03*
X481485Y439900D03*
Y431917D03*
X489485Y431417D03*
X492736Y491982D03*
X482836Y534249D03*
X491818Y534909D03*
X491445Y541135D03*
X482905Y527726D03*
Y548726D03*
Y544726D03*
X491534Y552726D03*
X491511Y546553D03*
X487209Y611071D03*
X484772Y621311D03*
X493392Y622285D03*
X493580Y616905D03*
X484772Y629311D03*
Y625311D03*
X493661Y627713D03*
X493778Y633724D03*
X481165Y646036D03*
X483059Y662649D03*
X488765Y667224D03*
X481742Y657477D03*
X486837Y701306D03*
Y704706D03*
X489406Y797558D03*
X489572Y822805D03*
X479448Y828594D03*
X479700Y847600D03*
X477574Y860815D03*
X490706Y859339D03*
X491616Y938771D03*
X476475Y952249D03*
X479613Y952189D03*
X489163Y977163D03*
X487091Y989550D03*
X480711Y999941D03*
X477857Y1004375D03*
X488041Y1020440D03*
X485678Y1039880D03*
X485633Y1036155D03*
X477765Y1093432D03*
X477607Y1089942D03*
X491503Y1086796D03*
Y1084296D03*
X478517Y1086724D03*
Y1084224D03*
Y1081724D03*
X476017D03*
Y1084224D03*
Y1086724D03*
X486369Y1105552D03*
X490647Y1101917D03*
X488927Y1104335D03*
X490582Y1106897D03*
X482575Y1104792D03*
X484082Y1106867D03*
X480167Y1113648D03*
X477667D03*
X477048Y1172384D03*
Y1169884D03*
Y1167384D03*
Y1164884D03*
Y1162384D03*
X479521Y1179209D03*
Y1181709D03*
Y1184209D03*
Y1186709D03*
X477048Y1174884D03*
X490671Y1192621D03*
Y1190121D03*
X477206Y1192621D03*
Y1190121D03*
X489647Y1260160D03*
Y1257160D03*
X486647D03*
Y1260160D03*
X480647Y1257160D03*
X477647D03*
Y1260160D03*
X480647D03*
X483647Y1257160D03*
Y1260160D03*
X490100Y1302100D03*
X487600D03*
X503325Y90650D03*
X508637Y90615D03*
X503075Y95236D03*
X492294Y106561D03*
X496023Y362913D03*
X497048Y369450D03*
X495750Y377531D03*
X506500Y379687D03*
X495203Y386890D03*
X503729Y439919D03*
X503682Y448419D03*
X500729Y469905D03*
X496729Y470419D03*
X504729Y469905D03*
X496729Y461919D03*
X504729Y461419D03*
X505476Y485128D03*
X497095Y481467D03*
X501224Y492050D03*
X501649Y482165D03*
X501887Y504825D03*
X499387D03*
X496887D03*
X500890Y500202D03*
X502493Y495917D03*
X492736Y495982D03*
X501828Y517401D03*
X499328D03*
X496828D03*
X502379Y522569D03*
X495444Y531948D03*
X503494Y531882D03*
X502379Y525369D03*
X500994Y531882D03*
X498494D03*
X504079Y529169D03*
X503729Y555194D03*
X500929D03*
Y571194D03*
X503729D03*
Y563194D03*
X500929D03*
X505286Y581222D03*
X502486D03*
X505286Y591215D03*
X502486D03*
X505458Y610562D03*
X502658D03*
Y607762D03*
X505458D03*
X497448Y610548D03*
X504265Y633736D03*
X499258Y633716D03*
X506278Y628078D03*
X494465Y657772D03*
X502755Y657694D03*
X496070Y665976D03*
X499528Y657843D03*
X504966Y678098D03*
X498284Y681453D03*
Y678953D03*
X500714Y708755D03*
X502832Y720491D03*
X504895Y770457D03*
X501495D03*
X504508Y783817D03*
X506166Y793224D03*
X504641Y789139D03*
X507095Y814784D03*
X494677Y830468D03*
X509665Y824512D03*
X495073Y835586D03*
X495470Y844271D03*
X495700Y849389D03*
X503383Y863025D03*
X498507Y865392D03*
X508248Y873319D03*
X509791Y881932D03*
X509017Y905295D03*
X494315Y941212D03*
X503144Y957934D03*
X504088Y985171D03*
X506888D03*
X506702Y978947D03*
X493091Y989550D03*
X503933Y981392D03*
X498435Y1008766D03*
X506566D03*
Y996766D03*
X498524Y997590D03*
X498585Y1016266D03*
X506566Y1012266D03*
X503177Y1058097D03*
X495677D03*
X493177D03*
X498177D03*
X500677D03*
X503177Y1060697D03*
X495677D03*
X493177D03*
X498177D03*
X500677D03*
X494003Y1086796D03*
X496503D03*
X499003D03*
X501503D03*
Y1084296D03*
X499003D03*
X496503D03*
X494003D03*
X501831Y1090288D03*
X496372Y1106298D03*
X504610Y1107997D03*
X501831Y1093088D03*
X500410Y1107997D03*
X497063Y1115896D03*
X505495Y1113648D03*
X506946Y1116101D03*
Y1118801D03*
X504710Y1110597D03*
X500410Y1113797D03*
X502610Y1112397D03*
X500410Y1110897D03*
X502510Y1109397D03*
X493397Y1110092D03*
X497063Y1118396D03*
X498727Y1128759D03*
X495236Y1129094D03*
X502376Y1172384D03*
Y1169884D03*
Y1167384D03*
Y1164884D03*
Y1162384D03*
X504876Y1172384D03*
Y1169884D03*
Y1167384D03*
Y1164884D03*
Y1162384D03*
X492818D03*
Y1164884D03*
Y1167384D03*
Y1169884D03*
Y1172384D03*
X495318D03*
Y1169884D03*
Y1167384D03*
Y1164884D03*
Y1162384D03*
X502562Y1158200D03*
X506451Y1179209D03*
Y1181709D03*
Y1184209D03*
Y1186709D03*
X504876Y1174884D03*
X493821Y1186921D03*
Y1184421D03*
Y1181921D03*
Y1179421D03*
X492818Y1174884D03*
X495318D03*
X502376D03*
X504136Y1190121D03*
Y1192621D03*
X496136Y1190121D03*
Y1192621D03*
X506562Y1222194D03*
X502562D03*
X498562D03*
X494562D03*
X506562Y1226194D03*
Y1230194D03*
Y1234194D03*
Y1238194D03*
X502562Y1226194D03*
Y1230194D03*
Y1234194D03*
Y1238194D03*
X498562Y1226194D03*
Y1230194D03*
Y1234194D03*
Y1238194D03*
X494562Y1226194D03*
Y1230194D03*
Y1234194D03*
Y1238194D03*
Y1246194D03*
Y1242194D03*
X506562D03*
Y1246194D03*
X502562Y1242194D03*
Y1246194D03*
X498562Y1242194D03*
Y1246194D03*
X504647Y1257160D03*
X507347D03*
X501647D03*
Y1260160D03*
X495647D03*
X492647D03*
Y1257160D03*
X495647D03*
X498647D03*
Y1260160D03*
X507347D03*
X504647D03*
X521872Y82593D03*
Y85193D03*
Y74793D03*
Y77393D03*
Y79993D03*
X521916Y92874D03*
X512958Y99961D03*
X513008Y95236D03*
X523943Y107649D03*
Y104249D03*
X520965Y162368D03*
X523565D03*
X511820Y207978D03*
Y210478D03*
Y215478D03*
Y212978D03*
X522276Y208213D03*
Y213213D03*
Y210713D03*
Y215713D03*
X515149Y264180D03*
X517649D03*
X515074Y258880D03*
X524043Y270026D03*
Y267526D03*
X514769Y312953D03*
X519638Y314346D03*
X511790Y313804D03*
X512943Y443071D03*
X520823Y442603D03*
X511753Y454339D03*
Y456839D03*
X509253D03*
Y454339D03*
X518240Y459371D03*
X509253Y459339D03*
X511753D03*
X512210Y475825D03*
X517310Y470045D03*
X513310Y462004D03*
X522756Y461818D03*
X508325Y485138D03*
X512210Y478625D03*
X513910Y482425D03*
X513325Y485138D03*
X510825D03*
X519786Y491214D03*
X523489Y492987D03*
X519786Y493714D03*
X523489Y495487D03*
X509955Y537958D03*
X513658Y539731D03*
X518716Y541895D03*
X521216Y544895D03*
Y541895D03*
X513658Y542231D03*
X518416Y544895D03*
X509955Y540458D03*
X521494Y582747D03*
X508086Y581222D03*
X520945Y590801D03*
X508086Y591215D03*
X520770Y597130D03*
X524770Y605637D03*
X518940Y620653D03*
Y617853D03*
X511058Y610562D03*
Y607762D03*
X508258Y610562D03*
Y607762D03*
X520770Y605443D03*
X516770D03*
X523616Y625013D03*
X515267Y627908D03*
X511278Y633473D03*
X521778Y642184D03*
X521868Y666577D03*
X518812Y662874D03*
X510425Y683246D03*
X522200Y677613D03*
X521540Y686319D03*
X515484Y695757D03*
X515504Y701351D03*
X521159Y706388D03*
X515649D03*
X512530Y718301D03*
X514531Y716398D03*
X523929Y706388D03*
X518389D03*
X521131Y741071D03*
X517731D03*
X511724Y741035D03*
X508324D03*
X520549Y761982D03*
X509096Y753072D03*
X515422Y753455D03*
X513504Y755804D03*
X513278Y783286D03*
X520833Y773389D03*
X513551Y773203D03*
X522697Y797102D03*
X519891Y795848D03*
X518157Y803973D03*
X518565Y811973D03*
X520741Y805149D03*
X522481Y824661D03*
X517702Y826600D03*
X514682Y834590D03*
X511741Y846649D03*
X524741Y845149D03*
X520870Y874694D03*
X525159Y913818D03*
X521572Y901500D03*
X516902Y910251D03*
X520146Y939241D03*
X523289Y939195D03*
X521353Y952266D03*
X522544Y992854D03*
X512232Y985172D03*
X514566Y1000766D03*
X514690Y996766D03*
Y1004766D03*
X514566Y1016266D03*
X514649Y1020266D03*
X514843Y1030766D03*
X519500Y1028377D03*
X518497Y1105552D03*
X522775Y1101917D03*
X521055Y1104335D03*
X514703Y1104792D03*
X522710Y1106897D03*
X516210Y1106867D03*
X509795Y1113648D03*
X512295D03*
X520646Y1169884D03*
Y1167384D03*
Y1164884D03*
Y1162384D03*
X523146D03*
Y1164884D03*
Y1167384D03*
Y1169884D03*
Y1172384D03*
X520646D03*
X520751Y1186921D03*
Y1184421D03*
Y1181921D03*
Y1179421D03*
X523146Y1174884D03*
X520646D03*
X523066Y1190121D03*
Y1192621D03*
X522562Y1222194D03*
X518562D03*
X514562D03*
X510562D03*
X522562Y1226194D03*
X518562D03*
Y1230194D03*
Y1234194D03*
X514562Y1226194D03*
Y1230194D03*
Y1234194D03*
Y1238194D03*
X510562Y1226194D03*
Y1230194D03*
Y1234194D03*
Y1238194D03*
X514562Y1242194D03*
Y1246194D03*
X510562Y1242194D03*
Y1246194D03*
X530197Y98551D03*
X540751Y97475D03*
X533747Y103783D03*
X532281Y141247D03*
X528509Y147540D03*
X539748Y143740D03*
X537128Y148277D03*
X530665Y162793D03*
Y165393D03*
Y170493D03*
Y167993D03*
X538170Y172190D03*
X535668Y181009D03*
X529662Y181426D03*
X532873Y181366D03*
X537589Y177616D03*
X529870Y184221D03*
X532487Y184012D03*
X533906Y211359D03*
Y213859D03*
X528848Y211695D03*
X537609Y213132D03*
X526348Y208695D03*
X529148D03*
X526348Y211695D03*
X537609Y215632D03*
X537853Y256303D03*
X532525Y265701D03*
X537612Y265896D03*
X526843Y270026D03*
X529343D03*
X526843Y267526D03*
X529343D03*
X534160Y281716D03*
X540101Y281982D03*
X532659Y359557D03*
X526388Y351301D03*
X531612Y354272D03*
X531636Y349057D03*
X528812Y369164D03*
X533211Y364746D03*
X533115Y371856D03*
X530144Y376062D03*
X531953Y380749D03*
X542034Y392209D03*
X541706Y386223D03*
X533189Y390723D03*
X531953Y385749D03*
X531992Y397552D03*
X526216Y456652D03*
X528716D03*
X526216Y459152D03*
Y461652D03*
X528716Y459152D03*
Y461652D03*
X535119Y491133D03*
X531047Y498151D03*
X535119Y493633D03*
Y496133D03*
Y498633D03*
X531047Y495151D03*
X528547D03*
X528247Y498151D03*
X525288Y537877D03*
X535219Y555897D03*
Y553297D03*
X533488Y548344D03*
X525288Y540377D03*
Y545377D03*
Y542877D03*
X528488Y548344D03*
X525988D03*
X530988D03*
X535219Y561097D03*
Y563697D03*
Y566797D03*
Y558497D03*
X532009Y570478D03*
X529214Y570686D03*
X529423Y573303D03*
X532069Y573689D03*
X532426Y576484D03*
X535819Y578405D03*
X541245Y578986D03*
X524770Y597232D03*
X534820Y596782D03*
X540770Y596729D03*
X529601Y596089D03*
X526756Y613913D03*
Y616713D03*
Y619513D03*
X538826Y614158D03*
Y616958D03*
Y619758D03*
X536770Y605443D03*
X537664Y661556D03*
X534264D03*
X529664Y664056D03*
X526264D03*
X538316Y687357D03*
X535738Y687489D03*
X536087Y702364D03*
X529469Y706230D03*
X526699Y706388D03*
X535585Y736593D03*
X538985D03*
X530985Y741593D03*
X527585D03*
X524598Y753387D03*
X539449Y782389D03*
X537578Y772428D03*
X532304Y806649D03*
X531313Y812850D03*
Y826630D03*
X532316Y833649D03*
X534000Y843000D03*
X537300Y842900D03*
X530741Y845149D03*
X534632Y849830D03*
X525718Y873821D03*
X533468Y878533D03*
X538468Y888033D03*
X530968Y888283D03*
X528975Y898346D03*
X537279Y897943D03*
X533143Y897910D03*
X531076Y913190D03*
X527879Y952189D03*
X530473Y961728D03*
X528500Y1106365D03*
X529191Y1115896D03*
X525525Y1110092D03*
X529191Y1118396D03*
X528274Y1160834D03*
X554198Y68581D03*
X554211Y80581D03*
X546293Y76587D03*
Y72615D03*
X547732Y100625D03*
X540682Y106186D03*
X552105Y112083D03*
X556394Y103621D03*
X548311Y141247D03*
X552798Y143518D03*
X551898Y152373D03*
X555048Y152562D03*
X540843Y168697D03*
X555850Y178560D03*
X555913Y172665D03*
X555740Y183834D03*
X541931Y191941D03*
X555260Y190185D03*
X549985Y192490D03*
X556030Y200864D03*
X548940Y206767D03*
X546440D03*
X543940D03*
X556119Y212455D03*
X556053Y207037D03*
X549070Y221708D03*
X546570D03*
X553420Y221642D03*
X545185Y231021D03*
Y228221D03*
X544070Y221708D03*
X543485Y224421D03*
X550736Y236189D03*
X548236D03*
X545736D03*
X550677Y248765D03*
X548177D03*
X545677D03*
X542628Y266114D03*
X545874Y268195D03*
X548374D03*
X551174Y270695D03*
X554834Y265897D03*
X551174Y268195D03*
X548374Y270695D03*
X545874D03*
X551536Y359223D03*
Y354723D03*
Y350223D03*
Y345723D03*
Y377223D03*
Y372723D03*
Y368223D03*
Y363723D03*
Y381723D03*
X551620Y390723D03*
X553563Y384987D03*
X544738Y581659D03*
X544770Y605443D03*
X551475Y661504D03*
X547227Y678299D03*
X547276Y675521D03*
X543101Y698772D03*
X540379Y719785D03*
X557751Y750851D03*
X550420Y793743D03*
X556326D03*
X540578Y793889D03*
X544515Y793875D03*
X544741Y809649D03*
X544878Y816309D03*
X546855Y829949D03*
X550087Y829836D03*
X556326Y829989D03*
X556741Y820149D03*
X544741Y823149D03*
X546241Y843149D03*
X557836Y851669D03*
X548665Y850399D03*
X540968Y878360D03*
X546940Y871389D03*
X548327Y905295D03*
X552238Y959102D03*
X552923Y988813D03*
X542793Y998507D03*
X544719Y1007522D03*
X551485Y1006648D03*
X551673Y1023900D03*
X548852Y1018307D03*
X545094Y1013678D03*
X545566Y1023731D03*
X554696Y1018469D03*
X556493Y1118351D03*
X557584Y1543411D03*
X560573Y60513D03*
X563433Y60438D03*
X557973Y55513D03*
X569114Y86012D03*
X558341Y88801D03*
X569114Y94374D03*
X561258Y94351D03*
X565207Y94279D03*
X560701Y85731D03*
X564255Y86046D03*
X564451Y116594D03*
X570394Y110784D03*
X564451Y119594D03*
X574973Y124663D03*
X564885Y124283D03*
X569951Y124879D03*
X563292Y161306D03*
X560543Y157370D03*
X564627Y176665D03*
Y168665D03*
X556726Y186629D03*
X564627Y196665D03*
Y192665D03*
X564740Y186778D03*
X564659Y204864D03*
Y208864D03*
X569708Y218085D03*
X572508D03*
X560300Y219379D03*
X560928Y228631D03*
X575035Y249108D03*
X566416Y248371D03*
X557334Y265897D03*
X573479Y374705D03*
X569938Y378317D03*
X559070Y684809D03*
Y700809D03*
Y688209D03*
X561570Y696209D03*
Y692809D03*
X559070Y716809D03*
X561570Y708809D03*
Y712209D03*
X559070Y704209D03*
Y720209D03*
X558616Y732530D03*
X562001Y732834D03*
X562374Y721593D03*
X567428Y750145D03*
X557847Y744599D03*
X563200Y739600D03*
X571493Y763090D03*
X570038Y752339D03*
X564362Y757979D03*
X560263Y782207D03*
X567126Y779066D03*
X571984Y784507D03*
X561001Y806889D03*
X567559Y803008D03*
Y824661D03*
X562400Y818900D03*
X560813Y840574D03*
X568990Y844721D03*
X572476Y845535D03*
X559295Y874267D03*
X559887Y877196D03*
X561134Y869291D03*
X559260Y891043D03*
X559214Y897425D03*
X564165Y894411D03*
X567827Y884000D03*
X562328Y957307D03*
X566303Y951807D03*
X569403D03*
X563103D03*
X570603Y957207D03*
X560923Y980443D03*
X556923Y980523D03*
X564923Y988813D03*
X560923D03*
X556923D03*
X568923D03*
X558112Y1009655D03*
X560912D03*
X567484Y1024003D03*
X571857Y1016827D03*
X559057Y1030563D03*
X562057D03*
X568057Y1030672D03*
X565057D03*
X571857Y1029427D03*
X566058Y1109564D03*
X560211D03*
X566058Y1122164D03*
X560211D03*
X566058Y1134764D03*
X560211D03*
X566058Y1147364D03*
X560211D03*
X566058Y1159964D03*
X560211D03*
X566058Y1172564D03*
X560211D03*
X566058Y1185164D03*
X560211D03*
X568532Y1200001D03*
X575620Y1207737D03*
X569135Y1214372D03*
X564890Y1218169D03*
X570796Y1530309D03*
X567324Y1528151D03*
X572432Y1521462D03*
X565400Y1535100D03*
X563968Y1541445D03*
X568279Y1538438D03*
X572507Y1541375D03*
X586037Y97667D03*
X581693Y102495D03*
X576420Y116594D03*
X575394Y110784D03*
X576420Y119594D03*
X579954Y125107D03*
X581427Y142862D03*
X588568Y143762D03*
X582468Y148717D03*
X576317Y138838D03*
X587516Y195176D03*
X585016D03*
X589034Y199248D03*
X587597Y210509D03*
X585097D03*
X589034Y201748D03*
X586870Y206806D03*
X576308Y216385D03*
X579021Y216970D03*
Y219470D03*
X579087Y226320D03*
X579021Y221970D03*
X586789Y230556D03*
X591044Y227824D03*
X582048Y228646D03*
X585774Y242078D03*
X581005Y232971D03*
X577655Y244571D03*
X584998Y256394D03*
X578193Y336391D03*
X584679Y336285D03*
X576556Y728219D03*
X575979Y732517D03*
X573778Y747437D03*
X577638Y769772D03*
X578271Y763556D03*
X583102Y767137D03*
X587183Y785008D03*
X578204Y775137D03*
X585912Y778470D03*
X588345Y798030D03*
X588659Y790336D03*
X582100Y787600D03*
X586060Y793145D03*
X581001Y810973D03*
X588377Y807536D03*
X588272Y804601D03*
X588231Y801520D03*
X577501Y829069D03*
X588001Y829624D03*
X582737Y819831D03*
X581158Y823473D03*
X573300Y829600D03*
X579827Y888000D03*
X580327Y892000D03*
X586136Y908935D03*
X583065Y903294D03*
X573103Y941307D03*
X585703D03*
X586103Y961807D03*
X573895Y965319D03*
X584923Y988813D03*
X576923D03*
X580923D03*
X588923D03*
X572923D03*
X577704Y1029427D03*
Y1016827D03*
X587880Y1034834D03*
X581967Y1105091D03*
X587467D03*
X582012Y1102091D03*
X587467Y1117691D03*
X581967D03*
X582012Y1127291D03*
Y1114691D03*
X587467Y1130291D03*
X581967D03*
X587467Y1142891D03*
X582012Y1139891D03*
X581967Y1155491D03*
X587467D03*
X581967Y1142891D03*
X582012Y1152491D03*
X581967Y1168091D03*
X587467D03*
X582012Y1165091D03*
X581967Y1180691D03*
X587467D03*
X582012Y1177691D03*
X586502Y1227300D03*
X583520Y1230407D03*
X581803Y1493687D03*
X578859Y1497758D03*
X588859Y1490895D03*
X590826Y1495688D03*
X588507Y1514141D03*
X582027Y1502800D03*
X581803Y1509687D03*
X577931Y1505687D03*
X575809Y1532912D03*
X572849Y1518702D03*
X587809Y1528389D03*
X583809Y1533025D03*
X579809Y1528163D03*
X587809Y1545854D03*
X583809Y1541607D03*
X577571Y1544013D03*
X594497Y103411D03*
X594891Y97667D03*
X605687Y90650D03*
X590287Y95111D03*
X594656Y106561D03*
X590016Y195176D03*
X592516D03*
X592034Y199248D03*
Y202048D03*
X589370Y206806D03*
X595634Y230117D03*
X591131Y246874D03*
X591650Y238714D03*
X593351Y244297D03*
X592900Y309871D03*
X605147Y378600D03*
Y382600D03*
X605262Y458711D03*
X602462D03*
X604606Y463600D03*
X598462Y504684D03*
X599110Y552466D03*
X605011Y603600D03*
Y619600D03*
Y623600D03*
X592272Y877262D03*
X592110Y895611D03*
X601084Y913544D03*
X604715Y914640D03*
X589203Y941407D03*
X591403Y938807D03*
Y936007D03*
X591754Y956979D03*
X597556Y965829D03*
X602484Y965764D03*
X600923Y988813D03*
X592923D03*
X604923D03*
X596923D03*
X599113Y1012354D03*
X593658Y1009354D03*
X593613Y1012354D03*
X599113Y1024954D03*
X593613D03*
X593658Y1021954D03*
X606434Y1041904D03*
X603682Y1053457D03*
X594183Y1220068D03*
X593519Y1224472D03*
X592885Y1229402D03*
X592634Y1234921D03*
X591487Y1501687D03*
X591481Y1509313D03*
X595809Y1532133D03*
X591872Y1518071D03*
X595809Y1546214D03*
X591809Y1542407D03*
X610999Y90615D03*
X615370Y95236D03*
X615320Y99961D03*
X605437Y95236D03*
X620727Y162368D03*
X614182Y210478D03*
Y215478D03*
Y212978D03*
Y207978D03*
X617511Y264180D03*
X620011D03*
X617436Y258880D03*
X607789Y453682D03*
X606026Y455921D03*
X609133Y941137D03*
X605733D03*
X608965Y966414D03*
X616923Y988813D03*
X608923D03*
X612923Y997860D03*
X618878Y1011914D03*
X621479Y1030482D03*
X607993Y1036920D03*
X610780Y1051037D03*
X617634Y1049283D03*
X617894Y1043955D03*
X612955Y1062941D03*
X622736Y1151870D03*
Y1159350D03*
X613738Y1546507D03*
X624234Y74793D03*
Y82593D03*
Y85193D03*
Y77393D03*
Y79993D03*
X624278Y92874D03*
X632559Y98551D03*
X636109Y103783D03*
X626305Y104249D03*
Y107649D03*
X630871Y147540D03*
X634643Y141247D03*
X639490Y148277D03*
X625927Y162368D03*
X623327D03*
X633027Y165393D03*
Y162793D03*
Y170493D03*
Y167993D03*
X639951Y177616D03*
X632024Y181426D03*
X635235Y181366D03*
X632232Y184221D03*
X634849Y184012D03*
X628710Y211695D03*
Y208695D03*
X631510D03*
X624638Y208213D03*
X636268Y211359D03*
Y213859D03*
X631210Y211695D03*
X624638Y213213D03*
Y210713D03*
Y215713D03*
X639974Y265896D03*
X634887Y265701D03*
X629205Y267526D03*
X626405D03*
X631705D03*
X629205Y270026D03*
X626405D03*
X631705D03*
X636522Y281716D03*
X632009Y541863D03*
Y545263D03*
X630201Y553407D03*
X632701D03*
X630201Y550907D03*
X632701D03*
X634185Y569426D03*
X634471Y566929D03*
X628425Y572070D03*
X629772Y569928D03*
X632119Y570962D03*
X631862Y568475D03*
X621592Y1033862D03*
X626476Y1155610D03*
X621727Y1556800D03*
X648655Y76587D03*
Y72615D03*
X650094Y100625D03*
X643113Y97475D03*
X643044Y106186D03*
X650673Y141247D03*
X655160Y143518D03*
X642110Y143740D03*
X654260Y152373D03*
X640532Y172190D03*
X638030Y181009D03*
X643205Y168697D03*
X644293Y191941D03*
X652347Y192490D03*
X646302Y206767D03*
X651302D03*
X648802D03*
X639971Y213132D03*
X648932Y221708D03*
X647547Y228221D03*
X645847Y224421D03*
X647547Y231021D03*
X646432Y221708D03*
X651432D03*
X639971Y215632D03*
X650598Y236189D03*
X648098D03*
X653098D03*
X653039Y248765D03*
X650539D03*
X648039D03*
X640215Y256303D03*
X644990Y266114D03*
X650736Y268195D03*
X653536Y270695D03*
Y268195D03*
X650736Y270695D03*
X648236D03*
Y268195D03*
X642463Y281982D03*
X642414Y545528D03*
X651149Y577716D03*
X648211Y610400D03*
X650958Y668153D03*
X662935Y60513D03*
X665795Y60438D03*
X657507Y58013D03*
X656560Y68581D03*
X671476Y86012D03*
X656573Y80581D03*
X660703Y88801D03*
X663620Y94351D03*
X667569Y94279D03*
X663063Y85731D03*
X666617Y86046D03*
X658756Y103621D03*
X666813Y116594D03*
X654467Y112083D03*
X666813Y119594D03*
X667247Y124283D03*
X672313Y124879D03*
X665654Y161306D03*
X657410Y152562D03*
X662905Y157370D03*
X666989Y176665D03*
Y168665D03*
X658275Y172665D03*
X658212Y178560D03*
X658102Y183834D03*
X659088Y186629D03*
X657622Y190185D03*
X658392Y200864D03*
X666989Y196665D03*
Y192665D03*
X667102Y186778D03*
X667021Y204864D03*
Y208864D03*
X658481Y212455D03*
X658415Y207037D03*
X655782Y221642D03*
X662662Y219379D03*
X663290Y228631D03*
X668886Y248371D03*
X657196Y265897D03*
X659696D03*
X661761Y382109D03*
X661760Y551683D03*
Y561420D03*
Y558917D03*
X657581Y577937D03*
X660586Y606929D03*
X665086Y604567D03*
X665586Y595500D03*
X660827Y612592D03*
X666244Y610072D03*
X660546Y618400D03*
X666180Y616317D03*
X665643Y646055D03*
X658233Y646449D03*
X658064Y650119D03*
X657967Y662981D03*
X662092Y666275D03*
X659209Y691851D03*
X661018Y707592D03*
X688399Y97667D03*
X671476Y94374D03*
X678782Y116594D03*
X684055Y102495D03*
X677756Y110784D03*
X672756D03*
X678782Y119594D03*
X682316Y125107D03*
X677335Y124663D03*
X683789Y142862D03*
X684830Y148717D03*
X678679Y138838D03*
X674870Y218085D03*
X681383Y219470D03*
Y216970D03*
X678670Y216385D03*
X681383Y221970D03*
X681449Y226320D03*
X672070Y218085D03*
X684410Y228646D03*
X683367Y232971D03*
X677397Y249108D03*
X680017Y244571D03*
X682857Y339477D03*
X687055Y376456D03*
X685353Y396718D03*
X678461Y455981D03*
X675237Y465611D03*
X682586Y530000D03*
X682086Y540500D03*
X681086Y547075D03*
X681286Y549800D03*
X680586Y568000D03*
X681126Y558800D03*
X681190Y562800D03*
X696859Y103411D03*
X697253Y97667D03*
X692649Y95111D03*
X697018Y106561D03*
X690930Y143762D03*
X691396Y199248D03*
X687378Y195176D03*
X689878D03*
X694396Y199248D03*
X694878Y195176D03*
X692378D03*
X691396Y201748D03*
X689232Y206806D03*
X687459Y210509D03*
X689959D03*
X694396Y202048D03*
X691732Y206806D03*
X697996Y230117D03*
X689151Y230556D03*
X693406Y227824D03*
X694012Y238714D03*
X688136Y242078D03*
X693493Y246874D03*
X695713Y244297D03*
X690504Y253198D03*
X689486Y339583D03*
X702448Y546712D03*
Y542712D03*
X699188Y656321D03*
X702086Y678462D03*
X692478Y730641D03*
X702691Y762971D03*
Y756971D03*
X692356Y764614D03*
X691991Y759581D03*
X702677Y780659D03*
Y775159D03*
X692155Y778974D03*
X692221Y773449D03*
X690449Y814406D03*
X708049Y90650D03*
X713361Y90615D03*
X717732Y95236D03*
X717682Y99961D03*
X707799Y95236D03*
X716544Y215478D03*
Y210478D03*
Y207978D03*
Y212978D03*
X718338Y305272D03*
X712692Y356779D03*
X717105Y410964D03*
X717420Y404334D03*
X709781Y442956D03*
X720996Y442856D03*
X711598Y438323D03*
X719051Y458455D03*
X719612Y451108D03*
X710643Y456335D03*
X711764Y445873D03*
X706211Y465874D03*
X711463Y546712D03*
X704364Y618288D03*
X711328Y653821D03*
X705390Y655789D03*
X705776Y678519D03*
X713200Y699676D03*
X716623Y702463D03*
X703600Y702212D03*
X703680Y697094D03*
X715802Y706446D03*
X710196Y707562D03*
X717434Y782500D03*
X710275Y786131D03*
X713222Y793312D03*
Y790812D03*
X712901Y821600D03*
X726596Y74793D03*
Y77393D03*
Y79993D03*
Y85193D03*
Y82593D03*
X726640Y92874D03*
X734921Y98551D03*
X728667Y104249D03*
Y107649D03*
X733233Y147540D03*
X728289Y162368D03*
X725689D03*
X734386Y181426D03*
X734594Y184221D03*
X727000Y213213D03*
Y208213D03*
X733872Y208695D03*
X731072D03*
X733572Y211695D03*
X731072D03*
X727000Y210713D03*
Y215713D03*
X722373Y264180D03*
X719873D03*
X719798Y258880D03*
X737249Y265701D03*
X731567Y267526D03*
X728767D03*
X734067D03*
Y270026D03*
X731567D03*
X728767D03*
X723404Y379657D03*
X721900Y384500D03*
X723440Y391496D03*
X734661Y393633D03*
X731511Y381113D03*
X723440Y398583D03*
X732035Y442606D03*
X722097Y453881D03*
X731952Y446606D03*
X722097Y446595D03*
X732959Y463479D03*
X733430Y467367D03*
X724362Y504731D03*
X722473Y693718D03*
X723656Y705858D03*
X720985Y711658D03*
X725667Y732161D03*
X723177Y728219D03*
X721163Y738981D03*
X733000Y816000D03*
X730880Y828924D03*
X733680Y828977D03*
X732713Y853890D03*
X722600Y869600D03*
X728503Y891692D03*
X736452Y890548D03*
X728692Y886653D03*
X724707Y893143D03*
X719661Y904900D03*
X722789Y927095D03*
X722400Y942500D03*
X725194Y942073D03*
X720271Y931730D03*
X732306Y942682D03*
X728846Y948331D03*
X733798Y950186D03*
X727116Y959326D03*
X732825Y1604100D03*
X736067Y1611892D03*
X729600Y1625165D03*
X732268Y1618260D03*
X751017Y76587D03*
Y72615D03*
X752456Y100625D03*
X745475Y97475D03*
X745406Y106186D03*
X738471Y103783D03*
X737005Y141247D03*
X744472Y143740D03*
X741852Y148277D03*
X735389Y165393D03*
Y162793D03*
Y170493D03*
Y167993D03*
X740392Y181009D03*
X737597Y181366D03*
X745567Y168697D03*
X742894Y172190D03*
X742313Y177616D03*
X746655Y191941D03*
X737211Y184012D03*
X750667Y192300D03*
X751164Y206767D03*
X748664D03*
X738630Y213859D03*
Y211359D03*
X742333Y213132D03*
X749909Y228221D03*
Y231021D03*
X751294Y221708D03*
X748209Y224421D03*
X748794Y221708D03*
X742333Y215632D03*
X750460Y236189D03*
X750401Y248765D03*
X742577Y256303D03*
X747352Y266114D03*
X742336Y265896D03*
X750598Y268195D03*
Y270695D03*
X744825Y281982D03*
X738884Y281716D03*
X741051Y316389D03*
X749444Y393858D03*
X749606Y384410D03*
X752785Y382047D03*
X753086Y403500D03*
X751086Y398583D03*
X749539Y438269D03*
Y440869D03*
Y435669D03*
Y430469D03*
Y433069D03*
X735599Y449961D03*
X739316Y458572D03*
X750393Y451677D03*
Y454177D03*
X741992Y763480D03*
X742000Y768137D03*
X743428Y772418D03*
X741993Y775909D03*
X736000Y864266D03*
X742407Y988452D03*
X743062Y1004460D03*
X749439Y1458777D03*
X740530Y1524113D03*
X747140Y1581335D03*
X749786Y1590517D03*
X738775Y1597866D03*
X737892Y1602340D03*
X749704Y1608631D03*
X744924Y1617709D03*
X743331Y1627871D03*
X741705Y1622015D03*
X738325Y1634485D03*
X762697Y55513D03*
X758922Y68581D03*
X765297Y60513D03*
X758935Y80581D03*
X763065Y88801D03*
X765982Y94351D03*
X769931Y94279D03*
X765425Y85731D03*
X756829Y112083D03*
X761118Y103621D03*
X769609Y124283D03*
X753035Y141247D03*
X757522Y143518D03*
X756622Y152373D03*
X759772Y152562D03*
X765267Y157370D03*
X760637Y172665D03*
X760464Y183834D03*
X760574Y178560D03*
X761450Y186629D03*
X754709Y192490D03*
X759984Y190185D03*
X760754Y200864D03*
X753182Y198671D03*
X753664Y206767D03*
X769383Y208864D03*
X760843Y212455D03*
X760777Y207037D03*
X753794Y221708D03*
X758144Y221642D03*
X765024Y219379D03*
X763653Y224536D03*
X752960Y236189D03*
X755460D03*
X755401Y248765D03*
X752901D03*
X753098Y268195D03*
X755898D03*
X753098Y270695D03*
X755898D03*
X759558Y265897D03*
X762058D03*
X769349Y324518D03*
X759029Y328867D03*
X754805Y339559D03*
X759624Y353961D03*
X756086Y377912D03*
X766344D03*
X755086Y391496D03*
X756086Y386500D03*
X766344Y381912D03*
X756174Y397912D03*
X755086Y409000D03*
X766344Y397912D03*
X752339Y438269D03*
Y433069D03*
Y430469D03*
Y435669D03*
Y440869D03*
X752893Y451677D03*
Y454177D03*
X752097Y460218D03*
Y463618D03*
X755035Y1443524D03*
X765713Y1437365D03*
X760398Y1440276D03*
X755187Y1580821D03*
X759802Y1590864D03*
X763542Y1590186D03*
X768361Y1610083D03*
X762671Y1619367D03*
X756358Y1613767D03*
X768157Y60438D03*
X773838Y86012D03*
Y94374D03*
X768979Y86046D03*
X781144Y116594D03*
X769175D03*
X775118Y110784D03*
X780118D03*
X781144Y119594D03*
X769175D03*
X784678Y125107D03*
X779697Y124663D03*
X774675Y124879D03*
X781041Y138838D03*
X768016Y161306D03*
X769351Y176665D03*
Y168665D03*
Y192665D03*
X769464Y186778D03*
X769383Y204864D03*
X774432Y218085D03*
X777232D03*
X783745Y216970D03*
X781032Y216385D03*
X783745Y221970D03*
X783811Y226320D03*
X783745Y219470D03*
X782379Y244571D03*
X779759Y249108D03*
X771140Y248371D03*
X772165Y314890D03*
X784118Y303962D03*
X771941Y311740D03*
X772162Y332584D03*
X778502Y348015D03*
X772859Y347937D03*
X774419Y353470D03*
X784902Y428653D03*
X775746Y539315D03*
X777708Y553287D03*
X781429Y545017D03*
X778860Y626912D03*
X778205Y622912D03*
X783694Y1410977D03*
X778685Y1416198D03*
X780162Y1412848D03*
X777749Y1431432D03*
X783469Y1424655D03*
X771557Y1446818D03*
X768910Y1437741D03*
X777749Y1435432D03*
Y1439432D03*
X777260Y1446237D03*
X778428Y1455156D03*
X777725Y1450193D03*
X783620Y1460108D03*
X768812Y1453306D03*
X781124Y1583553D03*
X781110Y1595254D03*
X777059Y1608982D03*
X784046Y1600438D03*
X778045Y1619395D03*
X778358Y1627418D03*
X771383Y1616917D03*
X799221Y103411D03*
X799615Y97667D03*
X790761D03*
X795011Y95111D03*
X786417Y102495D03*
X799380Y106561D03*
X786151Y142862D03*
X793292Y143762D03*
X787192Y148717D03*
X796758Y199248D03*
X797240Y195176D03*
X794740D03*
X789740D03*
X792240D03*
X793758Y199248D03*
X794094Y206806D03*
X791594D03*
X789821Y210509D03*
X792321D03*
X793758Y201748D03*
X796758Y202048D03*
X800358Y230117D03*
X795768Y227824D03*
X791513Y230556D03*
X786772Y228646D03*
X796374Y238714D03*
X790498Y242078D03*
X785729Y232971D03*
X795855Y246874D03*
X798075Y244297D03*
X789722Y256394D03*
X786461Y293028D03*
X790280Y287421D03*
X800155Y337368D03*
X800029Y333368D03*
X797141Y350368D03*
X795445Y356950D03*
X789581Y405011D03*
X793893Y409502D03*
X784804Y425371D03*
X794173Y450510D03*
X802136Y448334D03*
X796000Y553101D03*
X788600Y1006923D03*
X799631Y1025440D03*
X795631D03*
X789050Y1026150D03*
X796338Y1138130D03*
X793842Y1143384D03*
X797160Y1146609D03*
X792277Y1173065D03*
X799020Y1175975D03*
X798353Y1172011D03*
X787887Y1174500D03*
X798542Y1188345D03*
X792382Y1191664D03*
X794533Y1195766D03*
X794983Y1334030D03*
Y1331230D03*
X793548Y1397690D03*
X795296Y1416995D03*
X792848Y1414718D03*
X793459Y1429165D03*
X789647Y1427518D03*
X788648Y1422044D03*
X785820Y1425993D03*
X798601Y1431673D03*
X793288Y1450918D03*
X793744Y1437159D03*
X786787Y1433800D03*
X787694Y1442749D03*
X800607Y1440760D03*
X790361Y1447895D03*
X790754Y1441399D03*
X793994Y1441499D03*
X799057Y1449158D03*
X797083Y1467883D03*
X799057Y1456016D03*
X794005Y1464178D03*
X790296Y1463459D03*
X787038Y1460533D03*
X786591Y1452803D03*
X790989Y1455695D03*
X799314Y1475693D03*
X797318Y1471242D03*
X810411Y90650D03*
X815723Y90615D03*
X810161Y95236D03*
X805952Y301675D03*
X817456Y305368D03*
Y313368D03*
X809490Y305368D03*
X809466Y310604D03*
X801097Y325858D03*
X817100Y319600D03*
X809457Y330459D03*
X809490Y325368D03*
Y317368D03*
X809489Y313830D03*
X809490Y321368D03*
Y333368D03*
X816177Y441442D03*
X813456Y441474D03*
X810749Y443045D03*
X815840Y444091D03*
Y456060D03*
X810453Y453330D03*
X810406Y448214D03*
X810756Y471071D03*
Y468571D03*
X814580Y468806D03*
X814828Y472053D03*
X810756Y473571D03*
Y476071D03*
X813902Y730738D03*
X813678Y740979D03*
X813653Y746856D03*
X817584Y764219D03*
X813635Y762000D03*
X818000Y797000D03*
X817845Y817879D03*
X818500Y810135D03*
X813000Y805000D03*
X813548Y814000D03*
X813009Y819734D03*
X815500Y824000D03*
X815863Y830097D03*
X814299Y840877D03*
X813887Y835146D03*
X816037Y845578D03*
X812440Y862306D03*
X814080Y864464D03*
X812575Y880834D03*
X812219Y883586D03*
X817884Y915425D03*
X803673Y1025440D03*
X803453Y1134729D03*
X814835D03*
X806835D03*
X809632Y1142666D03*
X817964Y1157404D03*
X811507Y1157544D03*
X810018Y1167768D03*
X815037D03*
X814160Y1178240D03*
X814170Y1185205D03*
X805212Y1180175D03*
X805519Y1187215D03*
X815455Y1201043D03*
X811485D03*
X807489D03*
X804452Y1199814D03*
X804458Y1193112D03*
X809027Y1219895D03*
X807020Y1217900D03*
X812302Y1223170D03*
X815149Y1226016D03*
X810148Y1374884D03*
X806148Y1383715D03*
Y1375208D03*
X810204Y1401661D03*
X804654Y1404769D03*
X812901Y1432804D03*
X815901D03*
X810059Y1432778D03*
X812104Y1426483D03*
X809986Y1438785D03*
X812986D03*
X815986D03*
X809986Y1441485D03*
X812986D03*
X815986D03*
X812901Y1435504D03*
X815901D03*
X810001D03*
X803057Y1449158D03*
X801057Y1447158D03*
X805569Y1441519D03*
X803057Y1456016D03*
X801057Y1458016D03*
X802684Y1465549D03*
X801354Y1478681D03*
X807576Y1469584D03*
X804919Y1489247D03*
X828958Y79993D03*
Y77393D03*
Y74793D03*
Y85193D03*
Y82593D03*
X829002Y92874D03*
X820094Y95236D03*
X820044Y99961D03*
X831029Y104249D03*
Y107649D03*
X830651Y162368D03*
X828051D03*
X829362Y213213D03*
X818906Y207978D03*
Y212978D03*
Y215478D03*
Y210478D03*
X829362Y208213D03*
Y210713D03*
Y215713D03*
X822235Y264180D03*
X824735D03*
X822160Y258880D03*
X831129Y267526D03*
Y270026D03*
X822477Y309368D03*
X825971Y345101D03*
X829485D03*
X822626Y348066D03*
X818840Y444091D03*
X825103Y430358D03*
Y435558D03*
Y432958D03*
X831378Y433086D03*
Y435686D03*
Y430486D03*
X818840Y456060D03*
X824650Y455034D03*
Y450034D03*
X817328Y472053D03*
X820810Y471243D03*
X817380Y468806D03*
X823544Y475061D03*
Y472561D03*
X820810Y473743D03*
X828918Y480580D03*
X831418D03*
X831057Y484036D03*
X834282Y536085D03*
X828272Y535462D03*
X827291Y533100D03*
X829496Y676793D03*
X829784Y716589D03*
Y705489D03*
X823890Y703415D03*
X823670Y710542D03*
X824387Y726246D03*
X818307Y724144D03*
X821582Y727140D03*
X826484Y747127D03*
X827500Y750000D03*
X819788Y739634D03*
X830484Y738750D03*
X824500Y760500D03*
X830075Y769000D03*
X822151Y752283D03*
X824500Y756000D03*
X817365Y756827D03*
X824500Y778500D03*
Y774000D03*
Y782500D03*
X830075Y787000D03*
X824500Y796500D03*
X824342Y792315D03*
X824500Y800500D03*
X830075Y805000D03*
X824500Y814500D03*
X830075Y823000D03*
X829946Y829788D03*
X825721Y839816D03*
X830014Y833046D03*
X829757Y842672D03*
X822608Y848526D03*
X822916Y852576D03*
X823540Y857956D03*
X831654Y864494D03*
X831583Y853454D03*
X822938Y863298D03*
X826209Y866052D03*
X823234Y870830D03*
X833194Y873561D03*
X827992Y874107D03*
X826070Y893014D03*
X817152Y896380D03*
X817139Y890330D03*
X830063Y898500D03*
X819918Y889365D03*
X823900Y882083D03*
X824804Y898395D03*
X834465Y884538D03*
X829848Y914211D03*
X818031Y907747D03*
X825336Y916774D03*
X831057Y916745D03*
X834751Y922368D03*
X823552Y930700D03*
X829617Y939583D03*
X824414Y939655D03*
X816519Y931147D03*
X824168Y949538D03*
X825670Y964671D03*
X832423Y964669D03*
X828964Y977780D03*
X830356Y1116251D03*
X827856D03*
X825335Y1137129D03*
X819449Y1134534D03*
X819026Y1128137D03*
X825744Y1150087D03*
X823220Y1170767D03*
X818879Y1187310D03*
X823309Y1180235D03*
X823516Y1185238D03*
X819489Y1201039D03*
X823489Y1200969D03*
X823608Y1208993D03*
X819419Y1230265D03*
X817360Y1228226D03*
X816648Y1380758D03*
X824901Y1427404D03*
X827901D03*
X821901D03*
X818901Y1430104D03*
X821901D03*
X830901D03*
X827901D03*
X824901D03*
Y1432804D03*
X827901D03*
X830901D03*
X821901D03*
X818901D03*
X824901Y1435504D03*
X827901D03*
X821901D03*
X818901D03*
X821986Y1441485D03*
X818986D03*
Y1438785D03*
X821986D03*
X826204Y1444689D03*
Y1440689D03*
X826341Y1451236D03*
X826365Y1458974D03*
X826219Y1455244D03*
X837283Y98551D03*
X847837Y97475D03*
X840833Y103783D03*
X847768Y106186D03*
X837751Y165393D03*
Y162793D03*
Y170493D03*
Y167993D03*
X842754Y181009D03*
X839959Y181366D03*
X836748Y181426D03*
X847929Y168697D03*
X844675Y177616D03*
X845256Y172190D03*
X839573Y184012D03*
X836956Y184221D03*
X836234Y208695D03*
X833434D03*
X835934Y211695D03*
X840992Y213859D03*
Y211359D03*
X833434Y211695D03*
X844695Y213132D03*
Y215632D03*
X844939Y256303D03*
X844698Y265896D03*
X839611Y265701D03*
X849714Y266114D03*
X836429Y267526D03*
X833929D03*
Y270026D03*
X836429D03*
X841246Y281716D03*
X847187Y281982D03*
X842240Y324854D03*
X848879Y360849D03*
X845435Y356172D03*
X846098Y408715D03*
X849591Y411388D03*
X842515Y461382D03*
X850732Y469382D03*
X842779Y473076D03*
X842916Y467009D03*
X833293Y490636D03*
Y487836D03*
X833918Y480580D03*
X834215Y484138D03*
X844227Y479882D03*
X842476Y482382D03*
X833269Y506683D03*
X833953Y530621D03*
X848444Y657756D03*
X837272Y663910D03*
X839636Y666533D03*
X842352Y659243D03*
X842640Y662814D03*
X838152Y700215D03*
X845784Y705489D03*
Y716589D03*
X845850Y710969D03*
X845784Y708089D03*
X836078Y709619D03*
X835987Y713745D03*
X838484Y746701D03*
X846484Y738750D03*
X836713Y738751D03*
X842661Y769521D03*
X846000Y772079D03*
X840136Y830903D03*
X836839Y831301D03*
X836894Y824401D03*
X848224Y823502D03*
X835626Y843629D03*
X838189Y843459D03*
Y847490D03*
X835215Y847719D03*
X848384Y843459D03*
X846239Y847490D03*
X835553Y835119D03*
X848384Y839459D03*
Y835459D03*
X838194Y836962D03*
X848739Y847459D03*
X837183Y855459D03*
X840234Y851459D03*
X847138Y859459D03*
X839530Y859408D03*
X848384Y863459D03*
X846336Y855459D03*
X845820Y863413D03*
X848384Y851459D03*
X843574Y859423D03*
X837434Y851459D03*
X833327Y855560D03*
X837383Y879530D03*
X837396Y871459D03*
X840234Y875459D03*
X836999Y867413D03*
X845876Y879459D03*
X848384Y867459D03*
X845820Y867413D03*
X848384Y879459D03*
Y871459D03*
Y875459D03*
X837290Y887490D03*
X842827Y895443D03*
X835346Y891346D03*
X848322Y888421D03*
X848792Y896472D03*
X836066Y894955D03*
X847098Y891213D03*
X845633Y883492D03*
X845964Y887490D03*
X837276Y883459D03*
X848200Y883400D03*
X841329Y926602D03*
X841274Y914060D03*
X843315Y916612D03*
X836909Y916618D03*
Y914018D03*
X833683Y939579D03*
X836243D03*
X833683Y949105D03*
X836243D03*
X842856Y949146D03*
X836423Y964669D03*
X835431Y977775D03*
X840935Y1011499D03*
X844058Y1011738D03*
X848045Y1019310D03*
X848070Y1022190D03*
X839744Y1444959D03*
Y1440859D03*
Y1448959D03*
X836704Y1448849D03*
Y1440849D03*
X836744Y1444849D03*
X845306Y1438269D03*
X846844Y1454334D03*
X837685Y1453196D03*
X839744Y1457959D03*
X835474Y1457397D03*
X846044Y1451459D03*
X839744Y1461959D03*
X834475Y1460059D03*
X865059Y55513D03*
X861284Y68581D03*
X861297Y80581D03*
X853379Y76587D03*
Y72615D03*
X854818Y100625D03*
X859191Y112083D03*
X863480Y103621D03*
X862826Y183834D03*
X862999Y172665D03*
X862936Y178560D03*
X849017Y191941D03*
X863812Y186629D03*
X857071Y192490D03*
X862346Y190185D03*
X863116Y200864D03*
X853029Y192300D03*
X853526Y206767D03*
X856026D03*
X851026D03*
X863205Y212455D03*
X863139Y207037D03*
X860506Y221642D03*
X852271Y228221D03*
Y231021D03*
X853656Y221708D03*
X856156D03*
X850571Y224421D03*
X851156Y221708D03*
X866015Y224536D03*
X852822Y236189D03*
X855322D03*
X857822D03*
X852763Y248765D03*
X855263D03*
X857763D03*
X852960Y268195D03*
Y270695D03*
X855460D03*
X864420Y265897D03*
X858260Y268195D03*
Y270695D03*
X861920Y265897D03*
X855460Y268195D03*
X863430Y309368D03*
Y316970D03*
X863114Y324505D03*
X863040Y330140D03*
X861770Y343006D03*
X852569Y356712D03*
X856069Y356426D03*
X854086Y374500D03*
X858586D03*
X863086D03*
X860586Y383000D03*
X861235Y394000D03*
X854086Y392999D03*
X864086Y384000D03*
X855017Y411969D03*
X861413Y417071D03*
X858827Y419896D03*
X858410Y413890D03*
X858767Y416685D03*
X861622Y419688D03*
X862882Y458991D03*
X854882D03*
X862882Y461791D03*
X854882D03*
X850748Y465382D03*
X861468Y483303D03*
Y487303D03*
X858169Y495032D03*
X853989Y630453D03*
Y632953D03*
X861663Y646653D03*
X855300Y646819D03*
X853982Y657506D03*
X859441Y678015D03*
X849680Y694789D03*
X858186Y701170D03*
X855646Y692710D03*
X864029Y688970D03*
X867455Y710611D03*
X858002Y707244D03*
X857986Y722670D03*
X854484Y746701D03*
X859199Y744517D03*
X854484Y738633D03*
X859000Y756000D03*
X849500Y758500D03*
Y763500D03*
X863443Y753254D03*
X859000Y764000D03*
Y760000D03*
Y774000D03*
X849500Y776500D03*
Y781500D03*
X861425Y770500D03*
X859000Y781000D03*
Y778000D03*
X853282Y789887D03*
X857632Y789385D03*
X859000Y792000D03*
X849500Y794500D03*
Y799500D03*
X861425Y788500D03*
X859000Y800000D03*
Y796000D03*
X861425Y806500D03*
X859000Y810000D03*
X849500Y812500D03*
X859000Y814000D03*
X850496Y831469D03*
X861425Y824500D03*
X849500Y817500D03*
X859000Y818000D03*
X851184Y839459D03*
Y835459D03*
X859165Y848728D03*
X851239Y847459D03*
X851184Y843459D03*
Y863459D03*
X862114Y859479D03*
X851184Y851459D03*
X859603Y863570D03*
X859461Y859459D03*
X851184Y867459D03*
Y871459D03*
Y875459D03*
X859234Y879600D03*
X859463Y866125D03*
X851184Y879459D03*
X849267Y892567D03*
X859614Y883800D03*
Y887846D03*
X850900Y888359D03*
X850800Y883500D03*
X858988Y898307D03*
X855524Y898505D03*
X864253Y918042D03*
X856628D03*
X849600Y918028D03*
X849205Y924129D03*
X867096Y935963D03*
X858601Y934505D03*
X853030Y934690D03*
X851925Y951350D03*
X850686Y1006923D03*
X853449Y1007048D03*
X863334Y1009393D03*
X861047Y1018909D03*
X860887Y1023208D03*
Y1026762D03*
X863956Y1020763D03*
X863689Y1024974D03*
X863944Y1432359D03*
Y1429359D03*
X860944Y1432359D03*
X857944Y1429359D03*
X860944D03*
Y1426359D03*
X857944D03*
X863944D03*
X857944Y1432359D03*
X863944Y1435359D03*
Y1441359D03*
Y1438359D03*
X860944Y1441359D03*
X857944Y1435359D03*
X860944D03*
X857944Y1441359D03*
Y1438359D03*
X860944D03*
X850544Y1447559D03*
X853514Y1457510D03*
X850644Y1457359D03*
X870519Y60438D03*
X867659Y60513D03*
X876200Y86012D03*
X867787Y85731D03*
X865427Y88801D03*
X876200Y94374D03*
X872293Y94279D03*
X868344Y94351D03*
X871341Y86046D03*
X871713Y168665D03*
Y176665D03*
Y196665D03*
Y192665D03*
X871826Y186778D03*
X871745Y204864D03*
Y208864D03*
X867386Y219379D03*
X883118Y262687D03*
X876622Y293721D03*
X872050Y302644D03*
X873262Y300030D03*
X869924Y305368D03*
X879112Y302369D03*
X877977Y305368D03*
Y309368D03*
X869924Y313368D03*
X877977D03*
Y325368D03*
Y317368D03*
Y321368D03*
X869924D03*
Y328722D03*
X874005Y344917D03*
X870413Y342791D03*
X869924Y333722D03*
X877977Y333368D03*
Y329368D03*
X872158Y359962D03*
X868086Y373750D03*
X876736Y383125D03*
X877909Y391731D03*
X880736Y383125D03*
X882925Y391099D03*
X872736Y391754D03*
X867586Y393000D03*
Y385000D03*
X869342Y407627D03*
X868586Y398500D03*
X877253Y420380D03*
X876917Y415322D03*
X879417D03*
X881190Y411619D03*
X878690D03*
X874253Y422880D03*
Y420080D03*
X877253Y422880D03*
X881271Y426952D03*
X878771D03*
X873536Y437408D03*
X876036D03*
X881036D03*
X878536D03*
X873771Y426952D03*
X876271D03*
X870882Y458991D03*
X880910Y454634D03*
Y457434D03*
Y460234D03*
X870882Y461791D03*
X869454Y479303D03*
X869954Y487303D03*
X882954Y486256D03*
X882195Y539204D03*
X867093Y554703D03*
X866938Y549771D03*
X878382Y554942D03*
X874649Y545296D03*
X876949Y571419D03*
X867093Y586828D03*
Y574703D03*
X881476Y588202D03*
X881131Y577349D03*
X875290Y578703D03*
X876351Y605023D03*
Y608523D03*
X879135Y632552D03*
X872862Y666859D03*
X878881Y667156D03*
X876286Y690970D03*
X868919Y700894D03*
X876286Y694970D03*
Y698970D03*
X881157Y749148D03*
X874142Y748914D03*
X879875Y753612D03*
X873728Y752692D03*
X875473Y742056D03*
X878670Y742841D03*
X869325Y761259D03*
X870017Y757313D03*
X867000Y774000D03*
X870000Y780000D03*
X879887Y784719D03*
X880040Y792851D03*
X867000Y792000D03*
X876402Y797415D03*
X874925Y800746D03*
X870035Y801032D03*
X867000Y810000D03*
X879916Y808965D03*
X877407Y828017D03*
X877818Y824214D03*
X876475Y830372D03*
X871600Y898584D03*
X872628Y918042D03*
X876628Y915242D03*
X880628Y918042D03*
X876628D03*
X872126Y934766D03*
X865830Y961600D03*
X870209Y949384D03*
X865973Y978187D03*
X874066Y977928D03*
X875391Y993796D03*
X872183Y993980D03*
X878976Y994020D03*
X871069Y1023114D03*
X878927Y1022387D03*
X878783Y1018751D03*
X872845Y1018988D03*
X866906Y1018751D03*
X866887Y1023208D03*
X875887D03*
X878887Y1026762D03*
X872887D03*
X866887D03*
X869741Y1025895D03*
X873824Y1071604D03*
X871224D03*
X876424D03*
Y1074104D03*
X871224D03*
X873824D03*
X868624Y1071604D03*
Y1074104D03*
X870057Y1091604D03*
X875257D03*
Y1089104D03*
X870057D03*
X872657D03*
X880115Y1084666D03*
X867457Y1091604D03*
Y1089104D03*
X872657Y1091604D03*
X875375Y1107647D03*
X872675D03*
X870075D03*
X867475D03*
X871364Y1120636D03*
X873964D03*
X876564D03*
X879264D03*
X875376Y1110175D03*
X872676D03*
X870076D03*
X867476D03*
X871364Y1139336D03*
X868664D03*
X879264Y1130336D03*
X876564D03*
X873964D03*
X871364D03*
X870522Y1148080D03*
X868022D03*
X875321Y1207654D03*
X872600Y1300833D03*
Y1298333D03*
X872944Y1432359D03*
Y1429359D03*
Y1426359D03*
X869944Y1432359D03*
Y1429359D03*
Y1426359D03*
X866944Y1432359D03*
Y1429359D03*
Y1426359D03*
X872944Y1435359D03*
Y1441359D03*
Y1438359D03*
X869944Y1435359D03*
X866944D03*
X869944Y1441359D03*
Y1438359D03*
X866944Y1441359D03*
Y1438359D03*
X881244Y1448859D03*
Y1440859D03*
X878244Y1451605D03*
X881244Y1464859D03*
Y1453059D03*
Y1456859D03*
X875744Y1453573D03*
X881244Y1476859D03*
X883233Y147540D03*
X887005Y141247D03*
X894472Y143740D03*
X891852Y148277D03*
X893284Y233339D03*
Y236739D03*
X895064Y250186D03*
X891383Y243203D03*
X896034Y243307D03*
X885884Y255118D03*
X897004Y257480D03*
X892484Y260860D03*
X887148Y249670D03*
X896953Y272012D03*
X886496Y268968D03*
X895140Y265236D03*
X886059Y284644D03*
X885918Y289500D03*
X885989Y309368D03*
Y305368D03*
Y317368D03*
X885953Y325368D03*
X885989Y313368D03*
X885953Y321368D03*
Y329368D03*
Y333368D03*
X896592Y358369D03*
Y354369D03*
X888812Y357372D03*
X883552Y357276D03*
X896592Y374369D03*
X891251Y387484D03*
X890553Y392038D03*
X887266Y400158D03*
Y405158D03*
Y402658D03*
X896579Y404043D03*
X893779D03*
X889979Y405743D03*
X890903Y454634D03*
Y457434D03*
Y460234D03*
X891454Y486303D03*
X892931Y534093D03*
X885931D03*
X891449Y547363D03*
X893949D03*
X886549Y553963D03*
X885556Y543664D03*
X887417Y566713D03*
X891673Y600049D03*
X891933Y618143D03*
X895933Y609696D03*
X883309Y666608D03*
X892461Y666671D03*
X886304Y666650D03*
X884903Y696678D03*
X884911Y690279D03*
X886836Y715970D03*
X893241Y704656D03*
X883686Y729778D03*
X889525Y722060D03*
X882098Y741565D03*
X884976Y740891D03*
X884463Y744757D03*
X881637Y744154D03*
X883126Y766124D03*
X883413Y759855D03*
X892040Y784511D03*
X889763Y788159D03*
X898737Y792289D03*
X889516Y792851D03*
X891916Y799605D03*
X884002Y797616D03*
X887916Y800815D03*
X895916Y808965D03*
X883916D03*
X887916D03*
X895829Y800660D03*
X883916Y800815D03*
X890326Y828548D03*
X895050D03*
X889178Y905619D03*
X884628Y915242D03*
Y918042D03*
X896553D03*
X892628Y915242D03*
X888628D03*
Y918042D03*
X882763Y933472D03*
X891367Y941126D03*
X888400Y994579D03*
X894660Y994330D03*
X891343Y994378D03*
X885099Y1021685D03*
X881887Y1023208D03*
X888743Y1019931D03*
X895394Y1026985D03*
X893147Y1020025D03*
X893887Y1023208D03*
X887887D03*
X890887Y1026762D03*
X884887D03*
X882779Y1074104D03*
Y1071604D03*
X887979Y1074104D03*
X885379D03*
X890579D03*
Y1071604D03*
X885379D03*
X887979D03*
X882615Y1084666D03*
X887862Y1088067D03*
X894004Y1081231D03*
X892856Y1102760D03*
X894249Y1114103D03*
X891549D03*
X888949D03*
X886349D03*
Y1123803D03*
X888949D03*
X891549D03*
X894249D03*
X895275Y1132870D03*
X892575D03*
X895547Y1145169D03*
X894713Y1210419D03*
X898878Y1214182D03*
X899286Y1219469D03*
X892532Y1220112D03*
X897169Y1225259D03*
X886888Y1263058D03*
X889388D03*
X891888D03*
X889388Y1260558D03*
X886888D03*
X891888D03*
X886926Y1298712D03*
X889729Y1295516D03*
X891107Y1314305D03*
X887342Y1314990D03*
X889244Y1444859D03*
X892244Y1449636D03*
Y1440859D03*
X889944Y1457959D03*
X889244Y1460859D03*
X895244Y1457510D03*
X889336Y1452554D03*
X893919Y1462132D03*
X889244Y1472859D03*
Y1468859D03*
X903035Y141247D03*
X907522Y143518D03*
X906622Y152373D03*
X909772Y152562D03*
X899573Y158195D03*
X910977Y243307D03*
Y248032D03*
Y262205D03*
X898048Y269387D03*
X913057Y311046D03*
X915653Y307438D03*
X899352Y308560D03*
Y311960D03*
X909298Y302347D03*
X905898D03*
X898533Y334498D03*
X908521Y356708D03*
X908625Y359317D03*
X905483Y355262D03*
X905000Y362158D03*
X898869Y351114D03*
X906161Y367191D03*
X913288Y372752D03*
X910646Y376084D03*
X906344Y372524D03*
X911072Y386992D03*
X897736Y383125D03*
X901747Y398492D03*
Y403492D03*
Y400992D03*
X910250Y457262D03*
Y454462D03*
X907450D03*
Y457262D03*
X910250Y451662D03*
X907450D03*
X910250Y460062D03*
X907450D03*
X910236Y465272D03*
X910759Y475511D03*
X899931Y534093D03*
X899530Y530753D03*
X914296Y558143D03*
X913728Y550495D03*
X899407Y560019D03*
X908846Y560124D03*
X910789Y598726D03*
X898207Y599891D03*
X900676Y621536D03*
X904076D03*
X909508Y621616D03*
X912908D03*
X900753Y656925D03*
X912462Y683770D03*
X909265Y677795D03*
X912462Y687770D03*
X906886Y702285D03*
X902236Y689332D03*
Y694332D03*
X908699Y709387D03*
X913247Y714204D03*
X902841Y703665D03*
X910836Y721570D03*
X913858Y721289D03*
X907866Y795572D03*
X911028Y796598D03*
X909785Y810778D03*
X903916Y810809D03*
X913716Y811954D03*
X899916Y808965D03*
X902641Y800748D03*
X907884Y829866D03*
X908920Y905630D03*
X900628Y918042D03*
X912628Y915242D03*
X908628Y918042D03*
X900628Y915242D03*
X912628Y918042D03*
X904838D03*
X908628Y915242D03*
X900983Y940895D03*
X903759Y951358D03*
X909811Y962400D03*
X913005Y969605D03*
X912690Y994350D03*
X897825Y994413D03*
X909166Y994188D03*
X897717Y1019915D03*
X899887Y1023208D03*
Y1026762D03*
X908422Y1023103D03*
X908856Y1017677D03*
X902389Y1081764D03*
X908799Y1093659D03*
Y1088659D03*
X908278Y1083484D03*
X908799Y1096659D03*
Y1100659D03*
X902353Y1104333D03*
X898278Y1136426D03*
X898047Y1145169D03*
X903959Y1207823D03*
X906784Y1216607D03*
X913784Y1221057D03*
X910633Y1222799D03*
X906309Y1226647D03*
X909077Y1232724D03*
X899699Y1283872D03*
X910788Y1299456D03*
X906506Y1299188D03*
X902908Y1299828D03*
X911117Y1314130D03*
X902875Y1309301D03*
X905740Y1309264D03*
X908700Y1316300D03*
X911135Y1345560D03*
X904177Y1359955D03*
X899944Y1432359D03*
X908944Y1426359D03*
Y1429359D03*
Y1432359D03*
X911944Y1426359D03*
Y1429359D03*
Y1432359D03*
X905944Y1426359D03*
X899944D03*
X902944D03*
Y1429359D03*
X899944D03*
X902944Y1432359D03*
X905944Y1429359D03*
Y1432359D03*
X902944Y1438359D03*
X899944D03*
Y1441359D03*
X902944Y1435359D03*
X899944D03*
X908944Y1438359D03*
Y1441359D03*
X911944Y1438359D03*
Y1441359D03*
X902944D03*
X905944Y1438359D03*
Y1441359D03*
X908944Y1435359D03*
X911944D03*
X905944D03*
X919175Y116594D03*
X930118Y110784D03*
X925118D03*
X919175Y119594D03*
X924675Y124879D03*
X929697Y124663D03*
X919609Y124283D03*
X931041Y138838D03*
X918016Y161306D03*
X915267Y157370D03*
X916453Y167975D03*
X927898Y203256D03*
X925098D03*
X919577Y240945D03*
Y250394D03*
Y271654D03*
X919616Y268462D03*
X919577Y264567D03*
X923732Y304585D03*
X916229Y336333D03*
X919629D03*
X923311Y349959D03*
X929943Y372600D03*
X921343Y376888D03*
X916330Y377748D03*
X929947Y376821D03*
X915072Y386992D03*
X914323Y398551D03*
Y403551D03*
Y401051D03*
X927563Y424445D03*
X924763D03*
X921963D03*
X927280Y436716D03*
X921680D03*
X924480D03*
X917541Y441280D03*
Y443780D03*
X927766Y456442D03*
X927596Y447453D03*
X921973Y469328D03*
X927401Y469059D03*
X916593Y469140D03*
X928999Y477948D03*
X920999D03*
X924999D03*
X917811Y544325D03*
X923453Y569578D03*
X923642Y561578D03*
X919080Y587640D03*
X921507Y578791D03*
X919038Y579378D03*
X923599Y581578D03*
X921217Y589216D03*
X913998Y597103D03*
X925949Y612363D03*
Y608863D03*
X922626Y633772D03*
X915800Y629700D03*
X918300D03*
X929690Y666593D03*
X920090Y666714D03*
X928353Y686342D03*
X928704Y680261D03*
X921061Y715386D03*
X926961Y723797D03*
X914202Y797460D03*
X923872Y798271D03*
X922352Y800809D03*
X917803Y811365D03*
X927916Y800909D03*
X929790Y828603D03*
X927916Y817015D03*
X925228Y816934D03*
X929181Y895029D03*
X921451Y903800D03*
X920628Y918042D03*
X916628D03*
X924628D03*
X928628D03*
X924628Y915242D03*
X920628D03*
X928628D03*
X916628D03*
X914193Y945318D03*
X928227Y951125D03*
X921364Y951251D03*
X918265Y969745D03*
X923289Y965780D03*
X926796Y966297D03*
X929741Y967006D03*
X916932Y994405D03*
X924956Y994321D03*
X924864Y1026762D03*
Y1023208D03*
X925024Y1018909D03*
X927861Y1024768D03*
X916749Y1084659D03*
X916992Y1076659D03*
X916749Y1092664D03*
X916875Y1098643D03*
X916749Y1104659D03*
X914637Y1210568D03*
Y1214838D03*
X930754Y1310564D03*
X924650Y1327819D03*
Y1324419D03*
X914033Y1345613D03*
X927193Y1361547D03*
X931159Y1379427D03*
X920360Y1387039D03*
X920255Y1383264D03*
X931199Y1371951D03*
X931159Y1390827D03*
Y1406027D03*
X914944Y1426359D03*
Y1429359D03*
Y1432359D03*
Y1438359D03*
Y1441359D03*
Y1435359D03*
X921498Y1446692D03*
X925697Y1460109D03*
X917744Y1453573D03*
X920244Y1451605D03*
X919285Y1456226D03*
X924803Y1474743D03*
X925435Y1478114D03*
X940761Y97667D03*
X945011Y95111D03*
X931144Y116594D03*
X936417Y102495D03*
X931144Y119594D03*
X934678Y125107D03*
X936151Y142862D03*
X943292Y143762D03*
X937192Y148717D03*
X945406Y180347D03*
X940406D03*
X942906D03*
X947424Y184419D03*
X944424Y186919D03*
X944760Y191977D03*
X942260D03*
X940487Y195680D03*
X942987D03*
X944424Y184419D03*
X934411Y202141D03*
X931698Y201556D03*
X934411Y207141D03*
X934477Y211491D03*
X934411Y204641D03*
X946234Y213390D03*
X942179Y215727D03*
X937438Y213817D03*
X936395Y218142D03*
X933403Y245507D03*
X936962Y249807D03*
X944248Y239844D03*
X945018Y276051D03*
X943183Y281652D03*
X930727Y302571D03*
X937000Y312284D03*
Y315684D03*
X934128Y355168D03*
X934464Y358618D03*
X944238Y360828D03*
X934047Y369160D03*
X936175Y364823D03*
X931072Y386992D03*
X941872Y440942D03*
X933424Y458455D03*
X933161Y451442D03*
X933404Y463462D03*
X933412Y468942D03*
X936653Y526836D03*
X944351Y534211D03*
X948532Y541135D03*
X939992Y527726D03*
Y548726D03*
Y544726D03*
X948598Y546553D03*
X948621Y552726D03*
X931627Y557641D03*
Y569578D03*
Y581578D03*
Y577578D03*
Y573578D03*
X933725Y585936D03*
X933741Y598087D03*
Y594687D03*
X933725Y589336D03*
X944296Y611071D03*
X941859Y621311D03*
Y629311D03*
X943181Y632536D03*
X945434Y634325D03*
X941859Y625311D03*
X946128Y666522D03*
X935281Y680945D03*
X936026Y727450D03*
X933974Y719371D03*
X942676Y789286D03*
X933201Y798297D03*
X946970Y786366D03*
X944916Y808965D03*
X938357Y808856D03*
X931916Y817015D03*
X942858Y819430D03*
X945736Y819397D03*
X935124Y831382D03*
X940100Y830700D03*
X935262Y825135D03*
X932418D03*
X940716Y840074D03*
X944297Y839975D03*
X933021Y840893D03*
X933054Y843804D03*
X937200Y841000D03*
X936450Y858327D03*
X937551Y860801D03*
X932770Y878233D03*
X935765Y878317D03*
X934928Y871727D03*
X932319Y871626D03*
X938729Y874396D03*
X932300Y890200D03*
X942194Y891216D03*
X930800Y904840D03*
X941592Y900908D03*
X936628Y915242D03*
X940628D03*
X932628D03*
X936628Y918042D03*
X932628D03*
X936371Y951484D03*
X940716Y951733D03*
X946363Y951179D03*
X935255Y962725D03*
X945671Y982191D03*
X940015Y1020176D03*
X934911Y1023579D03*
X945864Y1023208D03*
X930864Y1026762D03*
X936864D03*
X942864D03*
X939864Y1023208D03*
X930864D03*
X930883Y1018751D03*
X936822Y1018988D03*
X942760Y1018751D03*
X943093Y1021769D03*
X932289Y1074182D03*
Y1071682D03*
X937489Y1074182D03*
X934889D03*
X940089D03*
Y1071682D03*
X934889D03*
X937489D03*
X944092Y1084666D03*
X931628Y1091409D03*
Y1088909D03*
X936828Y1091409D03*
X934228D03*
X939428D03*
Y1088909D03*
X934228D03*
X936828D03*
X943241Y1120636D03*
X940541D03*
X937941D03*
X935341D03*
X937941Y1130336D03*
X940541D03*
X943241D03*
X932641Y1139336D03*
X935341Y1130336D03*
Y1139336D03*
X934500Y1147708D03*
X932000D03*
X939298Y1207654D03*
X943891Y1306608D03*
X944207Y1320739D03*
X947308Y1325035D03*
X931137Y1375878D03*
X931159Y1383227D03*
X939559Y1398427D03*
X931159Y1394627D03*
Y1387027D03*
Y1398427D03*
Y1402227D03*
X939559D03*
X944235Y1406262D03*
X943725Y1430744D03*
Y1427744D03*
X934725Y1430744D03*
X940725Y1427744D03*
Y1430744D03*
X934725Y1427744D03*
X937725D03*
Y1430744D03*
X943725Y1433744D03*
Y1439744D03*
Y1436744D03*
X940725Y1433744D03*
Y1439744D03*
Y1436744D03*
X934725Y1433744D03*
X937725D03*
X934725Y1439744D03*
X937725D03*
X934725Y1436744D03*
X937725D03*
X937671Y1492139D03*
Y1488139D03*
X949221Y103411D03*
X949615Y97667D03*
X960411Y90650D03*
X960161Y95236D03*
X949380Y106561D03*
X947906Y180347D03*
X947424Y187219D03*
X950177Y215730D03*
X947040Y223885D03*
X948741Y229468D03*
X948785Y242464D03*
X951278Y250583D03*
X946482Y255940D03*
X949974Y291554D03*
X947733Y319680D03*
X950953Y317947D03*
X960376Y392807D03*
X962769Y451419D03*
X959816Y472905D03*
X955816Y473419D03*
Y464919D03*
X963816Y464419D03*
X962563Y485128D03*
X954182Y481467D03*
X958124Y492354D03*
X958736Y482165D03*
X958974Y504825D03*
X956474D03*
X953974D03*
X949823Y491982D03*
X959600Y496486D03*
X949823Y495982D03*
X957977Y500202D03*
X958915Y517401D03*
X956415D03*
X953915D03*
X959466Y522569D03*
Y525369D03*
X958081Y531882D03*
X955581D03*
X961166Y529169D03*
X952531Y531948D03*
X960581Y531882D03*
X948905Y534909D03*
X958016Y555194D03*
X960816D03*
X958016Y563194D03*
X960816D03*
Y571194D03*
X958016D03*
X959573Y581222D03*
X962373D03*
X959573Y591215D03*
X962373D03*
X962545Y607762D03*
X959745D03*
Y610562D03*
X962545D03*
X950479Y622285D03*
X954535Y610548D03*
X950667Y616905D03*
X963365Y628078D03*
X961352Y633736D03*
X950865Y633724D03*
X950748Y627713D03*
X956345Y633716D03*
X949137Y666660D03*
X954526Y666671D03*
X947556Y699550D03*
X956023Y706907D03*
X951151Y730111D03*
X963869Y725057D03*
X955950Y734178D03*
X957763Y725336D03*
X959950Y734178D03*
X957579Y744168D03*
X953837Y763025D03*
X950699Y779711D03*
X956017Y770300D03*
X957500Y780800D03*
X955076Y784861D03*
X950475Y789361D03*
X955225Y788984D03*
X949609Y796051D03*
X957487Y798553D03*
X951461Y812223D03*
X951791Y808121D03*
X957379Y826586D03*
X954760Y826734D03*
X951708Y818894D03*
X955712Y833988D03*
X956239Y829577D03*
X960100Y846665D03*
X954700Y837700D03*
X961175Y838525D03*
X955343Y866850D03*
X955850Y862902D03*
X957900Y856300D03*
X950300Y877800D03*
X953240Y876834D03*
X954567Y927654D03*
X964280Y927777D03*
X958567Y927654D03*
X947029Y915242D03*
X959545Y918306D03*
X951863Y936168D03*
X957235Y936398D03*
X962329Y936229D03*
X957671Y977921D03*
X949671D03*
X961671Y991564D03*
X953671D03*
X949671D03*
X953671Y982191D03*
X954937Y1021998D03*
X948864Y1026762D03*
X954864D03*
X951864Y1023208D03*
X957864D03*
X957678Y1018555D03*
X961208Y1018592D03*
X960636Y1021917D03*
X959371Y1026985D03*
X948975Y1021325D03*
X951956Y1071604D03*
X949356D03*
X954556D03*
Y1074104D03*
X949356D03*
X951956D03*
X946756Y1071604D03*
Y1074104D03*
X946592Y1084666D03*
X957981Y1081231D03*
X951839Y1088067D03*
X956833Y1102760D03*
X950326Y1114103D03*
Y1123803D03*
X952926D03*
X955526D03*
Y1114103D03*
X958226D03*
X952926D03*
X958226Y1123803D03*
X956552Y1132870D03*
X959252D03*
X962255Y1136426D03*
X962024Y1145169D03*
X959524D03*
X958690Y1210419D03*
X963263Y1219469D03*
X962855Y1214182D03*
X956509Y1220112D03*
X961146Y1225259D03*
X950865Y1263058D03*
X953365D03*
X955865D03*
X953365Y1260558D03*
X950865D03*
X955865D03*
X948259Y1295965D03*
X948832Y1371654D03*
X951832D03*
X952561Y1383465D03*
X952417Y1379528D03*
X949469D03*
X949385Y1375591D03*
X952385D03*
X952514Y1391339D03*
X952395Y1395276D03*
X952716Y1387402D03*
X952180Y1407087D03*
X950239Y1409555D03*
X948235Y1406262D03*
X946725Y1427744D03*
Y1430744D03*
X949725D03*
Y1427744D03*
X960883Y1427997D03*
Y1430997D03*
X946725Y1433744D03*
X949725D03*
X946725Y1439744D03*
X949725D03*
X946725Y1436744D03*
X949725D03*
X960883Y1433997D03*
Y1436997D03*
Y1439997D03*
X952695Y1444139D03*
X979002Y92874D03*
X965723Y90615D03*
X970094Y95236D03*
X970044Y99961D03*
X978051Y162368D03*
X968906Y207978D03*
Y212978D03*
Y215478D03*
Y210478D03*
X970865Y264068D03*
X973365D03*
X972160Y258880D03*
X977150Y331972D03*
Y338972D03*
X975631Y343112D03*
Y346612D03*
X971721Y407762D03*
X968348Y402369D03*
X971826Y430187D03*
X966694Y427599D03*
X968462Y429368D03*
X970840Y457339D03*
X968340D03*
X962816Y442919D03*
X972030Y446071D03*
X979910Y445603D03*
X970840Y459839D03*
Y462339D03*
X968340D03*
Y459839D03*
X963816Y472905D03*
X976397Y473045D03*
X972397Y465004D03*
X977327Y462371D03*
X965412Y485138D03*
X969297Y478625D03*
Y475825D03*
X970997Y482425D03*
X970412Y485138D03*
X967912D03*
X976873Y491214D03*
Y493714D03*
X970745Y539731D03*
X967042Y537658D03*
X970745Y542231D03*
X978303Y541895D03*
X975803D03*
X967042Y540458D03*
X975503Y544895D03*
X978303D03*
X978581Y582747D03*
X965173Y581222D03*
X978032Y590801D03*
X965173Y591215D03*
X977857Y597130D03*
X976027Y620653D03*
Y617853D03*
X968145Y610562D03*
X965345Y607762D03*
Y610562D03*
X968145Y607762D03*
X977857Y605443D03*
X973857D03*
X972354Y627908D03*
X968365Y633473D03*
X978865Y642184D03*
X966797Y667653D03*
X970197D03*
X965774Y706907D03*
X973712Y722064D03*
X968589Y722434D03*
X970839Y729923D03*
X965042Y722234D03*
X971081Y722637D03*
X978352Y730766D03*
X963950Y734178D03*
X973450Y747280D03*
X965983Y763567D03*
X966127Y776382D03*
X968094Y799792D03*
X976186Y789819D03*
X967562Y802982D03*
X978978Y817618D03*
X978214Y821224D03*
X967337Y828901D03*
X970040Y842903D03*
X969309Y839334D03*
X974437Y849140D03*
X973510Y834991D03*
X967842Y864801D03*
X970299Y853773D03*
X978880Y869552D03*
X967510Y868971D03*
X966813Y904556D03*
X973988Y910038D03*
X968507Y937615D03*
X971443Y938828D03*
X965671Y991564D03*
Y982191D03*
X963864Y1026762D03*
Y1023208D03*
X966366Y1081764D03*
X972776Y1093659D03*
X972255Y1083484D03*
X972776Y1088659D03*
Y1096659D03*
X966330Y1104333D03*
X972776Y1100659D03*
X967936Y1207823D03*
X978614Y1210568D03*
X970761Y1216607D03*
X978614Y1214838D03*
X978169Y1221268D03*
X974985Y1290950D03*
X979996Y1386100D03*
X963883Y1430997D03*
Y1427997D03*
X966883Y1430997D03*
Y1427997D03*
X969883D03*
Y1430997D03*
X975883Y1427997D03*
Y1430997D03*
X972883D03*
Y1427997D03*
X963883Y1433997D03*
X966883D03*
X969883D03*
X963883Y1436997D03*
Y1439997D03*
X966883Y1436997D03*
Y1439997D03*
X969883Y1436997D03*
Y1439997D03*
X975883Y1433997D03*
X972883D03*
X975883Y1436997D03*
X972883D03*
X975883Y1439997D03*
X972883D03*
X977547Y1546081D03*
X974547D03*
X971547D03*
X978958Y85193D03*
Y82593D03*
Y77393D03*
Y74793D03*
Y79993D03*
X987283Y98551D03*
X990833Y103783D03*
X981029Y104249D03*
Y107649D03*
X985595Y147540D03*
X989367Y141247D03*
X996834Y143740D03*
X994214Y148277D03*
X980651Y162368D03*
X987751Y162793D03*
Y165393D03*
Y167993D03*
Y170493D03*
X995256Y172190D03*
X994675Y177616D03*
X989959Y181366D03*
X986748Y181426D03*
X992754Y181009D03*
X986956Y184221D03*
X989573Y184012D03*
X994695Y213132D03*
X979362Y208213D03*
Y210713D03*
Y213213D03*
X986234Y208695D03*
X983434D03*
X985934Y211695D03*
X990992Y213859D03*
Y211359D03*
X983434Y211695D03*
X979362Y215713D03*
X994695Y215632D03*
X994939Y256303D03*
X989611Y265701D03*
X994698Y265896D03*
X986429Y270026D03*
X983929D03*
X981129D03*
X983929Y267526D03*
X986429D03*
X981129D03*
X991246Y281716D03*
X997187Y281982D03*
X987517Y314092D03*
X993552Y318175D03*
X990420Y340454D03*
Y337954D03*
X989630Y343862D03*
X983717Y341665D03*
X983956Y346652D03*
X993026Y353813D03*
X981719Y352217D03*
X988631Y349496D03*
X980045Y366559D03*
X986373Y370467D03*
X991392Y409230D03*
X985303Y464652D03*
Y462152D03*
Y459652D03*
X987803Y464652D03*
Y462152D03*
Y459652D03*
X981843Y464818D03*
X992206Y491133D03*
Y498633D03*
X988134Y495151D03*
X985634D03*
X980576Y492987D03*
X985334Y498151D03*
X980576Y495487D03*
X988134Y498151D03*
X992206Y493633D03*
Y496133D03*
X982375Y537877D03*
X992306Y555897D03*
Y553297D03*
X989888Y548366D03*
X987388D03*
X982388D03*
X984888D03*
X982375Y542877D03*
Y545377D03*
Y540377D03*
X992306Y561097D03*
Y563697D03*
Y566797D03*
Y558497D03*
X986301Y570686D03*
X989096Y570478D03*
X989513Y576484D03*
X989156Y573689D03*
X986510Y573303D03*
X992906Y578405D03*
X981857Y597232D03*
X991907Y596782D03*
X986688Y596089D03*
X983843Y619513D03*
Y616713D03*
Y613913D03*
X993857Y605443D03*
X981857Y605637D03*
X980703Y625013D03*
X986600Y717641D03*
X987461Y745796D03*
X981876Y745179D03*
X988371Y764143D03*
X983786Y765647D03*
X984357Y777555D03*
X997051Y778833D03*
X990699Y778630D03*
X987990Y774005D03*
X987394Y787490D03*
X987501Y812573D03*
X985921Y805135D03*
X994051Y810871D03*
X996385Y816141D03*
X979203Y829159D03*
X994094Y829000D03*
X982300Y821200D03*
X987702Y829159D03*
X989700Y846500D03*
X987202Y846395D03*
X987319Y843589D03*
X979203Y833159D03*
X989800Y843900D03*
X987200Y848940D03*
X987703Y837159D03*
X990457Y852043D03*
X983269Y853883D03*
X981700Y856300D03*
X979891Y876589D03*
X992441Y870398D03*
X988054Y888283D03*
X990300Y897500D03*
X979592Y902849D03*
X982783Y909995D03*
X979498Y907500D03*
X989311Y920364D03*
X983227Y968565D03*
X988240Y1020015D03*
Y1016923D03*
Y1023968D03*
X984909Y1081071D03*
X983751Y1078675D03*
X980969Y1076659D03*
X980726Y1084659D03*
X980852Y1098643D03*
X980726Y1104659D03*
Y1092664D03*
X986645Y1108465D03*
X989513Y1097683D03*
X995009Y1131223D03*
X991763Y1140378D03*
Y1128378D03*
Y1134378D03*
X984558Y1140774D03*
X988112Y1137774D03*
X984558Y1128774D03*
Y1134774D03*
X987804Y1131619D03*
X984817Y1303297D03*
X979001Y1288925D03*
X990613Y1324248D03*
Y1327048D03*
X993413Y1324248D03*
Y1327048D03*
X990501Y1320756D03*
X988784Y1361974D03*
X980139Y1381496D03*
X980166Y1373622D03*
X980203Y1377559D03*
X980047Y1397245D03*
X985448Y1398271D03*
X980092Y1389370D03*
X980139Y1393308D03*
X984136Y1401636D03*
X987136D03*
X986949Y1430997D03*
Y1427997D03*
X983949D03*
X989949Y1430997D03*
Y1427997D03*
X983949Y1430997D03*
X992949Y1427997D03*
Y1430997D03*
X986949Y1433997D03*
X983949D03*
X989949D03*
X992949D03*
X986949Y1436997D03*
X983949D03*
X986949Y1439997D03*
X983949D03*
X989949Y1436997D03*
Y1439997D03*
X992949Y1436997D03*
Y1439997D03*
X978934Y1444392D03*
X978987Y1489832D03*
X982241Y1489637D03*
X986773Y1546081D03*
X983773D03*
X980773D03*
X1011187Y-43526D03*
Y-40126D03*
X1011284Y68581D03*
X1011297Y80581D03*
X1003379Y72615D03*
Y76587D03*
X1004818Y100625D03*
X997837Y97475D03*
X1013480Y103621D03*
X997768Y106186D03*
X1009191Y112083D03*
X1005397Y141247D03*
X1009884Y143518D03*
X1008984Y152373D03*
X1012936Y178560D03*
X997929Y168697D03*
X1012826Y183834D03*
X1012999Y172665D03*
X999017Y191941D03*
X1003029Y192300D03*
X1012346Y190185D03*
X1007071Y192490D03*
X1013116Y200864D03*
X1003526Y206767D03*
X1006026D03*
X1001026D03*
X1010291Y199582D03*
X1013139Y207037D03*
X1013205Y212455D03*
X1002271Y228221D03*
Y231021D03*
X1010506Y221642D03*
X1003656Y221708D03*
X1006156D03*
X1000571Y224421D03*
X1001156Y221708D03*
X1002822Y236189D03*
X1005322D03*
X1007822D03*
X1002763Y248765D03*
X1005263D03*
X1007763D03*
X999714Y266114D03*
X1008260Y268195D03*
X1005460D03*
X1002960D03*
X1008260Y270695D03*
X1002960D03*
X1005460D03*
X1000698Y300276D03*
X1002580Y309619D03*
X1010499Y309062D03*
X1003181Y323057D03*
X1001105Y318006D03*
X1009770Y344486D03*
X997020Y345354D03*
X1003076Y332496D03*
X1000420Y353954D03*
X996024Y352132D03*
X1001825Y581659D03*
X998332Y578986D03*
X997857Y596729D03*
X995913Y619758D03*
Y616958D03*
Y614158D03*
X1001857Y605443D03*
X1003900Y628700D03*
X1001605Y627605D03*
X1005800Y637600D03*
X1002883Y622521D03*
X1001676Y678015D03*
X1011185Y724519D03*
X1009562Y722438D03*
X1003990Y765899D03*
X1007990D03*
X1002751Y757169D03*
X999990Y764566D03*
X1013151Y756726D03*
X1012695Y776728D03*
X999990Y774671D03*
X1013319Y785929D03*
X1007027Y792973D03*
X998376Y810970D03*
X1006054Y810969D03*
X1010699Y803454D03*
X1002699Y819475D03*
X1011144Y844340D03*
X1010977Y841737D03*
X1012703Y837659D03*
X1001187Y850084D03*
X1004577Y853679D03*
X1004713Y871389D03*
X998313Y888295D03*
X1005413Y905295D03*
X1004953Y923995D03*
X1008935Y924007D03*
X1004994Y955372D03*
X1007919Y948822D03*
X1011019D03*
X1004719D03*
X1012219Y954222D03*
X1006222Y980337D03*
X1009564Y988874D03*
X999879Y998507D03*
X1001805Y1007522D03*
X1008571Y1006648D03*
X1008759Y1023900D03*
X1002180Y1013678D03*
X1002652Y1023731D03*
X1005938Y1018307D03*
X995317Y1137378D03*
X996213Y1324248D03*
Y1327048D03*
X1009333Y1346693D03*
Y1343293D03*
X998600Y1369200D03*
X1008387Y1380797D03*
X998600Y1373400D03*
X997401Y1381200D03*
X999283Y1377400D03*
X1007850Y1368835D03*
X998643Y1398271D03*
X1008138Y1407186D03*
Y1409986D03*
X1005338Y1407186D03*
Y1409986D03*
X1008138Y1415586D03*
Y1412786D03*
X1005338Y1415586D03*
Y1412786D03*
X1008138Y1418386D03*
X1005338D03*
X998949Y1427997D03*
Y1430997D03*
X995949D03*
Y1427997D03*
X1009981Y1431097D03*
Y1428097D03*
X1006981D03*
Y1431097D03*
X998949Y1433997D03*
X995949D03*
X998949Y1436997D03*
X995949D03*
X998949Y1439997D03*
X995949D03*
X1009981Y1434097D03*
X1006981D03*
X1009981Y1437097D03*
X1006981D03*
X1009981Y1440097D03*
X1006981D03*
X1002194Y1444392D03*
X1015059Y55513D03*
X1020519Y60438D03*
X1017659Y60513D03*
X1026200Y86012D03*
X1017787Y85731D03*
X1026200Y94374D03*
X1015427Y88801D03*
X1022293Y94279D03*
X1018344Y94351D03*
X1021341Y86046D03*
X1021537Y116594D03*
X1027480Y110784D03*
X1021537Y119594D03*
X1021971Y124283D03*
X1027037Y124879D03*
X1020378Y161306D03*
X1012134Y152562D03*
X1017629Y157370D03*
X1021713Y176665D03*
Y168665D03*
X1013812Y186629D03*
X1021713Y196665D03*
X1021826Y186778D03*
X1021713Y192665D03*
X1021745Y204864D03*
Y208864D03*
X1026794Y218085D03*
X1017386Y219379D03*
X1018014Y228631D03*
X1023502Y248371D03*
X1014420Y265897D03*
X1011920D03*
X1027216Y289440D03*
X1022604Y290262D03*
X1016635Y300276D03*
X1012635D03*
X1025749D03*
X1020635D03*
X1022435Y312865D03*
X1021848Y310396D03*
X1020406Y350772D03*
X1012188Y443421D03*
X1015659Y679654D03*
Y683054D03*
X1021885Y698974D03*
X1022937Y691421D03*
X1014641Y724436D03*
X1012851Y722417D03*
X1026916Y719769D03*
X1018015Y751565D03*
X1013486Y750773D03*
X1024684Y756485D03*
X1017664Y779101D03*
X1014064Y793660D03*
X1018071Y798490D03*
X1013821Y813520D03*
X1014781Y810319D03*
X1017955Y812097D03*
X1021895Y818974D03*
X1020703Y837659D03*
X1013918Y851306D03*
X1017800Y867065D03*
X1016973Y877196D03*
X1016574Y874537D03*
X1016798Y890299D03*
X1021408Y895008D03*
X1024913Y884000D03*
X1012842Y910685D03*
X1022346Y917669D03*
X1029570Y917718D03*
X1018419Y917575D03*
X1014719Y938322D03*
X1027319D03*
X1027719Y958822D03*
X1014009Y980356D03*
X1018009D03*
X1014009Y988813D03*
X1018009D03*
X1021924Y980456D03*
X1026009Y988813D03*
X1022009D03*
X1017998Y1009655D03*
X1015198D03*
X1024570Y1024003D03*
X1011782Y1016591D03*
X1022143Y1030672D03*
X1019143D03*
X1016143D03*
X1025143D03*
X1023144Y1109564D03*
X1017297D03*
X1023144Y1122164D03*
X1017297D03*
X1023144Y1134764D03*
X1017297D03*
X1023144Y1147364D03*
X1017297D03*
X1023144Y1159964D03*
X1017297D03*
Y1172564D03*
X1023162Y1174445D03*
X1023139Y1184856D03*
X1017297Y1185164D03*
X1026221Y1214372D03*
X1021976Y1218169D03*
X1023358Y1363921D03*
X1013991Y1360842D03*
X1019391Y1377061D03*
X1012981Y1431097D03*
Y1428097D03*
X1015981D03*
Y1431097D03*
X1021981Y1428097D03*
Y1431097D03*
X1018981D03*
Y1428097D03*
X1012981Y1434097D03*
X1015981D03*
X1012981Y1437097D03*
Y1440097D03*
X1015981Y1437097D03*
Y1440097D03*
X1021981Y1434097D03*
X1018981D03*
X1021981Y1437097D03*
X1018981D03*
X1021981Y1440097D03*
X1018981D03*
X1025615Y1444492D03*
X1020023Y1489637D03*
X1016769Y1489832D03*
X1043123Y97667D03*
X1033506Y116594D03*
X1038779Y102495D03*
X1032480Y110784D03*
X1033506Y119594D03*
X1037040Y125107D03*
X1032059Y124663D03*
X1038513Y142862D03*
X1045654Y143762D03*
X1039554Y148717D03*
X1033403Y138838D03*
X1042102Y195176D03*
X1042183Y210509D03*
X1029594Y218085D03*
X1036107Y221970D03*
X1036173Y226320D03*
X1036107Y219470D03*
Y216970D03*
X1033394Y216385D03*
X1043875Y230556D03*
X1039134Y228646D03*
X1042860Y242078D03*
X1038091Y232971D03*
X1034741Y244571D03*
X1032121Y249108D03*
X1042084Y256394D03*
X1037290Y296293D03*
X1033890D03*
X1045650Y300093D03*
X1029639Y300141D03*
X1041783Y321114D03*
X1030220Y313554D03*
X1042948Y333696D03*
X1043106Y340230D03*
X1031259Y350427D03*
X1029885Y711762D03*
X1033200Y731700D03*
X1035619Y755809D03*
X1038344Y756476D03*
X1043016Y782161D03*
X1038678Y776750D03*
X1039251Y812340D03*
X1042414Y801443D03*
X1043425Y830800D03*
X1043626Y836563D03*
X1041100Y838500D03*
X1037527Y836486D03*
X1031813Y850273D03*
X1046045Y841217D03*
X1040822Y841339D03*
X1044390Y861210D03*
X1035185Y862793D03*
X1037685Y862789D03*
X1038363Y875288D03*
X1037709Y886209D03*
X1038010Y902565D03*
X1033019Y933022D03*
Y935822D03*
X1030819Y938422D03*
X1033370Y953994D03*
X1038009Y988813D03*
X1030009D03*
X1042009D03*
X1034009D03*
X1028943Y1016827D03*
X1034790D03*
X1028943Y1029427D03*
X1034790D03*
X1039499Y1098758D03*
X1039053Y1105091D03*
X1044553D03*
X1039098Y1102091D03*
X1039053Y1117691D03*
X1044553D03*
X1039098Y1114691D03*
Y1127291D03*
X1039053Y1130291D03*
X1044553D03*
Y1142891D03*
X1039098Y1139891D03*
X1039053Y1142891D03*
Y1155491D03*
X1044553D03*
X1039098Y1152491D03*
X1044553Y1168091D03*
X1039053D03*
X1039098Y1165091D03*
X1044553Y1180691D03*
X1039053D03*
X1039098Y1177691D03*
X1032831Y1207950D03*
X1029797Y1220921D03*
X1040606Y1230407D03*
X1043588Y1227300D03*
X1032867Y1431213D03*
Y1428213D03*
X1029867D03*
X1035867Y1431213D03*
Y1428213D03*
X1029867Y1431213D03*
X1038867Y1428213D03*
Y1431213D03*
X1041867D03*
Y1428213D03*
X1032867Y1434213D03*
X1029867D03*
X1035867D03*
X1038867D03*
X1032867Y1437213D03*
X1029867D03*
X1032867Y1440213D03*
X1029867D03*
X1035867Y1437213D03*
Y1440213D03*
X1038867Y1437213D03*
Y1440213D03*
X1041867Y1434213D03*
Y1437213D03*
Y1440213D03*
X1051583Y103411D03*
X1051977Y97667D03*
X1047373Y95111D03*
X1051742Y106561D03*
X1047102Y195176D03*
X1046120Y199248D03*
X1044602Y195176D03*
X1049120Y199248D03*
X1049602Y195176D03*
X1046120Y201748D03*
X1049120Y202048D03*
X1044683Y210509D03*
X1046456Y206806D03*
X1043956D03*
X1052720Y230117D03*
X1048130Y227824D03*
X1048736Y238714D03*
X1048217Y246874D03*
X1050437Y244297D03*
X1045364Y279895D03*
X1051796Y279965D03*
X1050164Y302748D03*
X1050076Y305512D03*
X1061387Y343509D03*
X1060679Y356151D03*
X1059549Y458711D03*
X1055885Y554555D03*
X1046068Y792742D03*
X1046930Y796557D03*
X1048314Y833102D03*
X1053392Y832788D03*
X1051550Y823146D03*
X1055700Y840900D03*
X1053913Y837718D03*
X1050358Y837793D03*
X1052500Y841200D03*
X1049087Y856033D03*
X1053909Y855472D03*
X1045300Y872352D03*
X1054900Y879321D03*
X1058155Y887635D03*
X1050295Y891100D03*
X1054009Y988813D03*
X1046009D03*
X1050009D03*
X1058009D03*
X1056199Y1012354D03*
X1050744Y1009354D03*
X1056199Y1024954D03*
X1050699D03*
Y1012354D03*
X1050744Y1021954D03*
X1046485Y1034538D03*
X1057212Y1040356D03*
X1049930Y1221407D03*
X1050605Y1224472D03*
X1049770Y1229402D03*
X1049720Y1234921D03*
X1052660Y1293257D03*
X1050002Y1293283D03*
X1049204Y1337377D03*
X1049670Y1347462D03*
X1046075Y1350650D03*
X1049493Y1350694D03*
X1044867Y1428213D03*
Y1431213D03*
Y1434213D03*
Y1437213D03*
Y1440213D03*
X1048403Y1444608D03*
X1062773Y90650D03*
X1068085Y90615D03*
X1072456Y95236D03*
X1072406Y99961D03*
X1062523Y95236D03*
X1071268Y207978D03*
Y212978D03*
Y215478D03*
Y210478D03*
X1074597Y264180D03*
X1074522Y258880D03*
X1076571Y310574D03*
X1060679Y368276D03*
X1062234Y378600D03*
Y382600D03*
X1062349Y458711D03*
X1064876Y453682D03*
X1063113Y455921D03*
X1061693Y463600D03*
X1062098Y603600D03*
X1061342Y610269D03*
X1061496Y612786D03*
X1062098Y619600D03*
X1063642Y634190D03*
X1062098Y623600D03*
X1066931Y645389D03*
X1060698Y931619D03*
X1069685Y933391D03*
X1066878Y931909D03*
X1070009Y988813D03*
X1069607Y980131D03*
X1066009Y980330D03*
X1062009Y988813D03*
X1065823Y988773D03*
X1074009Y988813D03*
X1070009Y997860D03*
X1073525Y1012428D03*
X1076110Y1029535D03*
X1065079Y1036920D03*
X1076577Y1041332D03*
X1074232Y1055836D03*
X1067866Y1051037D03*
X1060768Y1053457D03*
X1074650Y1070006D03*
X1069642Y1445541D03*
X1068861Y1451311D03*
X1081187Y-79306D03*
Y-82706D03*
X1081320Y85193D03*
Y82593D03*
Y79993D03*
Y77393D03*
Y74793D03*
X1089645Y98551D03*
X1081364Y92874D03*
X1083391Y104249D03*
Y107649D03*
X1087957Y147540D03*
X1091729Y141247D03*
X1083013Y162368D03*
X1090113Y165393D03*
Y162793D03*
X1080413Y162368D03*
X1090113Y170493D03*
Y167993D03*
X1092321Y181366D03*
X1089110Y181426D03*
X1091935Y184012D03*
X1089318Y184221D03*
X1081724Y208213D03*
X1085796Y208695D03*
Y211695D03*
X1081724Y210713D03*
Y213213D03*
X1088596Y208695D03*
X1088296Y211695D03*
X1081724Y215713D03*
X1077097Y264180D03*
X1091973Y265701D03*
X1083491Y267526D03*
X1088791D03*
X1086291D03*
X1083491Y270026D03*
X1086291D03*
X1088791D03*
X1093608Y281716D03*
X1080351Y328256D03*
X1079748Y322743D03*
Y319343D03*
X1080351Y331656D03*
X1082297Y340770D03*
X1092554Y340318D03*
X1085615Y339815D03*
X1092561Y353374D03*
X1082787Y348501D03*
X1091031Y374810D03*
X1089788Y550907D03*
X1087288D03*
X1089788Y553407D03*
X1087288D03*
X1089096Y541863D03*
Y545263D03*
X1091558Y566929D03*
X1091272Y569426D03*
X1088949Y568475D03*
X1089206Y570962D03*
X1086859Y569928D03*
X1085512Y572070D03*
X1078920Y856700D03*
X1090375Y899047D03*
X1076800Y1012900D03*
X1078755Y1031518D03*
X1079178Y1037884D03*
X1076868Y1047293D03*
X1079910Y1045264D03*
X1079822Y1151870D03*
X1083562Y1155610D03*
X1079822Y1159350D03*
X1083283Y1526583D03*
X1084000Y1529600D03*
X1091529Y1528718D03*
X1091525Y1546300D03*
X1090876Y1554183D03*
X1091569Y1561300D03*
X1092527Y1579422D03*
X1086469Y1588435D03*
X1090469D03*
X1083900Y1593206D03*
X1082176Y1600598D03*
X1090904Y1599047D03*
X1088021Y1606949D03*
X1093778Y1599574D03*
X1086904Y1599004D03*
X1090093Y1628297D03*
X1085474Y1629028D03*
X1089474Y1638213D03*
X1105741Y76587D03*
Y72615D03*
X1100199Y97475D03*
X1107180Y100625D03*
X1100130Y106186D03*
X1093195Y103783D03*
X1107759Y141247D03*
X1099196Y143740D03*
X1096576Y148277D03*
X1095116Y181009D03*
X1100291Y168697D03*
X1097618Y172190D03*
X1109903Y171523D03*
X1097037Y177616D03*
X1101379Y191941D03*
X1109433Y192490D03*
X1105888Y206767D03*
X1108388D03*
X1103388D03*
X1093354Y213859D03*
Y211359D03*
X1097057Y213132D03*
X1104633Y228221D03*
X1106018Y221708D03*
X1108518D03*
X1102933Y224421D03*
X1103518Y221708D03*
X1104633Y231021D03*
X1097057Y215632D03*
X1105184Y236189D03*
X1107684D03*
X1105125Y248765D03*
X1107625D03*
X1097301Y256303D03*
X1102076Y266114D03*
X1097060Y265896D03*
X1107822Y268195D03*
X1105322D03*
Y270695D03*
X1107822D03*
X1099549Y281982D03*
X1093478Y310305D03*
X1108779Y327705D03*
X1103432Y340544D03*
X1097976Y340477D03*
X1105012Y353504D03*
X1098845Y353404D03*
X1093841Y371335D03*
X1099501Y545528D03*
X1108236Y577716D03*
X1105298Y610400D03*
X1108045Y668153D03*
X1092769Y936975D03*
X1095080Y1513398D03*
X1096780Y1526700D03*
X1101402Y1531702D03*
X1095250Y1531600D03*
X1098617Y1546183D03*
X1096780Y1535400D03*
X1100876Y1554183D03*
X1099371Y1561153D03*
X1100476Y1579318D03*
X1102904Y1566668D03*
X1093682Y1582433D03*
X1098498Y1590435D03*
X1104233Y1587983D03*
X1100233Y1588000D03*
X1107620Y1603602D03*
X1098904Y1602138D03*
X1101946Y1614709D03*
X1096941Y1627905D03*
X1105474Y1629450D03*
X1101474Y1637820D03*
X1093474Y1638213D03*
X1105474Y1638426D03*
X1097474Y1637753D03*
X1114781Y58013D03*
X1113646Y68581D03*
X1120021Y60513D03*
X1122881Y60438D03*
X1113659Y80581D03*
X1120149Y85731D03*
X1117789Y88801D03*
X1123703Y86046D03*
X1120706Y94351D03*
X1124655Y94279D03*
X1115842Y103621D03*
X1123899Y116594D03*
X1111553Y112083D03*
X1123899Y119594D03*
X1124333Y124283D03*
X1112246Y143518D03*
X1111346Y152373D03*
X1122740Y161306D03*
X1114496Y152562D03*
X1119991Y157370D03*
X1124075Y168665D03*
Y176665D03*
X1115188Y183834D03*
X1115298Y178560D03*
X1115361Y172665D03*
X1116174Y186629D03*
X1124075Y192665D03*
Y196665D03*
X1115478Y200864D03*
X1114708Y190185D03*
X1124188Y186778D03*
X1124107Y204864D03*
X1115501Y207037D03*
X1115567Y212455D03*
X1124107Y208864D03*
X1112868Y221642D03*
X1119748Y219379D03*
X1120376Y228631D03*
X1110184Y236189D03*
X1110125Y248765D03*
X1116782Y265897D03*
X1114282D03*
X1110622Y268195D03*
Y270695D03*
X1115000Y329000D03*
Y334000D03*
Y339000D03*
X1118848Y382109D03*
X1118847Y551683D03*
Y561420D03*
Y558917D03*
X1122705Y588515D03*
X1114668Y577937D03*
X1117673Y606929D03*
X1122673Y595500D03*
X1122173Y604567D03*
X1122705Y591015D03*
X1123331Y610072D03*
X1123267Y616317D03*
X1117633Y618400D03*
X1117914Y612592D03*
X1115151Y650119D03*
X1115320Y646449D03*
X1115054Y662981D03*
X1116296Y691851D03*
X1111785Y686971D03*
X1118105Y707592D03*
X1128562Y86012D03*
Y94374D03*
X1135868Y116594D03*
X1141141Y102495D03*
X1129842Y110784D03*
X1134842D03*
X1135868Y119594D03*
X1139402Y125107D03*
X1129399Y124879D03*
X1134421Y124663D03*
X1140875Y142862D03*
X1141916Y148717D03*
X1135765Y138838D03*
X1129156Y218085D03*
X1131956D03*
X1138469Y221970D03*
X1138535Y226320D03*
X1138469Y219470D03*
Y216970D03*
X1135756Y216385D03*
X1141496Y228646D03*
X1140453Y232971D03*
X1137103Y244571D03*
X1134483Y249108D03*
X1125864Y248371D03*
X1137830Y336230D03*
X1135548Y455804D03*
X1134629Y465551D03*
X1126622Y506256D03*
X1139673Y530000D03*
X1139173Y540500D03*
X1138373Y549800D03*
X1138173Y547075D03*
X1137673Y568000D03*
X1138213Y558800D03*
X1138277Y562800D03*
X1129471Y732571D03*
X1153945Y103411D03*
X1145485Y97667D03*
X1154339D03*
X1149735Y95111D03*
X1154104Y106561D03*
X1148016Y143762D03*
X1149464Y195176D03*
X1148482Y199248D03*
X1151482D03*
X1144464Y195176D03*
X1146964D03*
X1151964D03*
X1151482Y202048D03*
X1146318Y206806D03*
X1144545Y210509D03*
X1147045D03*
X1148818Y206806D03*
X1148482Y201748D03*
X1146237Y230556D03*
X1155082Y230117D03*
X1150492Y227824D03*
X1151098Y238714D03*
X1145222Y242078D03*
X1150579Y246874D03*
X1152799Y244297D03*
X1147590Y253198D03*
X1145587Y339148D03*
X1142440Y396718D03*
X1157451Y618288D03*
X1156275Y656321D03*
X1155146Y699491D03*
X1152512Y728543D03*
X1148962Y747253D03*
X1152485Y764552D03*
X1147468Y766093D03*
X1154652Y791056D03*
X1145910Y803642D03*
X1153485Y813142D03*
X1154985Y802897D03*
X1153229Y848581D03*
X1170447Y90615D03*
X1165135Y90650D03*
X1174768Y99961D03*
X1164885Y95236D03*
X1173630Y207978D03*
Y210478D03*
Y212978D03*
Y215478D03*
X1173559Y304948D03*
X1171445Y422088D03*
X1166868Y442956D03*
X1168685Y438323D03*
X1168398Y456309D03*
X1168851Y445873D03*
X1163298Y465874D03*
X1159535Y546712D03*
Y542712D03*
X1165400Y553300D03*
X1167900D03*
X1161451Y618288D03*
X1160275Y656321D03*
X1164275D03*
X1162863Y678519D03*
X1159173Y678462D03*
X1170465Y677836D03*
X1157646Y699491D03*
X1162646D03*
X1160146D03*
X1169256Y694983D03*
X1163774Y713347D03*
X1166115Y718469D03*
X1171934Y733857D03*
X1173034Y765060D03*
X1169697Y791935D03*
X1164925Y791607D03*
X1164732Y802269D03*
X1173122Y802759D03*
X1163579Y850774D03*
X1161535Y844167D03*
X1159887Y869106D03*
X1174461Y914515D03*
X1183682Y85193D03*
Y82593D03*
Y74793D03*
Y79993D03*
Y77393D03*
X1183726Y92874D03*
X1174818Y95236D03*
X1185753Y107649D03*
Y104249D03*
X1182775Y162368D03*
X1185375D03*
X1188158Y211695D03*
X1184086Y210713D03*
Y213213D03*
Y208213D03*
X1190958Y208695D03*
X1188158D03*
X1184086Y215713D03*
X1176959Y264180D03*
X1179459D03*
X1177035Y257919D03*
X1185853Y267526D03*
X1188653D03*
X1185853Y270026D03*
X1188653D03*
X1179901Y306366D03*
X1181706Y310131D03*
X1178045Y312193D03*
X1181379Y316049D03*
X1174929Y319167D03*
X1179761Y336380D03*
X1187996Y331992D03*
X1191748Y392676D03*
X1188598Y381500D03*
X1178083Y442856D03*
X1189122Y442606D03*
X1176699Y451108D03*
X1176138Y458455D03*
X1179184Y453881D03*
Y446595D03*
X1188739Y446606D03*
X1190046Y463479D03*
X1174595Y771744D03*
X1176500Y784933D03*
X1185516Y844248D03*
X1190968Y848703D03*
X1184340Y851072D03*
X1183012Y856553D03*
X1190213Y856816D03*
X1187431Y868340D03*
X1180239Y868430D03*
X1179858Y883455D03*
X1179727Y886197D03*
X1181654Y894671D03*
X1185058Y883475D03*
X1187151Y921000D03*
X1182000Y936500D03*
X1189219Y940703D03*
X1192007Y98551D03*
X1202561Y97475D03*
X1195557Y103783D03*
X1202492Y106186D03*
X1190319Y147540D03*
X1194091Y141247D03*
X1201558Y143740D03*
X1198938Y148277D03*
X1192475Y165393D03*
Y162793D03*
Y167993D03*
Y170493D03*
X1199980Y172190D03*
X1194683Y181366D03*
X1191472Y181426D03*
X1197478Y181009D03*
X1202653Y168697D03*
X1199399Y177616D03*
X1203741Y191941D03*
X1194297Y184012D03*
X1191680Y184221D03*
X1205750Y206767D03*
X1195716Y211359D03*
Y213859D03*
X1199419Y213132D03*
X1190658Y211695D03*
X1205295Y224421D03*
X1205880Y221708D03*
X1199419Y215632D03*
X1199663Y256303D03*
X1199422Y265896D03*
X1204438Y266114D03*
X1194335Y265701D03*
X1191153Y267526D03*
Y270026D03*
X1201911Y281982D03*
X1195970Y281716D03*
X1201113Y315039D03*
X1190127Y324142D03*
X1195800Y324000D03*
X1206531Y393858D03*
X1208173Y398583D03*
X1192702Y440489D03*
X1192957Y435158D03*
X1193000Y444841D03*
X1192686Y449961D03*
X1196403Y458572D03*
X1192431Y868620D03*
X1192152Y884399D03*
X1192367Y903785D03*
X1190210Y900909D03*
X1191151Y936296D03*
X1193219Y940703D03*
X1197173Y940645D03*
X1196352Y951033D03*
X1191219Y967757D03*
X1191928Y987314D03*
X1198644Y985289D03*
X1195757Y988131D03*
X1203419Y1011161D03*
X1200008D03*
X1196300Y998600D03*
X1202028Y998349D03*
X1199700Y1013661D03*
X1201800Y1019431D03*
X1219783Y55513D03*
X1216008Y68581D03*
X1222383Y60513D03*
X1216021Y80581D03*
X1208103Y72615D03*
Y76587D03*
X1222511Y85731D03*
X1220151Y88801D03*
X1218204Y103621D03*
X1209542Y100625D03*
X1213915Y112083D03*
X1210121Y141247D03*
X1214608Y143518D03*
X1213708Y152373D03*
X1216858Y152562D03*
X1222353Y157370D03*
X1217550Y183834D03*
X1212265Y171523D03*
X1217723Y172665D03*
X1217660Y178560D03*
X1218536Y186629D03*
X1211795Y192490D03*
X1210268Y198671D03*
X1217840Y200864D03*
X1217070Y190185D03*
X1207753Y192300D03*
X1208250Y206767D03*
X1210750D03*
X1217863Y207037D03*
X1217929Y212455D03*
X1215230Y221642D03*
X1206995Y228221D03*
X1208380Y221708D03*
X1210880D03*
X1206995Y231021D03*
X1222110Y219379D03*
X1222738Y228631D03*
X1207546Y236189D03*
X1210046D03*
X1212546D03*
X1207487Y248765D03*
X1209987D03*
X1212487D03*
X1219144Y265897D03*
X1216644D03*
X1212984Y268195D03*
X1210184D03*
X1207684D03*
X1212984Y270695D03*
X1207684D03*
X1210184D03*
X1220723Y324466D03*
X1211892Y339559D03*
X1215776Y331072D03*
X1213173Y377912D03*
X1217177Y369925D03*
X1206693Y384410D03*
X1213173Y386500D03*
X1209872Y382047D03*
X1212173Y391496D03*
X1213261Y397912D03*
X1210173Y403500D03*
X1212173Y409000D03*
X1209426Y433069D03*
Y430469D03*
Y435669D03*
Y440869D03*
Y438269D03*
X1206626Y433069D03*
Y430469D03*
Y435669D03*
Y440869D03*
Y438269D03*
X1209980Y451677D03*
X1207480Y454177D03*
X1209980D03*
X1207480Y451677D03*
X1209184Y463618D03*
Y460218D03*
X1225405Y-79278D03*
Y-82678D03*
X1230761Y-43628D03*
Y-40228D03*
X1225243Y60438D03*
X1230924Y86012D03*
Y94374D03*
X1226065Y86046D03*
X1227017Y94279D03*
X1223068Y94351D03*
X1238230Y116594D03*
X1226261D03*
X1232204Y110784D03*
X1237204D03*
X1238230Y119594D03*
X1226261D03*
X1236783Y124663D03*
X1226695Y124283D03*
X1231761Y124879D03*
X1238127Y138838D03*
X1225102Y161306D03*
X1226437Y176665D03*
Y168665D03*
Y192665D03*
X1226550Y186778D03*
X1226469Y204864D03*
Y208864D03*
X1231518Y218085D03*
X1234318D03*
X1238118Y216385D03*
X1239465Y244571D03*
X1236845Y249108D03*
X1228226Y248371D03*
X1229252Y314890D03*
X1229028Y311740D03*
X1226436Y324518D03*
X1229922Y324550D03*
X1234904Y316942D03*
X1232197Y316964D03*
X1238293Y317296D03*
X1229438Y332584D03*
X1235589Y348015D03*
X1229942Y347937D03*
X1231506Y353470D03*
X1223431Y377912D03*
X1225755Y369391D03*
X1229122Y369355D03*
X1222601Y369251D03*
X1223431Y381912D03*
Y397912D03*
X1232833Y539315D03*
X1232149Y550137D03*
X1234941D03*
X1235930Y626229D03*
X1235292Y622912D03*
X1237500Y632405D03*
X1238034Y629961D03*
X1238695Y627313D03*
X1256307Y103411D03*
X1247847Y97667D03*
X1256701D03*
X1252097Y95111D03*
X1243503Y102495D03*
X1241764Y125107D03*
X1243237Y142862D03*
X1250378Y143762D03*
X1244278Y148717D03*
X1251826Y195176D03*
X1254326D03*
X1253844Y199248D03*
X1249326Y195176D03*
X1250844Y199248D03*
X1246826Y195176D03*
X1249407Y210509D03*
X1253844Y202048D03*
X1250844Y201748D03*
X1251180Y206806D03*
X1248680D03*
X1246907Y210509D03*
X1240831Y221970D03*
X1240897Y226320D03*
X1240831Y219470D03*
Y216970D03*
X1248599Y230556D03*
X1252854Y227824D03*
X1243858Y228646D03*
X1253460Y238714D03*
X1247584Y242078D03*
X1252941Y246874D03*
X1242815Y232971D03*
X1246808Y256394D03*
X1241205Y303962D03*
X1253245Y416888D03*
Y419488D03*
Y422088D03*
X1253087Y553101D03*
X1241629Y550065D03*
X1248106Y1004700D03*
X1245400Y1003700D03*
X1246000Y1014800D03*
X1252148Y1026223D03*
X1252500Y1014288D03*
X1246300Y1027800D03*
X1253424Y1138130D03*
X1250928Y1142828D03*
X1254200Y1146600D03*
X1249363Y1173065D03*
X1256218Y1175987D03*
X1249363Y1166065D03*
X1255439Y1172008D03*
X1255628Y1188345D03*
X1253056Y1194917D03*
X1254275Y1531334D03*
X1249894Y1527805D03*
X1253904Y1519645D03*
X1254275Y1539334D03*
X1250434Y1535334D03*
X1267497Y90650D03*
X1267247Y95236D03*
X1256466Y106561D03*
X1257444Y230117D03*
X1255161Y244297D03*
X1266962Y302167D03*
X1262665Y302730D03*
X1263328Y309003D03*
X1262075Y324075D03*
X1261659Y318258D03*
X1264088Y320382D03*
X1266616Y322456D03*
X1257000Y333500D03*
X1264215Y333215D03*
X1262500Y330655D03*
X1256000Y338000D03*
X1259991Y340691D03*
X1256000Y340500D03*
X1263500Y336000D03*
X1264659Y377173D03*
X1267944Y371767D03*
X1261764Y391533D03*
X1263484Y385644D03*
X1268659Y385123D03*
X1268067Y406060D03*
X1261231Y399918D03*
X1264336Y412106D03*
X1268328Y421489D03*
Y418889D03*
Y416289D03*
X1270397Y447081D03*
X1259223Y454334D03*
X1267540Y459330D03*
X1267493Y454214D03*
X1267836Y449045D03*
X1267843Y473571D03*
Y481071D03*
Y478571D03*
Y476071D03*
X1269629Y848124D03*
X1270892Y856343D03*
X1271121Y892513D03*
X1270276Y897062D03*
X1269221Y894760D03*
X1270586Y905324D03*
X1272661Y929858D03*
X1260539Y1134729D03*
X1267921D03*
X1266718Y1142666D03*
X1263921Y1134729D03*
X1268593Y1157544D03*
X1267104Y1167768D03*
X1272123D03*
X1271246Y1178240D03*
X1271256Y1185205D03*
X1262605Y1187215D03*
X1262298Y1180175D03*
X1260800Y1191096D03*
X1268571Y1201043D03*
X1264575D03*
X1261538Y1199814D03*
X1255296Y1196056D03*
X1263449Y1217228D03*
X1266113Y1219895D03*
X1269388Y1223170D03*
X1267333Y1531334D03*
X1262891Y1527334D03*
X1267183Y1539334D03*
X1262891Y1535334D03*
X1286044Y85539D03*
Y82939D03*
Y75139D03*
Y80339D03*
Y77739D03*
X1286088Y92874D03*
X1272809Y90615D03*
X1277130Y99961D03*
X1277180Y95236D03*
X1285137Y162368D03*
X1275992Y215478D03*
Y212978D03*
Y210478D03*
Y207978D03*
X1286448Y213213D03*
Y210713D03*
Y208213D03*
Y215713D03*
X1281821Y264180D03*
X1279321D03*
X1279246Y258880D03*
X1271571Y281185D03*
X1289345Y330655D03*
X1284419Y359377D03*
X1287437Y379429D03*
X1280699Y377173D03*
X1284659D03*
X1274436Y377350D03*
X1276659Y385123D03*
X1273659D03*
X1280659D03*
X1284333Y391569D03*
X1282760Y401066D03*
X1272421Y403300D03*
X1271828Y405889D03*
Y408489D03*
Y413689D03*
Y411089D03*
Y416289D03*
Y421489D03*
Y418889D03*
Y424089D03*
X1272215Y432718D03*
Y435518D03*
X1282092Y442118D03*
Y439318D03*
X1271828Y426689D03*
X1272927Y450091D03*
X1275927D03*
X1273397Y447081D03*
X1281737Y461034D03*
Y456034D03*
X1272927Y462060D03*
X1275927D03*
X1286005Y485580D03*
X1280631Y480194D03*
Y477694D03*
X1277897Y478876D03*
Y476376D03*
X1274415Y477053D03*
X1271915D03*
X1284900Y678800D03*
X1283400Y715500D03*
X1278255Y722241D03*
X1283400Y719700D03*
X1282539Y746076D03*
X1279539Y748576D03*
X1282539Y751076D03*
X1279539Y763576D03*
X1282539Y766076D03*
X1279539Y758576D03*
X1282539Y756076D03*
Y761076D03*
X1279539Y753576D03*
Y768576D03*
Y780576D03*
Y784576D03*
X1285092Y819500D03*
X1285500Y827500D03*
X1281388Y827388D03*
X1281777Y823500D03*
X1285500Y843500D03*
X1281331Y843331D03*
X1281269Y835492D03*
X1285500Y835500D03*
X1283025Y848305D03*
X1271438Y861846D03*
X1285500Y863500D03*
Y859500D03*
Y855500D03*
Y851500D03*
X1279460Y854487D03*
Y859487D03*
Y864487D03*
X1274396Y866896D03*
X1285500Y867500D03*
X1279460Y874487D03*
Y869487D03*
Y879487D03*
X1285302Y877283D03*
X1282285Y865602D03*
X1274264Y898591D03*
X1279460Y884487D03*
X1285302Y885783D03*
X1279299Y898813D03*
X1279460Y889487D03*
X1285302Y881783D03*
X1281075Y911075D03*
X1282184Y898854D03*
X1274400Y914123D03*
X1283494Y907176D03*
X1275493Y929858D03*
X1279493D03*
X1283493D03*
X1279693Y919800D03*
X1274670Y919808D03*
X1281400Y940256D03*
X1289547Y941000D03*
X1281733Y949475D03*
X1275788Y1124088D03*
X1282421Y1137129D03*
X1271921Y1134729D03*
X1275794D03*
X1282830Y1150087D03*
X1275050Y1157404D03*
X1280306Y1170767D03*
X1275965Y1187232D03*
X1280602Y1185238D03*
X1280395Y1180235D03*
X1272541Y1201043D03*
X1276575Y1201039D03*
X1280575Y1200969D03*
X1280694Y1208993D03*
X1274446Y1228226D03*
X1272235Y1226016D03*
X1297687Y-40256D03*
Y-43656D03*
X1297785Y33768D03*
X1302139Y26325D03*
X1302785Y31168D03*
X1294369Y98551D03*
X1304923Y97475D03*
X1297919Y103783D03*
X1288115Y104249D03*
Y107649D03*
X1294837Y162793D03*
X1287737Y162368D03*
X1294837Y165393D03*
Y167993D03*
Y170493D03*
X1301761Y177616D03*
X1302342Y172190D03*
X1299840Y181009D03*
X1293834Y181426D03*
X1297045Y181366D03*
X1294042Y184221D03*
X1296659Y184012D03*
X1301781Y213132D03*
X1298078Y211359D03*
Y213859D03*
X1290520Y211695D03*
X1293020D03*
X1290520Y208695D03*
X1293320D03*
X1301781Y215632D03*
X1302025Y256303D03*
X1296697Y265701D03*
X1301784Y265896D03*
X1293515Y270026D03*
X1291015D03*
X1288215D03*
Y267526D03*
X1293515D03*
X1291015D03*
X1304273Y281982D03*
X1298332Y281716D03*
X1294000Y324000D03*
X1303000Y326692D03*
X1293000Y338500D03*
X1303000Y331000D03*
X1302896Y343797D03*
Y340397D03*
X1292500Y335000D03*
X1299959Y356954D03*
X1294080Y349820D03*
X1291410Y371060D03*
X1295410Y371076D03*
X1293048Y379088D03*
X1298346Y379028D03*
X1293100Y409539D03*
X1296100D03*
X1293100Y406739D03*
X1296100Y407039D03*
X1295764Y401981D03*
X1298264D03*
X1300037Y398278D03*
X1297537D03*
X1292618Y413611D03*
X1295118D03*
X1300118D03*
X1297618D03*
X1292383Y424067D03*
X1294883D03*
X1299883D03*
X1297383D03*
X1299757Y438293D03*
Y441093D03*
X1290092Y442118D03*
Y439318D03*
X1299757Y443893D03*
X1287719Y470001D03*
X1290219D03*
X1299867Y477318D03*
X1299466Y466409D03*
X1299807Y472020D03*
X1288144Y489036D03*
X1291005Y485580D03*
X1288505D03*
X1301314Y484882D03*
X1299304Y487382D03*
X1290380Y495636D03*
Y492836D03*
X1300817Y568635D03*
X1301194Y565518D03*
X1305836Y660009D03*
X1298963Y659609D03*
X1289811Y677612D03*
X1289317Y706932D03*
X1291604Y781576D03*
Y776576D03*
Y771435D03*
X1295491Y798821D03*
X1298720Y798975D03*
X1289730Y806845D03*
X1302140Y812625D03*
X1302501Y824747D03*
X1297667Y832150D03*
X1293500Y827500D03*
X1296770Y828775D03*
X1293500Y843500D03*
Y835500D03*
X1296687Y839500D03*
X1293500Y851500D03*
X1294000Y863500D03*
X1293500Y879800D03*
Y871800D03*
Y875800D03*
X1288164Y892354D03*
X1296866Y894993D03*
X1305250Y889250D03*
X1293272Y887800D03*
X1293500Y883800D03*
X1291129Y892267D03*
X1294264Y905595D03*
X1301657Y899129D03*
X1288500Y901254D03*
X1298966Y899610D03*
X1296466D03*
X1298000Y917000D03*
X1294075D03*
X1304949Y928546D03*
X1292500Y928000D03*
X1295453Y928047D03*
X1291059Y917000D03*
X1302000D03*
X1302500Y939500D03*
X1300882Y937144D03*
X1296500Y961500D03*
X1289500Y949500D03*
X1300500Y960000D03*
X1290792Y961363D03*
X1300500Y970187D03*
X1297558Y970216D03*
X1292836Y975244D03*
X1292631Y979845D03*
X1299717Y1024136D03*
X1297852Y1014475D03*
X1295815Y1124943D03*
X1295893Y1122182D03*
X1310853Y37543D03*
X1314887Y45448D03*
X1318859D03*
X1311904Y100625D03*
X1320566Y103621D03*
X1304854Y106186D03*
X1316277Y112083D03*
X1305015Y168697D03*
X1319912Y183834D03*
X1314627Y171523D03*
X1320085Y172665D03*
X1320022Y178560D03*
X1306103Y191941D03*
X1319432Y190185D03*
X1314157Y192490D03*
X1320202Y200864D03*
X1310115Y192300D03*
X1308112Y206767D03*
X1313112D03*
X1310612D03*
X1320225Y207037D03*
X1320291Y212455D03*
X1313242Y221708D03*
X1310742D03*
X1309357Y231021D03*
Y228221D03*
X1317592Y221642D03*
X1308242Y221708D03*
X1307657Y224421D03*
X1309908Y236189D03*
X1314908D03*
X1312408D03*
X1312349Y248765D03*
X1309849D03*
X1314849D03*
X1306800Y266114D03*
X1310046Y268195D03*
X1312546D03*
X1315346D03*
X1319006Y265897D03*
X1312546Y270695D03*
X1310046D03*
X1315346D03*
X1318362Y310562D03*
X1305928Y318250D03*
X1308428D03*
X1315256Y336510D03*
X1313103Y339606D03*
X1312240Y334681D03*
X1315397Y333709D03*
X1308012Y348109D03*
X1305910Y377581D03*
X1310172Y367956D03*
X1308410Y379591D03*
X1311283Y370801D03*
X1308826Y389402D03*
X1306113Y383817D03*
X1312626Y387702D03*
X1315426D03*
X1306113Y386317D03*
Y388817D03*
X1309750Y438293D03*
Y441093D03*
Y443893D03*
X1311488Y471560D03*
X1307819Y474382D03*
X1307835Y470382D03*
X1319474Y467560D03*
X1319974Y475560D03*
X1311488D03*
X1318160Y520053D03*
X1317945Y523058D03*
X1319000Y562500D03*
Y558500D03*
Y586500D03*
Y574500D03*
Y578500D03*
Y605000D03*
Y590500D03*
X1319323Y598454D03*
X1319000Y621000D03*
Y609000D03*
Y633000D03*
Y625000D03*
Y637000D03*
Y653500D03*
Y649500D03*
Y641000D03*
Y669500D03*
Y665500D03*
Y681500D03*
Y677500D03*
X1313979Y677726D03*
X1319000Y685500D03*
Y696500D03*
Y700500D03*
Y712500D03*
Y716500D03*
Y724500D03*
Y728500D03*
Y732500D03*
X1321000Y796000D03*
X1313000D03*
X1317000Y799000D03*
Y788000D03*
X1313000D03*
X1315000Y811620D03*
X1319000D03*
X1317000Y804000D03*
X1313000D03*
X1321000D03*
X1310715Y820491D03*
Y822991D03*
Y817991D03*
X1310687Y830206D03*
Y832706D03*
Y827706D03*
X1310971Y842319D03*
X1305786Y867704D03*
X1310994Y866859D03*
X1309753Y877589D03*
X1305740Y877534D03*
X1310535Y870775D03*
X1308220Y889253D03*
X1311061Y889361D03*
X1314500Y911500D03*
X1319500Y901500D03*
X1314500Y905000D03*
X1305356Y902597D03*
X1319500Y905000D03*
X1309103Y917000D03*
X1313867Y925605D03*
X1311325Y928918D03*
X1319554Y925585D03*
X1309103Y936559D03*
X1306500Y936500D03*
X1315779Y943743D03*
X1313152Y936605D03*
X1312575Y943974D03*
X1321256Y943815D03*
X1311000Y961500D03*
X1307000Y960500D03*
X1315441Y960000D03*
X1307000Y970000D03*
X1311000Y970124D03*
X1307707Y979870D03*
X1317254Y990777D03*
X1317053Y988111D03*
X1319874Y989856D03*
X1307561Y986951D03*
X1315606Y1042825D03*
X1315756Y1039344D03*
X1312873Y1036543D03*
X1306385Y1036646D03*
X1319221Y1058097D03*
Y1060697D03*
X1316869Y1107997D03*
X1319069Y1112397D03*
X1318969Y1109397D03*
X1316869Y1113797D03*
Y1110897D03*
X1317437Y1160834D03*
X1318178Y1192621D03*
Y1190121D03*
X1319237Y1221428D03*
X1311237D03*
X1315237D03*
X1311237Y1233428D03*
Y1229428D03*
Y1225428D03*
X1315237Y1237428D03*
Y1233428D03*
Y1229428D03*
Y1225428D03*
X1319237Y1237428D03*
Y1233428D03*
Y1229428D03*
Y1225428D03*
X1315237Y1241428D03*
X1319237D03*
X1308107Y1283395D03*
X1310773Y1282411D03*
X1303900Y1288000D03*
X1318287Y1295381D03*
Y1291381D03*
X1324120Y22742D03*
X1331073Y33400D03*
X1328003Y32403D03*
X1328318Y27333D03*
X1336623Y30483D03*
X1322853Y37530D03*
X1328799Y168665D03*
Y176665D03*
X1320898Y186629D03*
X1328799Y192665D03*
Y196665D03*
X1328912Y186778D03*
X1328831Y204864D03*
Y208864D03*
X1324472Y219379D03*
X1325100Y228631D03*
X1321506Y265897D03*
X1334110Y310562D03*
X1321762D03*
X1329636Y307562D03*
X1326236D03*
X1332563Y326356D03*
X1325573Y326719D03*
X1332359Y322685D03*
X1326489Y356945D03*
X1331005Y356670D03*
X1331922Y359836D03*
X1325007Y370951D03*
X1334109Y373401D03*
X1334285Y386567D03*
X1331606D03*
X1328896D03*
X1320594Y387151D03*
Y382151D03*
Y384651D03*
X1329097Y435321D03*
Y438121D03*
X1326297Y435321D03*
Y438121D03*
X1329097Y440921D03*
X1326297D03*
X1329097Y443721D03*
X1326297D03*
X1335440Y452799D03*
X1329083Y448931D03*
X1329606Y459170D03*
X1332974Y474513D03*
X1321450Y520268D03*
X1321164Y523130D03*
X1326993Y556788D03*
X1331096Y549931D03*
X1327043Y573346D03*
X1327000Y562500D03*
X1326946Y567906D03*
X1338000Y562500D03*
X1327000Y578500D03*
Y583826D03*
X1335000Y594500D03*
X1327000Y605000D03*
Y594500D03*
Y609000D03*
X1333224Y615484D03*
X1327000Y613000D03*
Y621000D03*
X1335532Y622260D03*
X1338000Y609000D03*
X1327000Y629000D03*
X1327003Y623940D03*
X1335000Y641000D03*
X1338000Y653500D03*
X1327000Y641000D03*
X1327011Y646064D03*
X1327000Y657500D03*
X1335000Y685500D03*
X1327000D03*
Y695500D03*
Y700500D03*
X1338000D03*
X1327000Y711500D03*
Y716500D03*
X1335000Y732500D03*
X1327000D03*
X1330295Y746328D03*
X1326970Y736464D03*
X1336661Y753675D03*
Y745675D03*
Y737675D03*
X1330295Y751328D03*
X1330086Y763758D03*
X1330324Y779030D03*
X1336746Y781675D03*
X1329000Y796000D03*
X1325000Y799000D03*
X1337000Y796000D03*
X1333000Y799000D03*
Y788000D03*
X1329000D03*
X1321000D03*
X1325000D03*
X1331000Y811620D03*
X1327000D03*
X1329000Y804000D03*
X1325000D03*
X1333000D03*
X1323000Y811620D03*
X1335000D03*
X1335803Y826500D03*
X1331056Y904557D03*
X1336096Y905042D03*
X1336000Y900500D03*
X1324000Y901000D03*
X1331078Y900500D03*
X1330500Y925500D03*
X1334500D03*
X1326500D03*
X1333425Y930925D03*
X1324000D03*
X1333132Y933781D03*
X1336000Y943500D03*
X1329199Y933825D03*
X1323000Y934075D03*
X1326500Y943500D03*
X1335343Y961727D03*
X1321028Y961749D03*
X1332500Y961500D03*
X1325550Y960445D03*
X1332000Y969500D03*
X1327000D03*
X1329503Y991088D03*
X1334909Y990340D03*
X1332404Y988215D03*
X1329834Y988132D03*
X1324735Y989966D03*
X1327267Y988271D03*
X1322427Y988221D03*
X1333974Y1033483D03*
X1320549Y1037876D03*
X1322773Y1040599D03*
X1329221Y1058097D03*
X1321721D03*
X1324221D03*
X1326721D03*
Y1060697D03*
X1329221D03*
X1321721D03*
X1324221D03*
X1326163Y1082501D03*
X1326189Y1085205D03*
X1329163Y1082501D03*
X1329189Y1085205D03*
X1326189Y1088205D03*
X1326471Y1091227D03*
X1329189Y1088205D03*
X1323189Y1085205D03*
Y1087705D03*
X1323163Y1082501D03*
X1323021Y1090956D03*
X1337514Y1104335D03*
X1334956Y1105552D03*
X1321069Y1107997D03*
X1323021Y1093956D03*
X1331162Y1104792D03*
X1332669Y1106867D03*
X1321169Y1110597D03*
X1321954Y1113648D03*
X1326254D03*
X1328754D03*
X1323405Y1118801D03*
Y1116101D03*
X1325635Y1172384D03*
Y1162384D03*
Y1164884D03*
Y1167384D03*
Y1169884D03*
X1323135Y1172384D03*
Y1162384D03*
Y1164884D03*
Y1167384D03*
Y1169884D03*
X1334793Y1179421D03*
Y1181921D03*
Y1184421D03*
Y1186921D03*
X1320493Y1186709D03*
Y1184209D03*
Y1181709D03*
Y1179209D03*
X1325635Y1174884D03*
X1323135D03*
X1331643Y1192621D03*
Y1190121D03*
X1327237Y1221428D03*
X1331237D03*
X1335237D03*
X1323237D03*
X1327237Y1237428D03*
Y1233428D03*
Y1229428D03*
Y1225428D03*
X1331237Y1237428D03*
Y1233428D03*
Y1229428D03*
Y1225428D03*
X1335237Y1237428D03*
Y1233428D03*
Y1229428D03*
Y1225428D03*
X1323237Y1237428D03*
Y1233428D03*
Y1229428D03*
Y1225428D03*
X1335237Y1241428D03*
X1323237Y1245428D03*
Y1241428D03*
X1327237Y1245428D03*
Y1241428D03*
X1331237Y1245428D03*
Y1241428D03*
X1335237Y1245428D03*
X1333876Y1257160D03*
Y1260160D03*
X1337687Y-79306D03*
Y-82706D03*
X1336646Y22627D03*
X1336551Y26534D03*
X1340320Y147540D03*
X1344092Y141247D03*
X1351559Y143740D03*
X1348939Y148277D03*
X1348419Y265222D03*
X1340104Y279117D03*
X1344007Y279054D03*
X1337510Y310562D03*
X1347990Y322539D03*
X1341169Y325926D03*
X1346009Y336080D03*
X1346093Y340805D03*
X1349636Y340862D03*
X1346065Y347106D03*
X1338471Y356959D03*
X1337509Y373401D03*
X1349763Y371908D03*
X1342810Y408104D03*
X1345610D03*
X1348410D03*
X1336388Y424939D03*
X1342527Y420375D03*
X1345327D03*
X1348127D03*
X1336388Y427439D03*
X1346443Y431112D03*
X1352008Y435101D03*
X1352271Y442114D03*
X1346613Y440101D03*
X1352251Y447121D03*
X1346248Y452718D03*
X1340820Y452987D03*
X1352259Y452601D03*
X1347846Y461607D03*
X1339846D03*
X1339049Y471334D03*
X1343846Y461607D03*
X1346738Y564492D03*
X1339289Y568461D03*
X1342053Y579339D03*
X1346533Y576780D03*
X1340522Y586133D03*
X1343000Y590458D03*
X1346533Y581898D03*
X1344129Y606914D03*
X1344433Y601201D03*
X1339289Y614961D03*
X1344680Y619085D03*
X1346738Y611192D03*
X1346533Y628398D03*
X1346378Y623734D03*
X1342053Y625839D03*
X1340522Y632633D03*
X1343000Y636958D03*
X1346738Y655492D03*
X1339289Y659461D03*
X1346533Y667780D03*
X1342053Y670339D03*
X1346533Y672898D03*
X1340522Y677133D03*
X1343000Y681458D03*
X1350929Y687043D03*
X1340299Y686243D03*
X1346738Y702492D03*
X1346533Y719898D03*
X1339289Y706461D03*
X1342053Y717339D03*
X1346533Y714780D03*
X1340522Y724133D03*
X1343000Y728458D03*
X1344768Y737675D03*
Y741675D03*
Y745675D03*
Y749675D03*
Y753675D03*
Y761675D03*
Y757675D03*
X1336450Y765675D03*
X1344768Y773675D03*
Y781350D03*
X1345226Y777675D03*
X1341000Y799000D03*
X1345000Y796000D03*
X1341000Y788000D03*
X1345000D03*
X1337000D03*
X1348917Y796000D03*
Y788000D03*
X1352817Y796000D03*
X1349000Y804000D03*
X1351000Y811620D03*
X1347000D03*
X1343000D03*
X1337000Y804000D03*
X1345000D03*
X1341000D03*
X1349976Y829000D03*
X1350000Y825500D03*
X1340000Y900000D03*
X1351500Y903000D03*
Y906500D03*
X1340000Y906000D03*
Y903000D03*
X1351511Y900000D03*
X1350500Y925500D03*
X1338500D03*
X1342500D03*
X1346500D03*
X1353948Y943603D03*
X1345948D03*
X1349848Y936755D03*
X1338500Y930500D03*
X1350500D03*
X1342500D03*
X1346500D03*
X1337514Y988259D03*
X1343465Y1026123D03*
X1340665D03*
X1343465Y1028923D03*
X1340665D03*
X1347552Y1091816D03*
Y1089316D03*
X1345052Y1081816D03*
Y1084316D03*
Y1086816D03*
X1347552D03*
Y1084316D03*
X1350418Y1090288D03*
X1347552Y1081816D03*
X1344241Y1106298D03*
X1348997Y1107997D03*
X1350418Y1093088D03*
X1339234Y1101917D03*
X1339169Y1106897D03*
X1341984Y1110092D03*
X1345650Y1115896D03*
X1348997Y1113797D03*
Y1110897D03*
X1351197Y1112397D03*
X1351097Y1109397D03*
X1345650Y1118396D03*
X1347300Y1128332D03*
X1343725Y1128738D03*
X1343905Y1162384D03*
Y1164884D03*
Y1167384D03*
Y1169884D03*
Y1172384D03*
X1341405D03*
Y1169884D03*
Y1167384D03*
Y1164884D03*
Y1162384D03*
X1350963Y1172384D03*
Y1169884D03*
Y1167384D03*
Y1164884D03*
Y1162384D03*
X1351149Y1158200D03*
X1347423Y1186709D03*
Y1184209D03*
Y1181709D03*
Y1179209D03*
X1343905Y1174884D03*
X1341405D03*
X1350963D03*
X1337108Y1192621D03*
Y1190121D03*
X1345108D03*
Y1192621D03*
X1347237Y1221428D03*
X1343237D03*
X1339237D03*
X1347237Y1237428D03*
Y1233428D03*
Y1229428D03*
X1343237D03*
Y1233428D03*
Y1237428D03*
X1339237D03*
Y1233428D03*
Y1229428D03*
Y1225428D03*
X1347237Y1245428D03*
Y1241428D03*
X1343237D03*
Y1245428D03*
X1339237D03*
Y1241428D03*
X1339876Y1257160D03*
X1342876D03*
X1345876Y1260160D03*
Y1257160D03*
X1348876Y1260160D03*
Y1257160D03*
X1351876Y1260160D03*
Y1257160D03*
X1336876Y1260160D03*
Y1257160D03*
X1342876Y1260160D03*
X1339876D03*
X1360122Y141247D03*
X1364609Y143518D03*
X1363709Y152373D03*
X1366859Y152562D03*
X1363535Y327877D03*
X1366535Y335751D03*
Y339151D03*
X1363535Y331277D03*
Y343625D03*
X1366535Y354899D03*
Y351499D03*
X1363535Y347025D03*
X1360719Y424601D03*
X1352817Y788000D03*
X1367000Y811620D03*
X1365000Y804000D03*
X1355000Y811620D03*
X1363000D03*
X1353000Y804000D03*
X1359000Y811620D03*
X1357000Y804000D03*
X1361000D03*
X1354185Y906498D03*
X1367000Y904500D03*
X1363000Y900500D03*
X1367000D03*
X1354500Y925500D03*
X1366500D03*
X1358500D03*
X1362500D03*
X1365948Y939475D03*
X1357948Y938842D03*
X1361948Y943603D03*
X1369948D03*
X1362500Y930500D03*
X1366500D03*
X1354500D03*
X1358500D03*
X1364765Y1004766D03*
X1367444Y1003763D03*
X1357765Y1019766D03*
X1361265D03*
X1365049Y1028416D03*
X1365314Y1021793D03*
X1357265Y1026266D03*
Y1034266D03*
X1366265Y1039880D03*
X1369642Y1104335D03*
X1367084Y1105552D03*
X1353197Y1107997D03*
X1363290Y1104792D03*
X1364797Y1106867D03*
X1353297Y1110597D03*
X1354082Y1113648D03*
X1355533Y1116101D03*
Y1118801D03*
X1360882Y1113648D03*
X1358382D03*
X1353463Y1172384D03*
Y1169884D03*
Y1167384D03*
Y1164884D03*
Y1162384D03*
X1361723Y1179421D03*
Y1181921D03*
Y1184421D03*
Y1186921D03*
X1353463Y1174884D03*
X1364038Y1190121D03*
Y1192621D03*
X1363876Y1260160D03*
Y1257160D03*
X1354876Y1260160D03*
X1357876D03*
X1360876D03*
Y1257160D03*
X1357876D03*
X1354876D03*
X1366876Y1260160D03*
Y1257160D03*
X1376262Y116594D03*
X1382205Y110784D03*
X1387205D03*
X1376262Y119594D03*
X1386784Y124663D03*
X1376696Y124283D03*
X1381762Y124879D03*
X1375103Y161306D03*
X1372354Y157370D03*
X1384319Y218085D03*
X1381519D03*
X1386846Y249108D03*
X1378227Y248371D03*
X1384265Y320871D03*
Y325371D03*
X1383551Y337808D03*
X1384265Y329871D03*
X1383634Y342766D03*
X1384265Y334371D03*
X1375073Y356871D03*
Y361371D03*
X1383505Y349437D03*
X1384265Y352371D03*
X1372232Y361298D03*
X1383963Y366675D03*
X1377024Y397713D03*
X1375108Y420838D03*
X1375171Y424741D03*
X1375400Y435192D03*
X1375360Y432234D03*
X1383343Y508228D03*
X1383907Y516591D03*
X1383556Y554388D03*
X1378415Y558795D03*
X1383608Y571927D03*
X1378415Y563984D03*
Y569776D03*
X1378957Y584457D03*
X1383000Y584500D03*
X1382997Y581317D03*
X1383425Y590425D03*
X1378415Y605295D03*
X1383608Y618427D03*
X1378415Y610484D03*
Y616276D03*
X1383425Y636925D03*
X1378957Y630957D03*
X1384657Y631620D03*
X1378957Y627988D03*
X1378415Y649795D03*
Y654984D03*
Y660776D03*
X1386289Y672488D03*
X1383425Y681425D03*
X1378957Y675457D03*
X1383000Y675500D03*
X1378415Y696795D03*
Y701984D03*
X1378957Y719488D03*
X1378415Y707776D03*
X1383425Y728425D03*
X1378957Y722457D03*
X1385290Y722400D03*
X1371000Y811620D03*
X1381000Y804000D03*
X1373000D03*
X1369000D03*
X1385360Y811757D03*
X1381428Y812287D03*
X1375193Y811724D03*
X1376708Y901000D03*
X1378500Y925500D03*
X1374369Y925499D03*
X1370500Y925500D03*
X1382500D03*
X1382775Y930281D03*
X1373948Y940103D03*
X1374500Y930500D03*
X1370500D03*
X1378500D03*
X1381519Y996280D03*
X1383162Y991829D03*
X1373534Y1012325D03*
Y1004680D03*
X1378938Y1000586D03*
X1374034Y1015825D03*
X1374059Y1018860D03*
X1376359Y1016825D03*
X1378559Y1038534D03*
X1384784Y1033783D03*
X1385929Y1038665D03*
X1373874Y1032266D03*
Y1035716D03*
X1385152Y1046591D03*
X1377087Y1106365D03*
X1371362Y1101917D03*
X1371297Y1106897D03*
X1382456Y1107997D03*
X1374112Y1110092D03*
X1377778Y1115896D03*
X1384656Y1112397D03*
X1382456Y1110897D03*
Y1113797D03*
X1384556Y1109397D03*
X1377778Y1118396D03*
X1369233Y1169884D03*
Y1172384D03*
X1371733D03*
Y1169884D03*
Y1167384D03*
Y1164884D03*
Y1162384D03*
X1369233D03*
Y1164884D03*
Y1167384D03*
X1376861Y1160834D03*
X1383024D03*
X1369233Y1174884D03*
X1371733D03*
X1375459Y1197471D03*
Y1193471D03*
X1379959Y1197471D03*
Y1193471D03*
X1397848Y97667D03*
X1388231Y116594D03*
X1393504Y102495D03*
X1388231Y119594D03*
X1391765Y125107D03*
X1393238Y142862D03*
X1400379Y143762D03*
X1394279Y148717D03*
X1388128Y138838D03*
X1399327Y195176D03*
X1396827D03*
X1400845Y199248D03*
Y201748D03*
X1398681Y206806D03*
X1401181D03*
X1399408Y210509D03*
X1396908D03*
X1390832Y216970D03*
Y219470D03*
X1390898Y226320D03*
X1390832Y221970D03*
X1388119Y216385D03*
X1402855Y227824D03*
X1398600Y230556D03*
X1393859Y228646D03*
X1397585Y242078D03*
X1392816Y232971D03*
X1389466Y244571D03*
X1396809Y256394D03*
X1395726Y320529D03*
X1395568Y325529D03*
X1395726Y330529D03*
X1395736Y335529D03*
X1395726Y340529D03*
Y345529D03*
Y360529D03*
Y350529D03*
Y355529D03*
X1391896Y365529D03*
X1399884Y367165D03*
X1387847Y366710D03*
X1400231Y390256D03*
X1396528Y397454D03*
X1399571Y397418D03*
X1393575Y397310D03*
X1390553Y397436D03*
X1391623Y409900D03*
X1387125Y417312D03*
X1393177Y424804D03*
X1389557Y424678D03*
X1389431Y421593D03*
X1390271Y417578D03*
X1393208Y428109D03*
X1393336Y431100D03*
X1403085Y460565D03*
X1393944Y507856D03*
X1394044Y510990D03*
X1397079Y527726D03*
Y548726D03*
Y544726D03*
X1395605Y556217D03*
X1390741Y561000D03*
Y569000D03*
Y565000D03*
X1391087Y581317D03*
X1398946Y621311D03*
X1390741Y611500D03*
Y607500D03*
Y615500D03*
X1391586Y623692D03*
X1398946Y629311D03*
Y625311D03*
X1397000Y652000D03*
Y656000D03*
Y660000D03*
Y699000D03*
Y707000D03*
Y703000D03*
X1391040Y812027D03*
X1386335Y803704D03*
X1390537Y803679D03*
X1394537Y803653D03*
X1398530Y811717D03*
X1402417Y811692D03*
X1400069Y827515D03*
X1401300Y820485D03*
X1395955Y832697D03*
X1402000Y840000D03*
Y848000D03*
X1399872Y845109D03*
X1402000Y864000D03*
X1391316Y857849D03*
X1388488Y857822D03*
X1402000Y876000D03*
X1390182Y873460D03*
X1387582Y873487D03*
X1402000Y884000D03*
Y892000D03*
X1388479Y892923D03*
X1385979D03*
X1390979D03*
X1402000Y900000D03*
X1387520Y905307D03*
X1387753Y912629D03*
X1394891Y914783D03*
X1402187Y908270D03*
X1387504Y899931D03*
X1390541Y900086D03*
X1388980Y921075D03*
X1401000Y925789D03*
X1396869Y958707D03*
X1402064Y965913D03*
X1389192Y992568D03*
X1398854Y987277D03*
X1394885Y999941D03*
X1392031Y1004375D03*
X1385732Y1029482D03*
X1389762Y1043055D03*
X1387813Y1030952D03*
X1399807Y1036155D03*
X1399852Y1039779D03*
X1388523Y1090090D03*
X1392691Y1089224D03*
X1392086Y1092743D03*
X1392691Y1086724D03*
Y1084224D03*
Y1081724D03*
X1390191D03*
Y1084224D03*
Y1086724D03*
X1403101Y1104335D03*
X1400543Y1105552D03*
X1396749Y1104792D03*
X1388451Y1093048D03*
X1386656Y1107997D03*
X1398256Y1106867D03*
X1386756Y1110597D03*
X1394341Y1113648D03*
X1388992Y1118801D03*
Y1116101D03*
X1387541Y1113648D03*
X1391841D03*
X1388722Y1162384D03*
Y1164884D03*
Y1167384D03*
Y1169884D03*
Y1172384D03*
X1391222Y1162384D03*
Y1164884D03*
Y1167384D03*
Y1169884D03*
Y1172384D03*
X1388722Y1174884D03*
X1391222D03*
X1393695Y1186709D03*
Y1184209D03*
Y1181709D03*
Y1179209D03*
X1391380Y1190121D03*
Y1192621D03*
X1385821Y1260160D03*
X1391821Y1257160D03*
X1394821D03*
X1385821D03*
X1388821D03*
X1397821Y1260160D03*
Y1257160D03*
X1400821Y1260160D03*
Y1257160D03*
X1388821Y1260160D03*
X1394821D03*
X1391821D03*
X1385052Y1303139D03*
X1389052D03*
X1406308Y103411D03*
X1406702Y97667D03*
X1417498Y90650D03*
X1417248Y95236D03*
X1402098Y95111D03*
X1406467Y106561D03*
X1403845Y199248D03*
X1401827Y195176D03*
X1404327D03*
X1403845Y202048D03*
X1407445Y230117D03*
X1403461Y238714D03*
X1402942Y246874D03*
X1405162Y244297D03*
X1402921Y322403D03*
X1409830Y347649D03*
X1404690Y362209D03*
X1416912Y386903D03*
X1408854Y381207D03*
X1416470Y381397D03*
X1402968Y390177D03*
X1414369Y398056D03*
X1408254Y398041D03*
X1407844Y411033D03*
X1415610Y417644D03*
X1415674Y421278D03*
X1417856Y448419D03*
X1414903Y469905D03*
X1410903Y470419D03*
Y461919D03*
X1418903Y461419D03*
X1411269Y481467D03*
X1415623Y492268D03*
X1415823Y482165D03*
X1416061Y504825D03*
X1413561D03*
X1411061D03*
X1415064Y500202D03*
X1406910Y495982D03*
X1416413Y495649D03*
X1406910Y491982D03*
X1416002Y517401D03*
X1413502D03*
X1411002D03*
X1416553Y522569D03*
Y525369D03*
X1415168Y531882D03*
X1412668D03*
X1409618Y531948D03*
X1401438Y534211D03*
X1405992Y534909D03*
X1405619Y541135D03*
X1405685Y546553D03*
X1405708Y552726D03*
X1415103Y555194D03*
Y563194D03*
Y571194D03*
X1416660Y581222D03*
Y591215D03*
X1401383Y611071D03*
X1416832Y610562D03*
Y607762D03*
X1411622Y610548D03*
X1407566Y622285D03*
X1407754Y616905D03*
X1418439Y633736D03*
X1407952Y633724D03*
X1413432Y633716D03*
X1407835Y627713D03*
X1405229Y652028D03*
X1405000Y660000D03*
X1410000Y685000D03*
Y681000D03*
X1404500Y675000D03*
X1410000Y701000D03*
Y697000D03*
X1418000Y696000D03*
Y701000D03*
X1410000Y709000D03*
Y713000D03*
X1405000Y707000D03*
Y703000D03*
X1418000Y717000D03*
X1410000D03*
X1404500Y722000D03*
X1410000Y729000D03*
Y725000D03*
X1418000Y724000D03*
Y729000D03*
X1404249Y735858D03*
X1410000Y745000D03*
Y741000D03*
X1418000Y740000D03*
Y745000D03*
X1407482Y750853D03*
X1410000Y757000D03*
Y753000D03*
Y761000D03*
X1418000D03*
X1406867Y783273D03*
X1409115Y773520D03*
X1414597Y792375D03*
X1406483Y811717D03*
X1413500Y832000D03*
Y828000D03*
X1413449Y823934D03*
X1405402Y819917D03*
X1405500Y844000D03*
Y836000D03*
X1413500Y848000D03*
Y840000D03*
Y836000D03*
Y844000D03*
X1405500Y860000D03*
X1413500Y864000D03*
Y860000D03*
Y856000D03*
Y852000D03*
X1405500Y880000D03*
Y868000D03*
X1413500Y876000D03*
X1417797Y879501D03*
X1413500Y872000D03*
Y868000D03*
X1405500Y888000D03*
Y896000D03*
X1417081D03*
X1413500Y892000D03*
Y884000D03*
Y888000D03*
X1413733Y911137D03*
X1412376Y907848D03*
X1414876D03*
X1417376D03*
X1409876D03*
X1405500Y904000D03*
X1404760Y915186D03*
X1413500Y904000D03*
Y900000D03*
X1417284Y911009D03*
X1416802Y936845D03*
X1416244Y942285D03*
X1419337D03*
X1405214Y965074D03*
X1419446Y977192D03*
X1416618Y992307D03*
X1401265Y989465D03*
X1407265D03*
X1414143Y985486D03*
X1412698Y997590D03*
X1412609Y1008766D03*
X1412759Y1016266D03*
X1402215Y1020440D03*
X1414851Y1058097D03*
X1412351D03*
X1407351D03*
X1409851D03*
X1417351D03*
X1414851Y1060697D03*
X1412351D03*
X1407351D03*
X1409851D03*
X1417351D03*
X1405677Y1086796D03*
X1408177D03*
X1410677D03*
X1413177D03*
X1415677D03*
Y1084296D03*
X1413177D03*
X1410677D03*
X1408177D03*
X1405677D03*
X1416005Y1090288D03*
X1410546Y1106298D03*
X1404821Y1101917D03*
X1404756Y1106897D03*
X1416005Y1093088D03*
X1414584Y1107997D03*
X1411237Y1115896D03*
X1407571Y1110092D03*
X1414584Y1113797D03*
X1416784Y1112397D03*
X1414584Y1110897D03*
X1416684Y1109397D03*
X1411237Y1118396D03*
X1409425Y1129238D03*
X1413177Y1128894D03*
X1409492Y1167384D03*
Y1169884D03*
Y1172384D03*
X1406992D03*
Y1169884D03*
X1416550Y1162384D03*
Y1164884D03*
Y1167384D03*
Y1169884D03*
Y1172384D03*
X1406992Y1167384D03*
Y1164884D03*
Y1162384D03*
X1409492D03*
Y1164884D03*
X1416736Y1158200D03*
X1416550Y1174884D03*
X1409492D03*
X1406992D03*
X1407995Y1179421D03*
Y1181921D03*
Y1184421D03*
Y1186921D03*
X1410310Y1192621D03*
Y1190121D03*
X1404845D03*
Y1192621D03*
X1408736Y1222194D03*
X1412736D03*
X1416736D03*
X1408736Y1238194D03*
Y1234194D03*
Y1230194D03*
Y1226194D03*
X1412736Y1238194D03*
Y1234194D03*
Y1230194D03*
Y1226194D03*
X1416736Y1238194D03*
Y1234194D03*
Y1230194D03*
Y1226194D03*
X1412736Y1246194D03*
Y1242194D03*
X1416736Y1246194D03*
Y1242194D03*
X1408736D03*
Y1246194D03*
X1409821Y1260160D03*
X1412821D03*
Y1257160D03*
X1409821D03*
X1406821D03*
X1403821D03*
X1415821Y1260160D03*
Y1257160D03*
X1403821Y1260160D03*
X1406821D03*
X1417711Y1301729D03*
X1410817Y1305417D03*
X1407825Y1426975D03*
X1408536Y1536570D03*
X1407747Y1549054D03*
X1408044Y1559306D03*
X1407255Y1571732D03*
X1422810Y90615D03*
X1427131Y99961D03*
X1427181Y95236D03*
X1425993Y212978D03*
Y207978D03*
Y210478D03*
Y215478D03*
X1429322Y264180D03*
X1431822D03*
X1429247Y258880D03*
X1434166Y325361D03*
X1434164Y339232D03*
X1434038Y334114D03*
X1435818Y352361D03*
X1421005Y407616D03*
X1417903Y439919D03*
X1434997Y442603D03*
X1427117Y443071D03*
X1423427Y456839D03*
X1425927D03*
X1423427Y454339D03*
X1425927D03*
X1432414Y459371D03*
X1423427Y459339D03*
X1425927D03*
X1418903Y469905D03*
X1431484Y470045D03*
X1427484Y462004D03*
X1422499Y485138D03*
X1419650Y485128D03*
X1426384Y478625D03*
X1428084Y482425D03*
X1427499Y485138D03*
X1424999D03*
X1426384Y476125D03*
X1418253Y529169D03*
X1417668Y531882D03*
X1424129Y537658D03*
X1427832Y539731D03*
X1424129Y540458D03*
X1432590Y544895D03*
X1435390D03*
X1427832Y542231D03*
X1432890Y541895D03*
X1417903Y555194D03*
Y563194D03*
Y571194D03*
X1422260Y581222D03*
X1419460D03*
X1435119Y590801D03*
X1422260Y591215D03*
X1419460D03*
X1431000Y591000D03*
X1434944Y597130D03*
X1433114Y620653D03*
Y617853D03*
X1419632Y607762D03*
X1422432D03*
X1425232Y610562D03*
Y607762D03*
X1422432Y610562D03*
X1419632D03*
X1430944Y605443D03*
X1420452Y628078D03*
X1430175Y627852D03*
X1425452Y633473D03*
X1430481Y658153D03*
X1433529Y660564D03*
X1426615Y674112D03*
X1429000Y685000D03*
X1418000D03*
Y681000D03*
X1425909Y691120D03*
X1433464Y692658D03*
X1418000Y689000D03*
X1433053Y701839D03*
X1426000Y717000D03*
X1418000Y705000D03*
X1431522Y708633D03*
X1434000Y712958D03*
X1430289Y734961D03*
X1418000Y733000D03*
X1417969Y720894D03*
X1429000Y729000D03*
X1434000Y751958D03*
X1433153Y745839D03*
X1427000Y766500D03*
X1426000Y761000D03*
X1435000Y765500D03*
X1434000Y756958D03*
X1418023Y765343D03*
X1427000Y781834D03*
Y770500D03*
X1435000D03*
X1427000Y794500D03*
X1435000Y802500D03*
X1427000Y810500D03*
Y814500D03*
X1435000D03*
Y809500D03*
X1427000Y802500D03*
Y830500D03*
Y826500D03*
X1434975Y830500D03*
X1435000Y825500D03*
X1427000Y842500D03*
Y838500D03*
X1435000Y846500D03*
X1427000D03*
X1435043Y874694D03*
X1435082Y869475D03*
X1423190Y905295D03*
X1429059Y908579D03*
X1426085Y910281D03*
X1429907Y936998D03*
X1424897Y936777D03*
X1435516Y936000D03*
X1420699Y958452D03*
X1430839Y965546D03*
X1420740Y1008766D03*
X1428740Y1000766D03*
X1420740Y996766D03*
X1428864D03*
X1420740Y1012266D03*
X1428740Y1016266D03*
X1428823Y1020266D03*
X1435229Y1104335D03*
X1432671Y1105552D03*
X1428877Y1104792D03*
X1418784Y1107997D03*
X1430384Y1106867D03*
X1418884Y1110597D03*
X1421120Y1116101D03*
Y1118801D03*
X1426469Y1113648D03*
X1423969D03*
X1419669D03*
X1419050Y1162384D03*
Y1164884D03*
Y1167384D03*
Y1169884D03*
Y1172384D03*
Y1174884D03*
X1420625Y1186709D03*
Y1184209D03*
Y1181709D03*
Y1179209D03*
X1418310Y1192621D03*
Y1190121D03*
X1420736Y1222194D03*
X1424736D03*
X1428736D03*
X1432736D03*
X1420736Y1238194D03*
Y1234194D03*
Y1230194D03*
Y1226194D03*
X1424736Y1238194D03*
Y1234194D03*
Y1230194D03*
Y1226194D03*
X1428736Y1238194D03*
Y1234194D03*
Y1230194D03*
Y1226194D03*
X1432736Y1234194D03*
Y1230194D03*
Y1226194D03*
X1420736Y1246194D03*
Y1242194D03*
X1424736Y1246194D03*
Y1242194D03*
X1428736Y1246194D03*
Y1242194D03*
X1421821Y1257160D03*
X1418821D03*
Y1260160D03*
X1421821D03*
X1431080Y1301702D03*
X1421238Y1301712D03*
X1428009Y1301760D03*
X1424732Y1301603D03*
X1432258Y1414600D03*
X1430374Y1492474D03*
X1420877Y1494706D03*
X1421964Y1502813D03*
X1423930Y1520364D03*
X1429587Y1527450D03*
X1433405Y1546001D03*
X1432913Y1568679D03*
X1449685Y34228D03*
X1436045Y77393D03*
Y74793D03*
Y85193D03*
Y82593D03*
Y79993D03*
X1444370Y98551D03*
X1436089Y92874D03*
X1447920Y103783D03*
X1438116Y107649D03*
Y104249D03*
X1442682Y147540D03*
X1446454Y141247D03*
X1451301Y148277D03*
X1435138Y162368D03*
X1437738D03*
X1444838Y162793D03*
Y165393D03*
Y170493D03*
Y167993D03*
X1451762Y177616D03*
X1449841Y181009D03*
X1447046Y181366D03*
X1443835Y181426D03*
X1444043Y184221D03*
X1446660Y184012D03*
X1448079Y211359D03*
Y213859D03*
X1436449Y213213D03*
Y210713D03*
X1440521Y211695D03*
X1443021D03*
X1440521Y208695D03*
X1443321D03*
X1436449Y208213D03*
Y215713D03*
X1451785Y265896D03*
X1446698Y265701D03*
X1441016Y267526D03*
Y270026D03*
X1443516D03*
X1438216D03*
X1443516Y267526D03*
X1438216D03*
X1448333Y281716D03*
X1449060Y329861D03*
X1448948Y326448D03*
X1449060Y320861D03*
X1438829Y329861D03*
X1437064Y320861D03*
X1448822Y345324D03*
X1448734Y332910D03*
X1448500Y340575D03*
X1439712Y336673D03*
X1440420Y346833D03*
X1449060Y356861D03*
X1441180Y354909D03*
X1448572Y349441D03*
X1449060Y352361D03*
X1447502Y360785D03*
X1434697Y347125D03*
X1439719Y350387D03*
X1443041Y363648D03*
X1434608Y362584D03*
X1438768Y371655D03*
X1442633Y371502D03*
X1445906Y366030D03*
X1440523Y382747D03*
X1435424Y430361D03*
X1440390Y456652D03*
X1442890D03*
Y459152D03*
Y461652D03*
X1440390Y459152D03*
Y461652D03*
X1436930Y461818D03*
X1433960Y491214D03*
X1449293Y491133D03*
X1442721Y495151D03*
X1437663Y492987D03*
X1442421Y498151D03*
X1433960Y493714D03*
X1437663Y495487D03*
X1445221Y498151D03*
X1449293Y493633D03*
Y496133D03*
Y498633D03*
X1445221Y495151D03*
X1439462Y537877D03*
X1449393Y553297D03*
Y555897D03*
X1446988Y548418D03*
X1439462Y540377D03*
X1435390Y541895D03*
X1444488Y548418D03*
X1439488D03*
X1441988D03*
X1439462Y542877D03*
Y545377D03*
X1449393Y558497D03*
Y566797D03*
Y563697D03*
Y561097D03*
X1443388Y570686D03*
X1446183Y570478D03*
X1435668Y582747D03*
X1446600Y576484D03*
X1446243Y573689D03*
X1443597Y573303D03*
X1449993Y578405D03*
X1438944Y597232D03*
X1443775Y596089D03*
X1448994Y596782D03*
X1440930Y613913D03*
Y616713D03*
Y619513D03*
X1434944Y605443D03*
X1438944Y605637D03*
X1437790Y625013D03*
X1435952Y642184D03*
X1446323Y673183D03*
X1437738Y686992D03*
X1448991Y694392D03*
X1451976Y693844D03*
X1437533Y704398D03*
Y699280D03*
X1438930Y716363D03*
X1446860Y730735D03*
X1446538Y719548D03*
X1437738Y730992D03*
X1446717Y735536D03*
X1437533Y743280D03*
Y748398D03*
X1447289Y776461D03*
X1446000Y770500D03*
X1451000Y793458D03*
Y798458D03*
X1450253Y787339D03*
X1443000Y802500D03*
X1447000Y810500D03*
Y818500D03*
X1435000D03*
X1448000Y834500D03*
X1443000Y846500D03*
X1435000Y834500D03*
X1449000Y844500D03*
X1435212Y854042D03*
X1448726Y864400D03*
X1439891Y873821D03*
X1445367Y891888D03*
X1441223Y891957D03*
X1435745Y901500D03*
X1443231Y899006D03*
X1439103Y898564D03*
X1447261Y898571D03*
X1446022Y927000D03*
X1448137Y949440D03*
X1439031Y957683D03*
X1441088Y976409D03*
X1433996Y981437D03*
X1440700Y981763D03*
X1435669Y1005366D03*
X1440869Y1010256D03*
X1435197Y1028372D03*
X1442674Y1106365D03*
X1436949Y1101917D03*
X1436884Y1106897D03*
X1439699Y1110092D03*
X1443365Y1115896D03*
Y1118396D03*
X1442448Y1160834D03*
X1434820Y1162384D03*
Y1164884D03*
Y1167384D03*
Y1169884D03*
Y1172384D03*
X1437320D03*
Y1169884D03*
Y1167384D03*
Y1164884D03*
Y1162384D03*
X1434925Y1179421D03*
Y1181921D03*
Y1184421D03*
Y1186921D03*
X1434820Y1174884D03*
X1437320D03*
X1437240Y1192621D03*
Y1190121D03*
X1436736Y1222194D03*
Y1226194D03*
X1443660Y1310698D03*
X1440260D03*
X1446817Y1335846D03*
X1441200Y1338700D03*
X1435900Y1340800D03*
X1439258Y1414600D03*
X1446135Y1530876D03*
X1443103Y1527201D03*
X1441145Y1540415D03*
X1440153Y1563093D03*
X1443769Y1562173D03*
X1452717Y34052D03*
X1457347Y31518D03*
X1457829Y26425D03*
X1455013Y43128D03*
X1460466Y76587D03*
Y72615D03*
X1461905Y100625D03*
X1454924Y97475D03*
X1454855Y106186D03*
X1462484Y141247D03*
X1466971Y143518D03*
X1453921Y143740D03*
X1466071Y152373D03*
X1455016Y168697D03*
X1452343Y172190D03*
X1464628Y171523D03*
X1456104Y191941D03*
X1464158Y192490D03*
X1458113Y206767D03*
X1463113D03*
X1460613D03*
X1451782Y213132D03*
X1463243Y221708D03*
X1460743D03*
X1458243D03*
X1457658Y224421D03*
X1459358Y231021D03*
Y228221D03*
X1451782Y215632D03*
X1459909Y236189D03*
X1464909D03*
X1462409D03*
X1459850Y248765D03*
X1464850D03*
X1462350D03*
X1452026Y256303D03*
X1456801Y266114D03*
X1460047Y270695D03*
Y268195D03*
X1462547Y270695D03*
Y268195D03*
X1465347Y270695D03*
Y268195D03*
X1454274Y281982D03*
X1459060Y320861D03*
Y325361D03*
Y329861D03*
Y338861D03*
Y343361D03*
Y334361D03*
Y347861D03*
Y352361D03*
X1459873Y391705D03*
X1463145Y391579D03*
X1458214Y406231D03*
X1464536Y433114D03*
X1458912Y581659D03*
X1455419Y578986D03*
X1454944Y596729D03*
X1453000Y614158D03*
Y616958D03*
Y619758D03*
X1450944Y605443D03*
X1458944D03*
X1461474Y655807D03*
X1455761Y683448D03*
X1468372Y673812D03*
X1460111Y683536D03*
X1451428Y673252D03*
X1460816Y727964D03*
X1455291Y759656D03*
X1455159Y763714D03*
X1454504Y777575D03*
X1454533Y784780D03*
X1454738Y772492D03*
X1454533Y789898D03*
X1453102Y821102D03*
X1454541Y831339D03*
X1453102Y826500D03*
X1452619Y836457D03*
X1461113Y871389D03*
X1457218Y888764D03*
X1452641Y888033D03*
X1451286Y898549D03*
X1462500Y905295D03*
X1461888Y936055D03*
X1462000Y957000D03*
X1458202Y960288D03*
X1457937Y966712D03*
X1457352Y976277D03*
X1459519Y989432D03*
X1467096Y988813D03*
X1456966Y998507D03*
X1458892Y1007522D03*
X1465658Y1006648D03*
X1465846Y1023900D03*
X1463025Y1018307D03*
X1459267Y1013678D03*
X1456280Y1023405D03*
X1459683Y1028377D03*
X1481905Y-79278D03*
Y-82678D03*
X1479972Y40780D03*
X1472146Y55513D03*
X1468371Y68581D03*
X1474746Y60513D03*
X1477606Y60438D03*
X1468384Y80581D03*
X1474874Y85731D03*
X1483287Y86012D03*
X1472514Y88801D03*
X1478428Y86046D03*
X1475431Y94351D03*
X1479380Y94279D03*
X1470567Y103621D03*
X1478624Y116594D03*
X1466278Y112083D03*
X1484567Y110784D03*
X1478624Y119594D03*
X1479058Y124283D03*
X1484124Y124879D03*
X1477465Y161306D03*
X1469221Y152562D03*
X1474716Y157370D03*
X1478800Y168665D03*
Y176665D03*
X1469913Y183834D03*
X1470023Y178560D03*
X1470086Y172665D03*
X1470899Y186629D03*
X1469433Y190185D03*
X1478800Y192665D03*
Y196665D03*
X1470203Y200864D03*
X1478913Y186778D03*
X1478832Y204864D03*
X1470292Y212455D03*
X1470226Y207037D03*
X1478832Y208864D03*
X1467593Y221642D03*
X1474473Y219379D03*
X1475101Y228631D03*
X1480589Y248371D03*
X1471507Y265897D03*
X1469007D03*
X1477549Y327200D03*
Y322700D03*
Y345200D03*
Y340700D03*
Y331700D03*
Y358700D03*
Y349700D03*
Y354200D03*
X1480702Y368516D03*
X1468309Y408861D03*
X1475236Y412482D03*
X1466231Y423671D03*
X1469538Y416795D03*
X1466653Y428582D03*
X1471375Y433115D03*
X1477597Y682997D03*
X1475264Y680933D03*
X1474713Y685247D03*
X1479297Y693630D03*
X1476794Y691447D03*
X1476716Y704398D03*
X1479500Y689630D03*
Y697630D03*
X1474425Y712925D03*
X1479759Y720885D03*
X1469957Y706957D03*
X1474000Y707000D03*
X1479794Y709388D03*
X1472000Y727500D03*
X1469116Y719055D03*
X1480000Y731500D03*
X1479759Y743500D03*
X1479657Y735500D03*
X1469957Y750957D03*
X1476716Y748398D03*
X1480000Y739500D03*
X1471006Y744818D03*
X1470801Y739280D03*
X1474425Y756925D03*
X1479665Y754555D03*
X1474000Y753093D03*
X1476677Y827626D03*
X1473489Y861354D03*
X1474060Y877196D03*
X1473468Y874267D03*
X1482387Y872940D03*
X1474883Y868206D03*
X1473433Y891043D03*
X1473387Y897425D03*
X1482195Y885807D03*
X1470925Y920575D03*
X1480343Y914776D03*
X1480109Y943496D03*
X1480144Y946880D03*
X1479441Y961941D03*
X1480414Y952214D03*
X1476500Y974000D03*
X1482237Y966028D03*
X1479196Y970000D03*
X1480414Y975064D03*
X1475096Y980330D03*
X1471096D03*
X1479096Y988813D03*
X1471296D03*
X1475096D03*
X1483096D03*
X1475062Y1008300D03*
Y1002453D03*
X1482535Y1024254D03*
X1468869Y1018469D03*
X1476230Y1030672D03*
X1473230D03*
X1471374Y1118654D03*
X1474384Y1109564D03*
X1480231D03*
X1474384Y1122164D03*
X1480231D03*
X1474384Y1134764D03*
X1480231D03*
X1474384Y1147364D03*
X1480231D03*
X1474384Y1172564D03*
X1480231D03*
X1474384Y1159964D03*
X1480231D03*
X1474384Y1185164D03*
X1480231D03*
X1483308Y1214372D03*
X1479063Y1218169D03*
X1498621Y19043D03*
X1489556Y17645D03*
X1498621Y31043D03*
Y23043D03*
X1489829Y29424D03*
X1490563Y23043D03*
X1500210Y97667D03*
X1483287Y94374D03*
X1490593Y116594D03*
X1495866Y102495D03*
X1489567Y110784D03*
X1490593Y119594D03*
X1494127Y125107D03*
X1489146Y124663D03*
X1495600Y142862D03*
X1496641Y148717D03*
X1490490Y138838D03*
X1493260Y226320D03*
X1493194Y221970D03*
X1490481Y216385D03*
X1493194Y216970D03*
Y219470D03*
X1486681Y218085D03*
X1483881D03*
X1496221Y228646D03*
X1495178Y232971D03*
X1491828Y244571D03*
X1489208Y249108D03*
X1499171Y256394D03*
X1497446Y295877D03*
X1486860Y327200D03*
X1500659Y330024D03*
X1495605Y322700D03*
X1487318Y318200D03*
X1486360Y322700D03*
Y345200D03*
X1500386Y344642D03*
X1486913Y340327D03*
X1487152Y331272D03*
X1495689Y332534D03*
X1495521Y340700D03*
X1486360Y349700D03*
X1495521Y349681D03*
X1495925Y358700D03*
X1499839Y354001D03*
X1486890Y368576D03*
X1494286Y372699D03*
X1488000Y731500D03*
X1495500Y750500D03*
X1488731Y739500D03*
X1496629Y765000D03*
X1496763Y777000D03*
X1493301Y776911D03*
X1496814Y773000D03*
X1497000Y781000D03*
X1496756Y785000D03*
X1491425Y798425D03*
X1499633Y787794D03*
X1493716Y789898D03*
X1486957Y792457D03*
X1495170Y796670D03*
X1487050Y809413D03*
X1496845Y809000D03*
X1496806Y817000D03*
X1496621Y829000D03*
X1496447Y821000D03*
X1486386Y825296D03*
X1493092Y820444D03*
X1493038Y833898D03*
X1495240Y825000D03*
X1491425Y842425D03*
X1486957Y836457D03*
X1492625Y837324D03*
X1488138Y878339D03*
Y872839D03*
X1482566Y882154D03*
X1494954Y895264D03*
X1484824Y927324D03*
X1487240Y924453D03*
X1497063Y934000D03*
X1496072Y940201D03*
X1483324Y939324D03*
X1482921Y931324D03*
X1485500Y932500D03*
X1497075Y961000D03*
X1487240Y952012D03*
X1496072Y953981D03*
X1495500Y972500D03*
X1489500D03*
X1487096Y988813D03*
X1491096D03*
X1495096D03*
X1499096D03*
X1490235Y1004816D03*
X1487266Y1002046D03*
X1486030Y1016827D03*
X1491877D03*
X1486030Y1029427D03*
X1491877D03*
X1496140Y1105091D03*
X1496185Y1102091D03*
X1496140Y1117691D03*
X1496185Y1114691D03*
Y1127291D03*
X1496140Y1130291D03*
X1496185Y1139891D03*
X1496140Y1155491D03*
Y1142891D03*
X1496185Y1152491D03*
X1496140Y1168091D03*
X1496185Y1165091D03*
X1496140Y1180691D03*
X1496185Y1177691D03*
X1482705Y1200001D03*
X1489793Y1207737D03*
X1497693Y1230407D03*
X1508670Y103411D03*
X1509064Y97667D03*
X1504460Y95111D03*
X1508829Y106561D03*
X1502741Y143762D03*
X1506689Y195176D03*
X1506207Y199248D03*
X1501689Y195176D03*
X1503207Y199248D03*
X1499189Y195176D03*
X1504189D03*
X1506207Y202048D03*
X1503207Y201748D03*
X1499270Y210509D03*
X1501043Y206806D03*
X1501770Y210509D03*
X1503543Y206806D03*
X1509807Y230117D03*
X1500962Y230556D03*
X1505217Y227824D03*
X1505823Y238714D03*
X1499947Y242078D03*
X1505304Y246874D03*
X1507524Y244297D03*
X1503884Y295549D03*
X1501500Y321000D03*
X1501000Y317500D03*
X1501684Y336561D03*
X1516838Y347422D03*
X1515909Y354601D03*
X1516636Y458711D03*
X1513284Y552466D03*
X1504495Y796844D03*
X1510527Y833500D03*
X1504938Y859711D03*
X1500353Y859855D03*
X1500638Y873839D03*
X1512712Y867418D03*
X1502158Y899479D03*
X1510527Y908951D03*
X1513927D03*
X1504208Y909740D03*
X1509274Y921226D03*
X1505337Y921240D03*
X1509500Y937000D03*
Y944138D03*
X1516500Y947500D03*
X1501812Y938397D03*
X1512161Y957541D03*
X1509500Y950500D03*
X1498973Y975443D03*
X1511000Y970500D03*
X1511096Y988813D03*
X1507096D03*
X1503096D03*
X1515096D03*
X1513286Y1012354D03*
X1507831Y1009354D03*
X1507786Y1012354D03*
Y1024954D03*
X1513286D03*
X1507831Y1021954D03*
X1503572Y1034538D03*
X1501640Y1105091D03*
Y1117691D03*
Y1130291D03*
Y1142891D03*
Y1155491D03*
Y1168091D03*
Y1180691D03*
X1508356Y1220068D03*
X1500675Y1227300D03*
X1506807Y1234921D03*
X1507692Y1224472D03*
X1507058Y1229402D03*
X1517261Y-40358D03*
Y-43758D03*
X1525172Y90615D03*
X1519860Y90650D03*
X1529493Y99961D03*
X1529543Y95236D03*
X1519610D03*
X1528355Y210478D03*
Y215478D03*
Y212978D03*
Y207978D03*
X1519321Y378600D03*
Y382600D03*
X1519436Y458711D03*
X1521963Y453682D03*
X1520200Y455921D03*
X1518780Y463600D03*
X1519185Y603600D03*
Y619600D03*
Y623600D03*
X1520729Y634190D03*
X1524200Y646098D03*
X1518517Y878898D03*
X1518452Y873780D03*
X1525022Y909558D03*
X1522881Y901034D03*
X1522954Y897951D03*
X1521085Y921094D03*
X1515179D03*
X1527267Y932647D03*
X1522209Y937846D03*
X1521500Y947500D03*
X1528500Y947612D03*
X1529128Y952978D03*
X1521085Y957340D03*
X1525583Y968500D03*
X1530767Y972981D03*
X1519863Y977637D03*
X1525005Y974323D03*
X1530594Y979952D03*
X1531096Y988813D03*
X1523096D03*
X1519096D03*
X1527096Y997860D03*
X1526810Y1025090D03*
X1522904Y1021256D03*
X1521939Y1040818D03*
X1522099Y1035521D03*
X1531993Y1056453D03*
X1531961Y1050849D03*
X1524953Y1051037D03*
X1517855Y1053457D03*
X1538407Y85539D03*
Y82939D03*
Y75139D03*
Y80339D03*
Y77739D03*
X1546732Y98551D03*
X1538451Y92874D03*
X1540478Y107649D03*
Y104249D03*
X1545044Y147540D03*
X1540100Y162368D03*
X1537500D03*
X1547200Y162793D03*
Y165393D03*
Y167993D03*
Y170493D03*
X1546197Y181426D03*
X1546405Y184221D03*
X1538811Y213213D03*
Y210713D03*
X1542883Y211695D03*
X1545383D03*
X1542883Y208695D03*
X1545683D03*
X1538811Y208213D03*
Y215713D03*
X1534184Y264180D03*
X1531684D03*
X1531609Y258880D03*
X1549060Y265701D03*
X1545878Y270026D03*
X1543378D03*
X1540578D03*
X1543378Y267526D03*
X1540578D03*
X1545878D03*
X1544736Y305156D03*
X1545583Y316363D03*
X1539140Y320863D03*
X1545636Y325363D03*
X1542797Y329863D03*
X1545846Y334363D03*
X1544951Y343363D03*
X1538133Y354553D03*
X1545434Y352363D03*
X1546183Y541863D03*
Y545263D03*
X1544375Y553407D03*
X1546875D03*
X1544375Y550907D03*
X1546875D03*
X1542704Y572162D03*
X1543946Y569928D03*
X1546293Y570962D03*
X1546036Y568475D03*
X1548080Y910757D03*
X1547644Y903060D03*
X1532067Y1041832D03*
X1531947Y1046212D03*
X1531546Y1062769D03*
X1536909Y1151870D03*
Y1159350D03*
X1540649Y1155610D03*
X1562828Y72615D03*
Y76587D03*
X1564267Y100625D03*
X1557286Y97475D03*
X1557217Y106186D03*
X1550282Y103783D03*
X1548816Y141247D03*
X1564846D03*
X1556283Y143740D03*
X1553663Y148277D03*
X1552203Y181009D03*
X1549408Y181366D03*
X1557378Y168697D03*
X1554705Y172190D03*
X1554124Y177616D03*
X1558466Y191941D03*
X1549022Y184012D03*
X1560475Y206767D03*
X1562975D03*
X1554144Y213132D03*
X1550441Y211359D03*
Y213859D03*
X1560605Y221708D03*
X1560020Y224421D03*
X1563105Y221708D03*
X1561720Y231021D03*
Y228221D03*
X1554144Y215632D03*
X1562271Y236189D03*
X1562212Y248765D03*
X1554388Y256303D03*
X1559163Y266114D03*
X1554147Y265896D03*
X1562409Y268195D03*
Y270695D03*
X1556636Y281982D03*
X1550695Y281716D03*
X1550931Y305158D03*
X1554403Y316363D03*
X1553534Y327337D03*
X1553910Y331798D03*
X1553597Y336601D03*
X1553862Y344867D03*
X1551175Y347283D03*
X1556588Y545528D03*
X1548359Y569426D03*
X1548645Y566929D03*
X1562385Y610400D03*
X1564670Y650122D03*
X1565132Y668153D03*
X1561552Y665455D03*
X1548629Y927836D03*
X1548504Y915689D03*
X1548616Y931602D03*
X1551163Y952888D03*
X1552000Y969850D03*
X1571895Y58013D03*
X1570733Y68581D03*
X1577108Y60513D03*
X1570746Y80581D03*
X1577236Y85731D03*
X1574876Y88801D03*
X1581742Y94279D03*
X1577793Y94351D03*
X1572929Y103621D03*
X1568640Y112083D03*
X1581420Y124283D03*
X1569333Y143518D03*
X1568433Y152373D03*
X1579827Y161306D03*
X1571583Y152562D03*
X1577078Y157370D03*
X1572275Y183834D03*
X1566990Y171523D03*
X1572385Y178560D03*
X1572448Y172665D03*
X1573261Y186629D03*
X1571795Y190185D03*
X1566520Y192490D03*
X1572565Y200864D03*
X1565475Y206767D03*
X1572654Y212455D03*
X1572588Y207037D03*
X1581194Y208864D03*
X1565605Y221708D03*
X1569955Y221642D03*
X1576835Y219379D03*
X1577463Y228631D03*
X1564771Y236189D03*
X1567271D03*
X1564712Y248765D03*
X1567212D03*
X1567709Y270695D03*
X1573869Y265897D03*
X1571369D03*
X1567709Y268195D03*
X1564909Y270695D03*
Y268195D03*
X1563877Y325363D03*
Y316363D03*
X1571625Y344131D03*
X1574775Y333549D03*
X1563877Y329863D03*
Y343363D03*
Y334363D03*
X1578587Y341787D03*
X1578420Y338309D03*
X1574775Y344127D03*
X1563877Y352363D03*
X1575935Y382109D03*
X1577862Y554121D03*
X1575934Y561420D03*
Y558917D03*
X1565323Y577716D03*
X1571755Y577937D03*
X1579760Y595500D03*
X1574760Y606929D03*
X1579260Y604567D03*
X1574720Y618400D03*
X1575001Y612592D03*
X1580418Y610072D03*
X1580354Y616317D03*
X1576297Y627600D03*
X1577077Y631712D03*
X1574880Y645891D03*
X1571888Y649380D03*
X1572141Y662981D03*
X1578000Y678776D03*
X1569434Y677111D03*
X1568872Y686971D03*
X1575192Y707592D03*
X1592187Y-79306D03*
Y-82706D03*
X1582187Y-43786D03*
Y-40386D03*
X1579968Y60438D03*
X1585649Y86012D03*
Y94374D03*
X1580790Y86046D03*
X1592955Y116594D03*
X1580986D03*
X1586929Y110784D03*
X1591929D03*
X1592955Y119594D03*
X1580986D03*
X1596489Y125107D03*
X1586486Y124879D03*
X1591508Y124663D03*
X1592852Y138838D03*
X1581162Y168665D03*
Y176665D03*
Y192665D03*
Y196665D03*
X1581275Y186778D03*
X1581194Y204864D03*
X1586243Y218085D03*
X1595622Y226320D03*
X1592843Y216385D03*
X1595556Y216970D03*
Y219470D03*
Y221970D03*
X1589043Y218085D03*
X1594190Y244571D03*
X1591570Y249108D03*
X1582951Y248371D03*
X1595069Y337361D03*
X1595109Y342663D03*
X1594466Y350984D03*
X1592635Y455911D03*
X1591443Y465332D03*
X1595460Y549800D03*
X1595260Y547075D03*
X1594760Y568000D03*
X1595364Y562800D03*
X1595300Y558800D03*
X1596790Y1442557D03*
X1592643Y1460707D03*
X1593019Y1457557D03*
X1591775Y1473090D03*
X1596038Y1492000D03*
X1591925Y1512075D03*
X1591333Y1501980D03*
X1590748Y1523377D03*
X1602572Y97667D03*
X1611032Y103411D03*
X1611426Y97667D03*
X1606822Y95111D03*
X1598228Y102495D03*
X1611191Y106561D03*
X1597962Y142862D03*
X1605103Y143762D03*
X1599003Y148717D03*
X1604051Y195176D03*
X1605569Y199248D03*
X1601551Y195176D03*
X1606551D03*
X1609051D03*
X1608569Y199248D03*
X1603405Y206806D03*
X1605905D03*
X1601632Y210509D03*
X1604132D03*
X1608569Y202048D03*
X1605569Y201748D03*
X1603324Y230556D03*
X1607579Y227824D03*
X1612169Y230117D03*
X1598583Y228646D03*
X1608185Y238714D03*
X1602309Y242078D03*
X1607666Y246874D03*
X1597540Y232971D03*
X1609886Y244297D03*
X1604677Y253198D03*
X1596691Y287397D03*
X1596197Y293477D03*
X1607947Y332326D03*
X1605966Y343794D03*
X1602138Y351047D03*
X1596253Y375633D03*
X1596534Y379760D03*
X1599527Y396718D03*
X1596760Y530000D03*
X1596260Y540500D03*
X1611316Y685800D03*
X1611027Y722427D03*
X1611327Y735973D03*
X1611627Y780327D03*
X1609500Y776100D03*
X1611873Y795127D03*
X1606190Y803774D03*
X1606709Y819165D03*
X1600333Y1440504D03*
X1596836Y1446488D03*
X1600333Y1449068D03*
X1601968Y1453442D03*
X1597457Y1460662D03*
X1605430Y1468023D03*
X1597039Y1475100D03*
X1599726Y1474990D03*
X1600008Y1488492D03*
X1601500Y1514500D03*
X1608500Y1506000D03*
Y1515000D03*
X1613790Y1531334D03*
X1609348Y1527334D03*
X1613790Y1523334D03*
X1604000Y1519000D03*
X1600732Y1539334D03*
X1609348Y1535334D03*
X1598574Y1543373D03*
X1622222Y90650D03*
X1627534Y90615D03*
X1621972Y95236D03*
X1626147Y351033D03*
X1628636Y422088D03*
X1623955Y442956D03*
X1625772Y438323D03*
X1621596Y456386D03*
X1625938Y445873D03*
X1620385Y465874D03*
X1616622Y546712D03*
Y542712D03*
X1618538Y618288D03*
X1614538D03*
X1627224Y643252D03*
X1613362Y656321D03*
X1621362D03*
X1617362D03*
X1616260Y678462D03*
X1619950Y678519D03*
X1615913Y692245D03*
X1628200Y711417D03*
X1612800Y705900D03*
X1620600D03*
X1620500Y723200D03*
X1628343Y747288D03*
X1616683Y744517D03*
X1620100Y738300D03*
X1624000Y760900D03*
X1612573Y761427D03*
X1628027Y801427D03*
X1613117Y828117D03*
X1640769Y85539D03*
Y82939D03*
Y75139D03*
Y80339D03*
Y77739D03*
X1640813Y92874D03*
X1631905Y95236D03*
X1631855Y99961D03*
X1642840Y104249D03*
Y107649D03*
X1639862Y162368D03*
X1642462D03*
X1641173Y213213D03*
Y210713D03*
Y208213D03*
X1630717Y210478D03*
Y215478D03*
Y212978D03*
Y207978D03*
X1641173Y215713D03*
X1634046Y264180D03*
X1636546D03*
X1633971Y258880D03*
X1642940Y267526D03*
Y270026D03*
X1629553Y329067D03*
X1629302Y334402D03*
X1640030Y335550D03*
X1636561Y343072D03*
X1629514Y331727D03*
X1630691Y347432D03*
X1640197Y374690D03*
X1638340Y379536D03*
X1641615Y379600D03*
X1635170Y442856D03*
X1632439Y452265D03*
X1633225Y458455D03*
X1636271Y453881D03*
X1635185Y446595D03*
X1635283Y728117D03*
X1630327Y774627D03*
X1629927Y787327D03*
X1644552Y871353D03*
X1635176Y886761D03*
X1644718Y909263D03*
X1635000Y919263D03*
X1644325Y942120D03*
X1637771Y952120D03*
X1640581Y1551907D03*
X1649094Y98551D03*
X1659648Y97475D03*
X1652644Y103783D03*
X1659579Y106186D03*
X1647406Y147540D03*
X1651178Y141247D03*
X1658645Y143740D03*
X1656025Y148277D03*
X1649562Y162793D03*
Y165393D03*
Y167993D03*
Y170493D03*
X1656486Y177616D03*
X1654565Y181009D03*
X1648559Y181426D03*
X1651770Y181366D03*
X1659740Y168697D03*
X1657067Y172190D03*
X1660828Y191941D03*
X1651384Y184012D03*
X1648767Y184221D03*
X1647745Y211695D03*
X1645245Y208695D03*
X1648045D03*
X1656506Y213132D03*
X1652803Y211359D03*
Y213859D03*
X1645245Y211695D03*
X1656506Y215632D03*
X1656750Y256303D03*
X1656509Y265896D03*
X1661525Y266114D03*
X1651422Y265701D03*
X1648240Y267526D03*
X1645740D03*
Y270026D03*
X1648240D03*
X1653057Y281716D03*
X1658998Y281982D03*
X1658200Y315039D03*
X1654771Y352088D03*
X1645685Y381500D03*
X1648835Y390500D03*
X1650044Y435158D03*
X1649789Y440489D03*
X1646209Y442606D03*
X1650087Y444841D03*
X1649773Y449961D03*
X1653490Y458572D03*
X1645826Y446606D03*
X1647133Y463479D03*
X1647604Y467367D03*
X1656112Y768669D03*
X1657042Y773604D03*
X1647402Y881460D03*
X1648375Y886766D03*
X1650205Y925911D03*
X1647763Y919268D03*
X1648387Y945554D03*
X1647470Y952125D03*
X1651443Y981515D03*
X1647565Y981432D03*
X1652944Y993796D03*
X1653414Y990590D03*
X1676870Y55513D03*
X1673095Y68581D03*
X1679470Y60513D03*
X1673108Y80581D03*
X1665190Y76587D03*
Y72615D03*
X1679598Y85731D03*
X1677238Y88801D03*
X1675291Y103621D03*
X1666629Y100625D03*
X1671002Y112083D03*
X1667208Y141247D03*
X1671695Y143518D03*
X1670795Y152373D03*
X1673945Y152562D03*
X1674637Y183834D03*
X1669352Y171523D03*
X1674810Y172665D03*
X1674747Y178560D03*
X1675623Y186629D03*
X1674157Y190185D03*
X1668882Y192490D03*
X1667318Y198828D03*
X1674927Y200864D03*
X1664840Y192300D03*
X1662837Y206767D03*
X1667837D03*
X1665337D03*
X1674950Y207037D03*
X1675016Y212455D03*
X1667967Y221708D03*
X1665467D03*
X1664082Y231021D03*
Y228221D03*
X1672317Y221642D03*
X1662967Y221708D03*
X1662382Y224421D03*
X1669633Y236189D03*
X1667133D03*
X1664633D03*
X1667074Y248765D03*
X1664574D03*
X1669574D03*
X1676231Y265897D03*
X1673731D03*
X1670071Y268195D03*
Y270695D03*
X1667271Y268195D03*
X1664771D03*
Y270695D03*
X1667271D03*
X1673203Y328867D03*
X1668979Y339559D03*
X1666860Y353661D03*
X1663650Y353283D03*
X1673723Y353881D03*
X1670323Y353534D03*
X1670260Y377912D03*
X1669260Y391496D03*
X1663618Y393858D03*
X1663780Y384410D03*
X1666959Y382047D03*
X1670260Y386500D03*
X1669260Y409000D03*
X1665260Y398583D03*
X1670348Y397912D03*
X1667260Y403500D03*
X1663713Y440869D03*
Y438269D03*
X1666513Y433069D03*
Y430469D03*
Y435669D03*
Y440869D03*
Y438269D03*
X1663713Y433069D03*
Y430469D03*
Y435669D03*
X1664567Y451677D03*
X1667067D03*
X1664567Y454177D03*
X1667067D03*
X1666271Y460218D03*
Y463618D03*
X1682330Y60438D03*
X1688011Y86012D03*
Y94374D03*
X1683152Y86046D03*
X1680155Y94351D03*
X1684104Y94279D03*
X1683348Y116594D03*
X1694291Y110784D03*
X1689291D03*
X1683348Y119594D03*
X1683782Y124283D03*
X1693870Y124663D03*
X1688848Y124879D03*
X1695214Y138838D03*
X1682189Y161306D03*
X1679440Y157370D03*
X1683524Y168665D03*
Y176665D03*
Y192665D03*
X1683637Y186778D03*
X1683556Y204864D03*
Y208864D03*
X1688605Y218085D03*
X1691405D03*
X1679197Y219379D03*
X1679825Y228631D03*
X1693932Y249108D03*
X1685313Y248371D03*
X1686339Y314890D03*
X1686115Y311740D03*
X1683523Y324518D03*
X1677810Y324466D03*
X1686408Y332584D03*
X1687424Y347937D03*
X1692676Y348015D03*
X1688593Y353470D03*
X1691182Y357016D03*
X1680518Y377912D03*
Y381912D03*
Y397912D03*
X1689920Y539315D03*
X1689236Y550137D03*
X1692028D03*
X1693000Y626912D03*
X1692379Y622912D03*
X1704934Y97667D03*
X1709184Y95111D03*
X1695317Y116594D03*
X1700590Y102495D03*
X1695317Y119594D03*
X1698851Y125107D03*
X1700324Y142862D03*
X1707465Y143762D03*
X1701365Y148717D03*
X1708913Y195176D03*
X1710931Y199248D03*
X1706413Y195176D03*
X1703913D03*
X1707931Y199248D03*
Y201748D03*
X1706494Y210509D03*
X1703994D03*
X1705767Y206806D03*
X1708267D03*
X1697984Y226320D03*
X1695205Y216385D03*
X1697918Y216970D03*
Y219470D03*
Y221970D03*
X1705686Y230556D03*
X1709941Y228747D03*
X1700945Y228646D03*
X1704671Y242078D03*
X1699902Y232971D03*
X1696552Y244571D03*
X1703895Y256394D03*
X1700223Y292141D03*
X1703609Y287320D03*
X1698292Y303962D03*
X1698716Y550065D03*
X1708015Y1142700D03*
X1711333Y1146609D03*
X1706450Y1173065D03*
X1703400Y1174400D03*
X1713394Y103411D03*
X1713788Y97667D03*
X1724584Y90650D03*
X1724334Y95236D03*
X1713553Y106561D03*
X1711413Y195176D03*
X1710931Y202048D03*
X1714531Y230117D03*
X1710547Y238714D03*
X1710028Y246874D03*
X1712248Y244297D03*
X1716755Y326179D03*
X1712226Y344028D03*
X1715930Y340969D03*
X1715590Y331719D03*
X1721746Y377173D03*
X1715228Y387966D03*
X1718851Y391533D03*
X1720571Y385644D03*
X1725746Y385123D03*
X1718318Y399918D03*
X1725154Y406060D03*
X1725415Y416289D03*
Y418889D03*
Y421489D03*
X1721423Y412106D03*
X1716310Y454334D03*
X1724627Y459330D03*
X1724580Y454214D03*
X1724923Y449045D03*
X1724930Y473571D03*
Y476071D03*
Y478571D03*
Y481071D03*
X1710174Y553101D03*
X1717626Y1134729D03*
X1710511Y1138130D03*
X1721008Y1134729D03*
X1723805Y1142666D03*
X1725008Y1134636D03*
X1725680Y1157544D03*
X1724191Y1167768D03*
X1713239Y1176038D03*
X1712526Y1171950D03*
X1728343Y1185205D03*
X1719692Y1187215D03*
X1719385Y1180175D03*
X1712715Y1188500D03*
X1721662Y1201043D03*
X1725658D03*
X1718625Y1199814D03*
X1712542Y1196600D03*
X1720536Y1217228D03*
X1723200Y1219895D03*
X1710825Y1231688D03*
X1712966Y1229841D03*
X1736405Y-79278D03*
Y-82678D03*
X1743175Y92874D03*
X1729896Y90615D03*
X1734267Y95236D03*
X1734217Y99961D03*
X1742224Y162368D03*
X1733079Y207978D03*
Y210478D03*
Y215478D03*
Y212978D03*
X1736408Y264180D03*
X1738908D03*
X1736333Y258880D03*
X1744524Y379429D03*
X1741746Y377173D03*
X1737786D03*
X1729751D03*
X1733746Y385123D03*
X1730746D03*
X1737746D03*
X1741420Y391569D03*
X1739847Y401066D03*
X1729508Y403300D03*
X1728915Y405889D03*
Y408489D03*
Y413689D03*
Y411089D03*
Y416289D03*
Y421489D03*
Y418889D03*
Y424089D03*
X1729302Y432718D03*
Y435518D03*
X1739179Y439318D03*
X1728915Y426689D03*
X1739179Y442118D03*
X1733014Y450091D03*
X1730014D03*
X1727404Y447209D03*
X1730404D03*
X1738824Y456034D03*
Y461034D03*
X1733014Y462060D03*
X1730014D03*
X1734952Y479217D03*
X1737646Y477213D03*
Y479713D03*
X1729002Y477053D03*
X1731502D03*
X1734952Y476717D03*
X1741800Y917900D03*
X1742029Y1116251D03*
X1739508Y1137129D03*
X1729008Y1134729D03*
X1732881D03*
X1739917Y1150087D03*
X1732137Y1157404D03*
X1737393Y1170767D03*
X1729210Y1167768D03*
X1728333Y1178240D03*
X1733052Y1187310D03*
X1737689Y1185238D03*
X1737482Y1180235D03*
X1733662Y1201039D03*
X1729628Y1201043D03*
X1737662Y1200969D03*
X1737781Y1208993D03*
X1726475Y1223170D03*
X1731533Y1228226D03*
X1729322Y1226016D03*
X1743131Y85539D03*
Y82939D03*
Y75139D03*
Y80339D03*
Y77739D03*
X1751456Y98551D03*
X1755006Y103783D03*
X1745202Y104249D03*
Y107649D03*
X1744824Y162368D03*
X1751924Y162793D03*
Y165393D03*
Y167993D03*
Y170493D03*
X1758848Y177616D03*
X1759429Y172190D03*
X1756927Y181009D03*
X1750921Y181426D03*
X1754132Y181366D03*
X1751129Y184221D03*
X1753746Y184012D03*
X1747607Y211695D03*
X1755165Y211359D03*
Y213859D03*
X1750107Y211695D03*
X1747607Y208695D03*
X1750407D03*
X1743535Y208213D03*
Y213213D03*
Y210713D03*
Y215713D03*
X1753784Y265701D03*
X1758871Y265896D03*
X1750602Y267526D03*
X1745302D03*
X1748102D03*
X1745302Y270026D03*
X1748102D03*
X1750602D03*
X1755419Y281716D03*
X1748497Y371060D03*
X1752497Y371076D03*
X1750135Y379088D03*
X1755433Y379028D03*
X1744180Y383966D03*
X1750187Y409539D03*
X1753187D03*
X1750187Y406739D03*
X1753187Y407039D03*
X1752851Y401981D03*
X1755351D03*
X1757124Y398278D03*
X1754624D03*
X1749470Y424067D03*
X1751970D03*
X1756970D03*
X1754470D03*
X1749705Y413611D03*
X1752205D03*
X1757205D03*
X1754705D03*
X1756844Y438293D03*
X1747179Y439318D03*
X1756844Y441093D03*
X1747179Y442118D03*
X1756844Y443893D03*
X1747306Y470001D03*
X1744806D03*
X1756894Y472020D03*
X1756553Y466409D03*
X1756954Y477318D03*
X1745231Y489036D03*
X1743092Y485580D03*
X1745592D03*
X1748092D03*
X1758401Y484882D03*
X1756391Y487382D03*
X1747467Y492836D03*
Y495636D03*
X1756089Y542952D03*
X1750879Y541940D03*
X1754906Y824333D03*
Y820737D03*
X1746897Y879199D03*
X1746884Y884649D03*
X1747900Y900160D03*
X1744900D03*
X1750915Y902055D03*
X1749267Y918413D03*
X1751200Y931100D03*
X1746600Y935100D03*
X1751854Y991297D03*
X1749314Y987904D03*
X1745824Y987058D03*
X1748677Y993986D03*
X1753860Y997271D03*
X1759569Y1021944D03*
X1744529Y1116251D03*
X1758390Y1577905D03*
X1759947Y1599029D03*
X1750685Y1621654D03*
X1767552Y76587D03*
Y72615D03*
X1762010Y97475D03*
X1768991Y100625D03*
X1761941Y106186D03*
X1773364Y112083D03*
X1771714Y171523D03*
X1776999Y183834D03*
X1762102Y168697D03*
X1763190Y191941D03*
X1771244Y192490D03*
X1776519Y190185D03*
X1767202Y192300D03*
X1765199Y206767D03*
X1770199D03*
X1767699D03*
X1758868Y213132D03*
X1765329Y221708D03*
X1770329D03*
X1767829D03*
X1764744Y224421D03*
X1766444Y231021D03*
Y228221D03*
X1774679Y221642D03*
X1758868Y215632D03*
X1771995Y236189D03*
X1769495D03*
X1766995D03*
X1771936Y248765D03*
X1769436D03*
X1766936D03*
X1759112Y256303D03*
X1763887Y266114D03*
X1767133Y270695D03*
X1769633D03*
X1772433Y268195D03*
Y270695D03*
X1769633Y268195D03*
X1767133D03*
X1761360Y281982D03*
X1762997Y377581D03*
X1765497Y379591D03*
X1772513Y387702D03*
X1769713D03*
X1765913Y389402D03*
X1763200Y388817D03*
Y383817D03*
Y386317D03*
X1766837Y438293D03*
Y441093D03*
Y443893D03*
X1768586Y467560D03*
X1764903Y470382D03*
X1764906Y474382D03*
X1776561Y467560D03*
X1777061Y475560D03*
X1768575D03*
X1770135Y490711D03*
X1758957Y543036D03*
X1773789Y927663D03*
X1765664Y923724D03*
X1769064D03*
X1773789Y930663D03*
X1774476Y995049D03*
X1773810Y990821D03*
X1762486Y990260D03*
X1760201Y992475D03*
X1758881Y995633D03*
X1769004Y1019395D03*
X1768844Y1023694D03*
Y1027248D03*
X1771773Y1028829D03*
X1772188Y1428369D03*
X1766313Y1580198D03*
X1761072Y1590719D03*
X1765040Y1599511D03*
X1760422Y1640303D03*
X1768422D03*
X1772422D03*
X1762041Y1631511D03*
X1768422Y1632245D03*
X1773820Y1631238D03*
X1779232Y55513D03*
X1775457Y68581D03*
X1785246Y60660D03*
X1781832Y60513D03*
X1775470Y80581D03*
X1781960Y85731D03*
X1790712Y81713D03*
X1790664Y71908D03*
X1779600Y88801D03*
X1790373Y94663D03*
X1786466Y85923D03*
Y94279D03*
X1782517Y94351D03*
X1777653Y103621D03*
X1785886Y168665D03*
Y176665D03*
X1777172Y172665D03*
X1777109Y178560D03*
X1777985Y186629D03*
X1785779Y192665D03*
X1785886Y196665D03*
X1777289Y200864D03*
X1785999Y186778D03*
X1785918Y204864D03*
X1777378Y212455D03*
X1777312Y207037D03*
X1785918Y208864D03*
X1781559Y219379D03*
X1782187Y228631D03*
X1778593Y265897D03*
X1776093D03*
X1787674Y303130D03*
X1777681Y387151D03*
Y382151D03*
Y384651D03*
X1786184Y435321D03*
Y438121D03*
X1783384Y435321D03*
Y438121D03*
X1786184Y440921D03*
X1783384D03*
X1786184Y443721D03*
X1783384D03*
X1786170Y448931D03*
X1792527Y452799D03*
X1786693Y459170D03*
X1790061Y474513D03*
X1779404Y826570D03*
X1791041Y818795D03*
X1780016Y874400D03*
X1775904Y924546D03*
X1778047Y916120D03*
X1789537Y930498D03*
X1780158Y953295D03*
X1785758Y956095D03*
Y953295D03*
X1782958D03*
Y956095D03*
X1780158D03*
X1789363Y969160D03*
X1782563Y979660D03*
X1785663D03*
X1779363D03*
X1786863Y985060D03*
X1779143Y995203D03*
X1779033Y1023432D03*
X1786740Y1019237D03*
X1780802Y1019474D03*
X1774863Y1019237D03*
X1774844Y1023694D03*
X1783844D03*
X1786844Y1027248D03*
X1780844D03*
X1774844D03*
X1789844Y1023694D03*
X1775998Y1074707D03*
Y1072207D03*
X1781198Y1074707D03*
X1778598D03*
X1783798D03*
Y1072207D03*
X1778598D03*
X1781198D03*
X1790736Y1072090D03*
Y1074590D03*
X1780326Y1089851D03*
X1777726D03*
X1782926D03*
Y1092351D03*
X1777726D03*
X1780326D03*
X1775126Y1089851D03*
Y1092351D03*
X1790639Y1082585D03*
X1790572Y1085152D03*
X1780662Y1108413D03*
X1783262D03*
X1778062D03*
X1775462D03*
X1785321Y1121122D03*
X1787921D03*
X1790521D03*
X1780566Y1111038D03*
X1783166D03*
X1777966D03*
X1775366D03*
X1790521Y1130822D03*
X1781874Y1139822D03*
X1787921Y1130822D03*
X1785321D03*
X1784374Y1139822D03*
X1781802Y1147822D03*
X1784302D03*
X1783278Y1208140D03*
X1778227Y1438099D03*
X1786091Y1443715D03*
X1787745Y1437765D03*
X1783178Y1437550D03*
X1778104Y1470289D03*
X1801761Y-43888D03*
Y-40488D03*
X1791088Y77296D03*
X1804758Y294429D03*
X1793524Y303343D03*
X1805196Y300952D03*
X1799897Y408104D03*
X1802697D03*
X1805497D03*
X1793475Y424939D03*
X1799614Y420375D03*
X1802414D03*
X1805214D03*
X1793475Y427439D03*
X1809095Y435101D03*
X1803700Y440101D03*
X1803530Y431112D03*
X1809358Y442114D03*
X1803335Y452718D03*
X1809346Y452601D03*
X1797907Y452987D03*
X1809338Y447121D03*
X1804933Y461607D03*
X1796933D03*
X1796136Y471334D03*
X1800933Y461607D03*
X1802000Y892447D03*
X1797365Y930761D03*
X1793474Y930374D03*
X1805463Y969260D03*
X1801963Y969160D03*
X1802363Y989660D03*
X1803351Y1027471D03*
X1805188Y1019078D03*
X1799646Y1018999D03*
X1793470Y1018762D03*
X1801844Y1023694D03*
X1795844D03*
X1798844Y1027248D03*
X1792844D03*
X1795936Y1072090D03*
X1793336D03*
X1798536D03*
Y1074590D03*
X1793336D03*
X1795936D03*
X1801961Y1081717D03*
X1795819Y1088553D03*
X1800813Y1103246D03*
X1806206Y1114589D03*
X1803506D03*
X1800906D03*
X1798306D03*
X1798702Y1124328D03*
X1801302D03*
X1803902D03*
X1806602D03*
X1793221Y1121122D03*
Y1130822D03*
X1804532Y1133356D03*
X1807232D03*
X1807035Y1136912D03*
Y1144912D03*
X1806835Y1214668D03*
X1800489Y1220598D03*
X1807243Y1219955D03*
X1802670Y1210905D03*
X1805126Y1225745D03*
X1799845Y1261044D03*
X1794845D03*
X1797345D03*
X1799845Y1263544D03*
X1797345D03*
X1794845D03*
X1803885Y1435046D03*
X1806428Y1444543D03*
X1795374D03*
X1802813Y1464015D03*
X1803762Y1467236D03*
X1819900Y906900D03*
X1807663Y966660D03*
Y963860D03*
X1808014Y984832D03*
X1812538Y1026859D03*
X1811468Y1021084D03*
X1807844Y1023694D03*
Y1027248D03*
X1810349Y1031264D03*
X1816756Y1089145D03*
Y1094145D03*
X1816235Y1083970D03*
X1810346Y1082250D03*
X1816756Y1097145D03*
Y1101145D03*
X1810310Y1104819D03*
X1809535Y1136912D03*
Y1144912D03*
X1812130Y1205349D03*
X1822594Y1211054D03*
Y1215324D03*
X1814741Y1217093D03*
X1811482Y1226423D03*
X1810018Y1295944D03*
X1812818D03*
X1815618Y1298744D03*
Y1295944D03*
X1812818Y1298744D03*
X1810018D03*
X1812202Y1432624D03*
X1809342Y1476733D03*
X1824706Y1085145D03*
X1824949Y1077145D03*
X1824706Y1100185D03*
Y1106145D03*
X1828272Y1095968D03*
X1824706Y1093150D03*
X1830915Y1109146D03*
X1834665Y1213239D03*
G54D23*
X51750Y617861D03*
X48207D03*
X44664D03*
X51750Y620661D03*
X48207D03*
X44664D03*
X55294Y617861D03*
Y620661D03*
X146948Y1088287D03*
X143208D03*
X146948Y1099507D03*
X143208D03*
X146948Y1106988D03*
X143208D03*
X146948Y1114468D03*
Y1121948D03*
X143208Y1114468D03*
Y1121948D03*
X146948Y1129429D03*
X143208D03*
X146948Y1148129D03*
X143208D03*
X146947Y1170570D03*
X143207D03*
X146947Y1178051D03*
X143207D03*
X165649Y1073326D03*
X158169D03*
X150689D03*
X165649Y1092027D03*
X158169D03*
X150689D03*
X165649Y1077066D03*
X161909Y1084547D03*
X158169Y1077066D03*
X154429Y1084547D03*
X161909Y1080807D03*
X154429D03*
X165649Y1095767D03*
X161909Y1103247D03*
X158169Y1095767D03*
X154429Y1103247D03*
X150689Y1095767D03*
X161909Y1099507D03*
X154429D03*
X161909Y1118208D03*
Y1121948D03*
X165649Y1110728D03*
X161909D03*
X154429D03*
Y1118208D03*
X150689Y1110728D03*
Y1118208D03*
X154429Y1125688D03*
X150689D03*
X165649Y1148129D03*
Y1144389D03*
Y1155610D03*
X160039Y1176180D03*
X156299D03*
X169389Y1084547D03*
Y1080807D03*
Y1103247D03*
X176870Y1151870D03*
Y1148129D03*
Y1144389D03*
X169389Y1151870D03*
Y1148129D03*
X176870Y1166830D03*
Y1159350D03*
X169389D03*
X176870Y1174310D03*
Y1178051D03*
Y1181791D03*
X188090Y1114468D03*
X184350D03*
X191830D03*
X195570D03*
X191830Y1140649D03*
Y1136909D03*
X195570Y1140649D03*
X184350Y1136909D03*
X191830Y1133169D03*
Y1129429D03*
Y1144389D03*
Y1151869D03*
X195570Y1148129D03*
Y1155610D03*
X184350Y1144389D03*
X188090Y1155610D03*
X184350Y1151870D03*
X188090Y1148129D03*
X191830Y1159350D03*
Y1170570D03*
X195570Y1166830D03*
X184350Y1159350D03*
Y1170570D03*
X188090Y1166830D03*
X191830Y1185531D03*
Y1178051D03*
X195570Y1181791D03*
Y1174310D03*
X184350Y1185531D03*
X188090Y1181791D03*
Y1174310D03*
X184350Y1178051D03*
X191830Y1193011D03*
X195570Y1215452D03*
X197440Y1217322D03*
X186220D03*
X189960D03*
Y1213582D03*
X203051Y1114468D03*
X199311D03*
X206791D03*
X210531D03*
X206791Y1136909D03*
X203051D03*
X199311D03*
X214271D03*
X210531D03*
X199311Y1129429D03*
X206791D03*
X214271D03*
X210531D03*
X203051D03*
X210531Y1155610D03*
X203051D03*
X206791Y1144389D03*
X203051D03*
X199311D03*
X214271D03*
X210531D03*
X214271Y1151870D03*
X210531D03*
X206791D03*
X203051D03*
X199311D03*
X214271Y1170570D03*
X210531Y1166830D03*
X214271Y1159350D03*
X206791Y1170570D03*
X203051Y1166830D03*
X199311Y1170570D03*
X206791Y1159350D03*
X199311D03*
X203051Y1174310D03*
X210531D03*
X203051Y1185531D03*
X199311D03*
X206791D03*
X214271D03*
X210531D03*
X206791Y1178051D03*
X203051D03*
X199311D03*
X214271D03*
X210531D03*
X214271Y1193011D03*
X210531D03*
X199311D03*
X203051D03*
X206791D03*
X214271Y1200491D03*
X210531D03*
X199311D03*
X206791D03*
X203051D03*
X201181Y1213582D03*
X214271Y1211712D03*
X208661Y1213582D03*
X203051Y1215452D03*
X214271D03*
X201181Y1217322D03*
X208661D03*
X210531Y1215452D03*
X204921Y1213582D03*
X225492Y1114468D03*
X221752D03*
X218011D03*
X225492Y1136909D03*
X221751D03*
X218011D03*
X229232D03*
Y1129429D03*
X218011D03*
X221751D03*
X225492D03*
X218011Y1155610D03*
X225492D03*
Y1144389D03*
X221751D03*
X218011D03*
X229232D03*
Y1151870D03*
X221752D03*
X218011D03*
X225492D03*
Y1166830D03*
X221751Y1170570D03*
X218011Y1166830D03*
X221751Y1159350D03*
X229232Y1170570D03*
Y1159350D03*
X225492Y1174310D03*
X218011D03*
X225492Y1185531D03*
X218011D03*
X221751D03*
X229232D03*
X225492Y1178051D03*
X221751D03*
X218011D03*
X229232D03*
X218011Y1193011D03*
X221751D03*
X225492D03*
X229232D03*
X218011Y1200491D03*
X221751D03*
X225492D03*
X229232D03*
X218011Y1215452D03*
X229232Y1211712D03*
Y1215452D03*
X225492Y1211712D03*
X221752D03*
Y1215452D03*
X240452Y1114468D03*
X244192D03*
X236712Y1118208D03*
X244192D03*
X236712Y1114468D03*
X240452Y1118208D03*
Y1136909D03*
X236712D03*
X244192D03*
Y1129429D03*
X240452D03*
X236712D03*
Y1155610D03*
X244192D03*
X240452Y1151869D03*
X236712D03*
X244192D03*
X240452Y1144389D03*
X236712D03*
X244192D03*
X236712Y1166830D03*
X240452Y1170570D03*
Y1159350D03*
X244192Y1166830D03*
X236712Y1174310D03*
X244192D03*
X240452Y1185531D03*
X236712D03*
X244192D03*
X240452Y1178051D03*
X236712D03*
X244192D03*
X240452Y1193011D03*
X236712D03*
X244192D03*
X236712Y1200491D03*
X244192D03*
X240452D03*
X244192Y1215452D03*
X240452D03*
X242322Y1217322D03*
X236712Y1211712D03*
Y1215452D03*
X238582Y1217322D03*
X262893Y1118208D03*
X259153Y1114468D03*
X262893D03*
X255413Y1118208D03*
Y1114468D03*
X247933D03*
X259153Y1118208D03*
X251673Y1114468D03*
X247933Y1118208D03*
X251673D03*
X255413Y1136909D03*
X251673D03*
X247933D03*
X259153D03*
X262893D03*
X247933Y1129429D03*
X259153D03*
X262893D03*
X255413D03*
X251673D03*
Y1155610D03*
X259153D03*
X251673Y1144389D03*
X247933D03*
X255413D03*
X259153Y1151869D03*
X262893D03*
X247933D03*
X255413D03*
X251673D03*
X262893Y1144389D03*
X259153D03*
X251673Y1166830D03*
X255413Y1170570D03*
X247933D03*
X255413Y1159350D03*
X247933D03*
X259153Y1166830D03*
X262893Y1170570D03*
Y1159350D03*
X251673Y1174310D03*
X259153D03*
X247933Y1185531D03*
X255413D03*
X251673D03*
X259153D03*
X262893D03*
X251673Y1178051D03*
X247933D03*
X255413D03*
X259153D03*
X262893D03*
X251673Y1193011D03*
X255413D03*
X247933D03*
X262893D03*
X259153D03*
Y1200491D03*
X262893D03*
X251673D03*
X247933D03*
X255413D03*
Y1215452D03*
X262893D03*
X247932Y1215451D03*
X259153Y1215452D03*
X251673D03*
X247932Y1211711D03*
X251673D03*
X270373Y1114468D03*
X274114D03*
X277854D03*
X266633Y1136909D03*
Y1129429D03*
X274114D03*
Y1140649D03*
Y1136909D03*
X266633Y1155610D03*
X277854D03*
X266633Y1151869D03*
Y1144389D03*
X274114D03*
X277854Y1159350D03*
Y1166830D03*
Y1170570D03*
X266633D03*
X270373D03*
X266633Y1159350D03*
X270373D03*
Y1166830D03*
X266633D03*
Y1174310D03*
X277854D03*
X266633Y1185531D03*
Y1178051D03*
X270373Y1181791D03*
X274114Y1185531D03*
Y1189271D03*
Y1178051D03*
X266633Y1193011D03*
Y1200491D03*
X274114D03*
Y1193011D03*
X277854Y1204232D03*
Y1196751D03*
Y1200491D03*
X274114Y1215452D03*
X277854D03*
X266633D03*
X274114Y1211712D03*
X277854Y1207972D03*
X285334Y1118208D03*
X281594D03*
X285334Y1114468D03*
X281594D03*
X289074Y1140649D03*
X285334D03*
Y1136909D03*
X292815Y1140649D03*
X285334Y1155610D03*
X281594Y1144389D03*
X285334Y1148129D03*
Y1144389D03*
X289074Y1148129D03*
X292815D03*
Y1155610D03*
X285334Y1170570D03*
Y1166830D03*
Y1159350D03*
X292815Y1170570D03*
X285334Y1174310D03*
X289074Y1189271D03*
X285334D03*
X281594Y1181791D03*
X285334Y1178051D03*
X289074Y1181791D03*
X285334Y1196751D03*
Y1204232D03*
X281594Y1200491D03*
X285334D03*
Y1207972D03*
Y1215452D03*
Y1211712D03*
X281594Y1215452D03*
Y1207972D03*
X311515Y1140649D03*
X304035Y1144389D03*
Y1151869D03*
X307775Y1144389D03*
Y1151869D03*
X296555Y1155610D03*
X311515Y1148129D03*
Y1155610D03*
X304035Y1166830D03*
Y1159350D03*
X307775Y1166830D03*
X296555Y1170570D03*
X311515D03*
X304035Y1174310D03*
Y1181791D03*
Y1189271D03*
X307775Y1174310D03*
Y1181791D03*
Y1189271D03*
X311515Y1178051D03*
Y1185531D03*
Y1193011D03*
X322736Y1136909D03*
X326476D03*
X315255Y1140649D03*
X322736Y1144389D03*
Y1151870D03*
X326476Y1144389D03*
X315255Y1148129D03*
X326476Y1151870D03*
X315255Y1155610D03*
X322736Y1159350D03*
X326476D03*
X315255Y1170570D03*
X322736Y1174310D03*
Y1181791D03*
Y1189271D03*
X326476Y1174310D03*
X315255Y1178051D03*
X326476Y1181791D03*
X315255Y1185531D03*
X326476Y1189271D03*
X315255Y1193011D03*
X425023Y441086D03*
Y433999D03*
Y437543D03*
X422223Y441086D03*
Y433999D03*
Y437543D03*
X425023Y444629D03*
X422223D03*
X501750Y620661D03*
X505293D03*
X501750Y617861D03*
X505293D03*
X512380D03*
X508836Y620661D03*
Y617861D03*
X512380Y620661D03*
X600295Y1088287D03*
X604035D03*
X600295Y1099507D03*
X604035D03*
X600295Y1106988D03*
X604035D03*
Y1121948D03*
X600295D03*
Y1114468D03*
X604035D03*
X600295Y1136909D03*
X604035D03*
X600295Y1129429D03*
X604035D03*
Y1148129D03*
X600295D03*
X604034Y1170570D03*
X600294D03*
X604034Y1178051D03*
X600294D03*
X615256Y1073326D03*
X607776D03*
X618996Y1084547D03*
Y1080807D03*
X615256Y1077066D03*
X611516Y1080807D03*
Y1084547D03*
X607776Y1092027D03*
X615256D03*
X607776Y1095767D03*
X615256D03*
X618996Y1103247D03*
X611516D03*
X618996Y1099507D03*
X611516D03*
X618996Y1118208D03*
Y1121948D03*
X611516Y1118208D03*
X607776D03*
X611516Y1110728D03*
X618996D03*
X607776D03*
X611516Y1125688D03*
X607776D03*
Y1133169D03*
X615256Y1178051D03*
X611516D03*
X622736Y1073326D03*
Y1077066D03*
X626476Y1084547D03*
X622736Y1092027D03*
X626476Y1080807D03*
X622736Y1095767D03*
X626476Y1103247D03*
X622736Y1118208D03*
X626476Y1114468D03*
X622736Y1110728D03*
X630216Y1114468D03*
X633957Y1151870D03*
Y1148129D03*
Y1144389D03*
X626476Y1148129D03*
X622736Y1144389D03*
Y1148129D03*
X626476Y1151870D03*
X622736Y1155610D03*
X633957Y1166830D03*
Y1159350D03*
X626476D03*
X633957Y1174310D03*
Y1178051D03*
Y1181791D03*
X645177Y1114468D03*
X641437D03*
X648917D03*
X652657D03*
X648917Y1140649D03*
Y1136909D03*
X652657Y1140649D03*
X641437Y1136909D03*
X648917Y1129429D03*
Y1133169D03*
X652657Y1148129D03*
Y1155610D03*
X648917Y1144389D03*
Y1151869D03*
X641437Y1144389D03*
Y1151870D03*
X645177Y1155610D03*
Y1148129D03*
X648917Y1159350D03*
Y1170570D03*
X652657Y1166830D03*
X641437Y1170570D03*
X645177Y1166830D03*
X641437Y1159350D03*
X648917Y1185531D03*
Y1178051D03*
X652657Y1181791D03*
Y1174310D03*
X641437Y1185531D03*
Y1178051D03*
X645177Y1181791D03*
Y1174310D03*
X648917Y1193011D03*
X652657Y1215452D03*
Y1219192D03*
X641437Y1215452D03*
X648917D03*
X645177D03*
X660138Y1114468D03*
X656398D03*
X663878D03*
X667618D03*
Y1129429D03*
X660138D03*
X656398D03*
X663878D03*
Y1136909D03*
X660138D03*
X656398D03*
X667618D03*
X660138Y1155610D03*
X667618D03*
Y1144389D03*
X663878D03*
X660138D03*
X656398D03*
X667618Y1151870D03*
X663878D03*
X660138D03*
X656398D03*
X663878Y1170570D03*
X660138Y1166830D03*
X656398Y1170570D03*
X663878Y1159350D03*
X656398D03*
X667618Y1166830D03*
Y1174310D03*
X660138D03*
X667618Y1185531D03*
X660138D03*
X656398D03*
X663878D03*
X667618Y1178051D03*
X663878D03*
X660138D03*
X656398D03*
X667618Y1200491D03*
X656398D03*
X663878D03*
X660138D03*
X663878Y1193011D03*
X660138D03*
X656398D03*
X667618D03*
X663878Y1211712D03*
X656398D03*
X660138Y1215452D03*
X656398D03*
X663878D03*
X667618D03*
X660138Y1211712D03*
X682579Y1114468D03*
X678839D03*
X675098D03*
Y1129429D03*
X671358D03*
X678838D03*
X682579D03*
Y1136909D03*
X678838D03*
X675098D03*
X671358D03*
X682579Y1155610D03*
X675098D03*
X678839Y1151870D03*
X675098D03*
X671358D03*
X682579D03*
Y1144389D03*
X671358D03*
X678838D03*
X675098D03*
X682579Y1166830D03*
X678838Y1170570D03*
X671358D03*
X675098Y1166830D03*
X671358Y1159350D03*
X678838D03*
X682579Y1174310D03*
X675098D03*
X682579Y1185531D03*
X675098D03*
X671358D03*
X678838D03*
X682579Y1178051D03*
X678838D03*
X675098D03*
X671358D03*
X675098Y1200491D03*
X671358D03*
X678838D03*
X682579D03*
Y1193011D03*
X678838D03*
X675098D03*
X671358D03*
X682579Y1211712D03*
X678839D03*
Y1215452D03*
X671358Y1211712D03*
Y1215452D03*
X675098D03*
X693799Y1114468D03*
Y1118208D03*
X701279Y1114468D03*
X697539Y1118208D03*
Y1114468D03*
X701279Y1118208D03*
Y1129429D03*
X697539D03*
X693799D03*
X686319D03*
X697539Y1136909D03*
X693799D03*
X701279D03*
X686319D03*
X701279Y1155610D03*
X693799D03*
X701279Y1151869D03*
X697539D03*
X693799D03*
X701279Y1144389D03*
X697539D03*
X693799D03*
X686319D03*
Y1151870D03*
X693799Y1166830D03*
X697539Y1170570D03*
Y1159350D03*
X701279Y1166830D03*
X686319Y1170570D03*
Y1159350D03*
X701279Y1174310D03*
X693799D03*
X701279Y1185531D03*
X697539D03*
X693799D03*
X701279Y1178051D03*
X697539D03*
X693799D03*
X686319Y1185531D03*
Y1178051D03*
X701279Y1200491D03*
X697539D03*
X693799D03*
X686319D03*
X701279Y1193011D03*
X697539D03*
X693799D03*
X686319D03*
Y1211712D03*
Y1215452D03*
X699409Y1217322D03*
X697539Y1215452D03*
X693799D03*
Y1211712D03*
X701279Y1215452D03*
X695669Y1217322D03*
X708760Y1114468D03*
X716240Y1118208D03*
X705020Y1114468D03*
X712500D03*
X716240D03*
X705020Y1118208D03*
X712500D03*
X708760D03*
X705020Y1129429D03*
X708760D03*
X712500D03*
X716240D03*
Y1136909D03*
X705020D03*
X708760D03*
X712500D03*
X708760Y1155610D03*
X716240D03*
Y1151869D03*
X708760D03*
X712500D03*
X705020D03*
X712500Y1144389D03*
X705020D03*
X708760D03*
X716240D03*
Y1166830D03*
X705020Y1159350D03*
X712500D03*
X705020Y1170570D03*
X712500D03*
X708760Y1166830D03*
X716240Y1174310D03*
X708760D03*
X716240Y1185531D03*
X708760D03*
X712500D03*
X705020D03*
X716240Y1178051D03*
X712500D03*
X705020D03*
X708760D03*
X712500Y1200491D03*
X705020D03*
X708760D03*
X716240D03*
X708760Y1193011D03*
X712500D03*
X705020D03*
X716240D03*
Y1215452D03*
X708760D03*
X712500D03*
X705019Y1215451D03*
Y1211711D03*
X708760D03*
X731201Y1114468D03*
X734941D03*
X727460D03*
X719980Y1118208D03*
Y1114468D03*
Y1129429D03*
X723720D03*
X731201D03*
X719980Y1136909D03*
X723720D03*
X731201D03*
Y1140649D03*
X723720Y1155610D03*
X719980Y1151869D03*
X723720D03*
Y1144389D03*
X719980D03*
X734941Y1155610D03*
X731201Y1144389D03*
X719980Y1159350D03*
X727460D03*
X723720D03*
Y1166830D03*
X727460D03*
X719980Y1170570D03*
X727460D03*
X723720D03*
X734941Y1159350D03*
Y1166830D03*
Y1170570D03*
X723720Y1174310D03*
X727460Y1181791D03*
X719980Y1185531D03*
Y1178051D03*
X723720D03*
Y1185531D03*
X734941Y1174310D03*
X731201Y1189271D03*
Y1185531D03*
Y1178051D03*
X719980Y1200491D03*
X723720D03*
X731201D03*
X719980Y1193011D03*
X723720D03*
X731201D03*
X734941Y1196751D03*
Y1204232D03*
Y1200491D03*
X731201Y1215452D03*
X734941D03*
X723720D03*
X719980D03*
X731201Y1211712D03*
X734941Y1207972D03*
X727461Y1215452D03*
X738681Y1118208D03*
X742421D03*
X738681Y1114468D03*
X742421D03*
Y1140649D03*
Y1136909D03*
X746161Y1140649D03*
X749902D03*
X742421Y1155610D03*
X746161Y1148129D03*
X738681Y1144389D03*
X742421Y1148129D03*
Y1144389D03*
X749902Y1155610D03*
Y1148129D03*
X742421Y1159350D03*
Y1166830D03*
Y1170570D03*
X749902D03*
X742421Y1189271D03*
X746161D03*
X742421Y1174310D03*
X738681Y1181791D03*
X746161D03*
X742421Y1178051D03*
Y1196751D03*
X738681Y1200491D03*
X742421Y1204232D03*
Y1200491D03*
Y1211712D03*
Y1215452D03*
Y1207972D03*
X738681Y1215452D03*
Y1207972D03*
Y1211712D03*
X761122Y1144389D03*
Y1151869D03*
X753642Y1155610D03*
X764862Y1151869D03*
Y1144389D03*
Y1166830D03*
X761122D03*
Y1159350D03*
X753642Y1170570D03*
X764862Y1174310D03*
X761122Y1181791D03*
X764862D03*
X761122Y1174310D03*
X768602Y1140649D03*
X772342D03*
Y1148129D03*
Y1155610D03*
X783563Y1151870D03*
X779823D03*
Y1144389D03*
X783563D03*
X768602Y1155610D03*
Y1148129D03*
X779823Y1159350D03*
X772342Y1170570D03*
X768602D03*
X783563Y1159350D03*
Y1189271D03*
X768602Y1185531D03*
X772342Y1178051D03*
X779823Y1189271D03*
X772342Y1185531D03*
X783563Y1174310D03*
X779823D03*
X783563Y1181791D03*
X768602Y1178051D03*
X779823Y1181791D03*
X768602Y1193011D03*
X772342D03*
X920349Y450340D03*
X917549D03*
X920349Y453884D03*
Y457427D03*
X917549Y453884D03*
Y457427D03*
X920349Y460970D03*
X917549D03*
X962380Y617861D03*
X958837D03*
X962380Y620661D03*
X958837D03*
X969467D03*
X965923Y617861D03*
Y620661D03*
X969467Y617861D03*
X1057381Y1088287D03*
Y1106988D03*
Y1099507D03*
Y1114468D03*
Y1121948D03*
Y1129429D03*
Y1136909D03*
Y1148129D03*
X1057380Y1170570D03*
Y1178051D03*
X1072342Y1073326D03*
X1064862D03*
Y1092027D03*
X1072342Y1077066D03*
X1068602Y1084547D03*
Y1080807D03*
X1061121Y1088287D03*
X1072342Y1092027D03*
X1068602Y1099507D03*
X1072342Y1095767D03*
X1061121Y1106988D03*
X1068602Y1103247D03*
X1064862Y1095767D03*
X1061121Y1099507D03*
Y1114468D03*
X1068602Y1110728D03*
Y1118208D03*
X1064862Y1110728D03*
Y1118208D03*
X1061121Y1121948D03*
X1064862Y1125688D03*
X1068602D03*
X1061121Y1129429D03*
X1064862Y1133169D03*
X1061121Y1136909D03*
Y1148129D03*
X1061120Y1170570D03*
X1072342Y1178051D03*
X1068602D03*
X1061120D03*
X1079822Y1073326D03*
Y1092027D03*
X1083562Y1084547D03*
X1079822Y1077066D03*
X1076082Y1084547D03*
Y1080807D03*
X1083562D03*
X1076082Y1103247D03*
X1079822Y1095767D03*
X1076082Y1099507D03*
X1083562Y1103247D03*
X1079822Y1118208D03*
X1076082Y1121948D03*
Y1118208D03*
X1079822Y1110728D03*
X1083562Y1114468D03*
X1087302D03*
X1076082Y1110728D03*
X1091043Y1151870D03*
Y1148129D03*
Y1144389D03*
X1083562Y1148129D03*
X1079822Y1144389D03*
Y1148129D03*
X1083562Y1151870D03*
X1079822Y1155610D03*
X1091043Y1166830D03*
Y1159350D03*
X1083562D03*
X1091043Y1181791D03*
Y1178051D03*
Y1174310D03*
X1102263Y1114468D03*
X1098523D03*
X1106003D03*
Y1140649D03*
Y1136909D03*
X1098523D03*
X1106003Y1129429D03*
Y1133169D03*
Y1151869D03*
Y1144389D03*
X1098523D03*
Y1151870D03*
X1102263Y1148129D03*
Y1155610D03*
X1106003Y1170570D03*
Y1159350D03*
X1102263Y1166830D03*
X1098523Y1159350D03*
Y1170570D03*
X1106003Y1178051D03*
Y1185531D03*
X1098523D03*
X1102263Y1174310D03*
X1098523Y1178051D03*
X1102263Y1181791D03*
X1106003Y1193011D03*
Y1215452D03*
X1098523D03*
X1102263D03*
X1117224Y1114468D03*
X1113484D03*
X1120964D03*
X1124704D03*
X1109743D03*
X1120964Y1129429D03*
X1113484D03*
X1117224D03*
X1124704D03*
Y1136909D03*
X1113484D03*
X1117224D03*
X1120964D03*
X1109743Y1140649D03*
X1124704Y1144389D03*
X1113484D03*
X1117224D03*
X1120964D03*
X1113484Y1151870D03*
X1117224D03*
X1120964D03*
X1124704D03*
Y1155610D03*
X1109743D03*
Y1148129D03*
X1117224Y1155610D03*
X1113484Y1159350D03*
X1120964D03*
X1109743Y1166830D03*
X1113484Y1170570D03*
X1117224Y1166830D03*
X1120964Y1170570D03*
X1124704Y1166830D03*
X1113484Y1178051D03*
X1117224D03*
X1120964D03*
X1124704D03*
X1120964Y1185531D03*
X1113484D03*
X1117224D03*
X1124704D03*
X1109743Y1174310D03*
Y1181791D03*
X1117224Y1174310D03*
X1124704D03*
X1117224Y1200491D03*
X1120964D03*
X1113484D03*
X1124704D03*
X1120964Y1193011D03*
X1117224D03*
X1113484D03*
X1124704D03*
Y1215452D03*
X1120964D03*
Y1211712D03*
X1117224Y1215452D03*
X1109743D03*
X1113484Y1211712D03*
X1111613Y1217322D03*
X1115354D03*
X1117224Y1211712D03*
X1139665Y1114468D03*
X1135925D03*
X1132184D03*
Y1129429D03*
X1128444D03*
X1135924D03*
X1139665D03*
Y1136909D03*
X1135924D03*
X1132184D03*
X1128444D03*
Y1144389D03*
X1135924D03*
X1132184D03*
X1139665D03*
X1135925Y1151870D03*
X1132184D03*
X1128444D03*
X1139665D03*
Y1155610D03*
X1132184D03*
X1139665Y1166830D03*
X1135924Y1170570D03*
X1128444D03*
X1132184Y1166830D03*
X1128444Y1159350D03*
X1135924D03*
X1139665Y1178051D03*
X1135924D03*
X1132184D03*
X1128444D03*
X1139665Y1185531D03*
X1132184D03*
X1128444D03*
X1135924D03*
X1139665Y1174310D03*
X1132184D03*
Y1200491D03*
X1128444D03*
X1135924D03*
X1139665D03*
X1128444Y1193011D03*
X1132184D03*
X1135924D03*
X1139665D03*
Y1211712D03*
X1135925D03*
Y1215452D03*
X1128444D03*
X1132184D03*
X1128444Y1211712D03*
X1154625Y1118208D03*
X1150885D03*
X1154625Y1114468D03*
X1150885D03*
X1154625Y1129429D03*
X1150885D03*
X1143405D03*
Y1136909D03*
X1154625D03*
X1150885D03*
X1143405Y1144389D03*
X1150885Y1151869D03*
X1154625D03*
Y1144389D03*
X1150885D03*
X1143405Y1151870D03*
X1150885Y1155610D03*
X1143405Y1170570D03*
X1154625Y1159350D03*
X1143405D03*
X1150885Y1166830D03*
X1154625Y1170570D03*
X1143405Y1178051D03*
Y1185531D03*
X1154625D03*
X1150885D03*
X1154625Y1178051D03*
X1150885D03*
Y1174310D03*
X1143405Y1200491D03*
X1154625D03*
X1150885D03*
Y1193011D03*
X1154625D03*
X1143405D03*
Y1211712D03*
Y1215452D03*
X1150885Y1211712D03*
Y1215452D03*
X1154625D03*
X1156495Y1217322D03*
X1152755D03*
X1162106Y1114468D03*
X1169586D03*
X1162106Y1118208D03*
X1173326Y1114468D03*
X1158365Y1118208D03*
X1173326D03*
X1165846Y1114468D03*
X1158365D03*
X1169586Y1118208D03*
X1165846D03*
X1169586Y1129429D03*
X1165846D03*
X1162106D03*
X1158365D03*
X1173326D03*
Y1136909D03*
X1169586D03*
X1165846D03*
X1158365D03*
X1162106D03*
X1173326Y1151869D03*
X1158365D03*
X1162106D03*
X1169586D03*
X1165846D03*
X1173326Y1144389D03*
X1165846D03*
X1158365D03*
X1162106D03*
X1169586D03*
X1173326Y1155610D03*
X1165846D03*
X1158365D03*
X1173326Y1166830D03*
X1165846D03*
X1169586Y1170570D03*
X1158365Y1166830D03*
X1162106Y1170570D03*
X1169586Y1159350D03*
X1162106D03*
X1158365Y1185531D03*
X1162106D03*
X1169586D03*
X1165846D03*
X1173326D03*
X1165846Y1178051D03*
X1158365D03*
X1162106D03*
X1169586D03*
X1173326D03*
X1165846Y1174310D03*
X1158365D03*
X1173326D03*
Y1200491D03*
X1165846D03*
X1162106D03*
X1158365D03*
X1169586D03*
X1165846Y1193011D03*
X1169586D03*
X1158365D03*
X1162106D03*
X1173326D03*
Y1215452D03*
X1165846D03*
X1169586D03*
X1162105Y1215451D03*
X1158365Y1215452D03*
X1162105Y1211711D03*
X1165846D03*
X1188287Y1114468D03*
X1177066D03*
Y1118208D03*
X1184546Y1114468D03*
X1180806Y1129429D03*
X1177066D03*
X1188287D03*
X1180806Y1136909D03*
X1177066D03*
X1188287D03*
Y1140649D03*
X1180806Y1151869D03*
X1177066D03*
Y1144389D03*
X1180806D03*
Y1155610D03*
X1188287Y1144389D03*
X1180806Y1170570D03*
X1184546D03*
X1177066D03*
X1184546Y1166830D03*
X1180806D03*
X1177066Y1159350D03*
X1180806D03*
X1184546D03*
X1177066Y1185531D03*
Y1178051D03*
X1180806Y1185531D03*
Y1178051D03*
Y1174310D03*
X1184546Y1181791D03*
X1188287Y1185531D03*
Y1189271D03*
Y1178051D03*
X1180806Y1200491D03*
X1177066D03*
X1188287D03*
X1177066Y1193011D03*
X1180806D03*
X1188287D03*
Y1215452D03*
X1180806D03*
X1177066D03*
X1188287Y1211712D03*
X1199507Y1118208D03*
X1195767D03*
Y1114468D03*
X1192027D03*
X1199507D03*
Y1140649D03*
Y1136909D03*
X1203247Y1140649D03*
X1199507Y1155610D03*
X1192027D03*
X1203247Y1148129D03*
X1195767Y1144389D03*
X1199507Y1148129D03*
Y1144389D03*
Y1170570D03*
Y1166830D03*
Y1159350D03*
X1192027Y1166830D03*
Y1170570D03*
Y1159350D03*
X1203247Y1189271D03*
X1199507D03*
Y1174310D03*
X1195767Y1181791D03*
X1192027Y1174310D03*
X1199507Y1178051D03*
X1203247Y1181791D03*
X1199507Y1196751D03*
Y1204232D03*
X1195767Y1200491D03*
X1192027Y1196751D03*
Y1200491D03*
Y1204232D03*
X1199507Y1200491D03*
X1192027Y1215452D03*
X1199507Y1211712D03*
Y1215452D03*
Y1207972D03*
X1195767Y1215452D03*
X1192027Y1207972D03*
X1195767D03*
Y1211712D03*
X1206988Y1140649D03*
X1218208Y1144389D03*
Y1151869D03*
X1206988Y1155610D03*
Y1148129D03*
X1210728Y1155610D03*
X1221948Y1151869D03*
Y1144389D03*
X1218208Y1166830D03*
Y1159350D03*
X1221948Y1166830D03*
X1210728Y1170570D03*
X1206988D03*
X1218208Y1189271D03*
Y1174310D03*
X1221948Y1181791D03*
Y1174310D03*
X1218208Y1181791D03*
X1221948Y1189271D03*
X1236909Y1136909D03*
X1225688Y1140649D03*
X1229428D03*
X1236909Y1151870D03*
X1225688Y1148129D03*
X1229428D03*
X1225688Y1155610D03*
X1236909Y1144389D03*
X1229428Y1155610D03*
Y1170570D03*
X1225688D03*
X1236909Y1159350D03*
Y1181791D03*
X1225688Y1185531D03*
X1236909Y1189271D03*
X1229428Y1178051D03*
Y1185531D03*
X1236909Y1174310D03*
X1225688Y1178051D03*
Y1193011D03*
X1229428D03*
X1240649Y1136909D03*
Y1151870D03*
Y1144389D03*
Y1159350D03*
Y1174310D03*
Y1181791D03*
Y1189271D03*
X1339196Y441086D03*
Y433999D03*
Y437543D03*
X1336396Y441086D03*
Y433999D03*
Y437543D03*
X1339196Y444629D03*
X1336396D03*
X1415924Y620661D03*
Y617861D03*
X1423010Y620661D03*
X1419467Y617861D03*
X1423010D03*
X1426554Y620661D03*
Y617861D03*
X1419467Y620661D03*
X1514468Y1088287D03*
Y1099507D03*
Y1106988D03*
Y1121948D03*
Y1114468D03*
Y1129429D03*
Y1136909D03*
Y1148129D03*
Y1155610D03*
X1514467Y1170570D03*
Y1178051D03*
X1521949Y1073326D03*
X1529429D03*
Y1077066D03*
X1525689Y1084547D03*
X1529429Y1092027D03*
X1521949D03*
X1518208Y1088287D03*
X1525689Y1080807D03*
X1518208Y1099507D03*
X1525689D03*
X1529429Y1095767D03*
X1525689Y1103247D03*
X1518208Y1106988D03*
X1521949Y1095767D03*
Y1110728D03*
X1518208Y1114468D03*
X1525689Y1110728D03*
X1518208Y1121948D03*
X1521949Y1118208D03*
X1525689D03*
Y1125688D03*
X1518208Y1129429D03*
X1521949Y1125688D03*
X1518208Y1136909D03*
X1521949Y1133169D03*
X1518208Y1148129D03*
Y1155610D03*
X1518207Y1170570D03*
X1527559Y1176180D03*
X1518207Y1178051D03*
X1536909Y1073326D03*
X1533169Y1080807D03*
Y1084547D03*
X1540649Y1080807D03*
X1536909Y1077066D03*
X1540649Y1084547D03*
X1536909Y1092027D03*
Y1095767D03*
X1533169Y1099507D03*
X1540649Y1103247D03*
X1533169D03*
X1536909Y1118208D03*
X1533169D03*
Y1121948D03*
X1544389Y1114468D03*
X1536909Y1110728D03*
X1533169D03*
X1540649Y1114468D03*
X1536909Y1148129D03*
X1540649Y1151870D03*
Y1148129D03*
X1536909Y1144389D03*
Y1155610D03*
X1540649Y1159350D03*
Y1170570D03*
Y1174310D03*
Y1178050D03*
X1531299Y1176180D03*
X1559350Y1114468D03*
X1555610D03*
X1563090D03*
Y1140649D03*
Y1136909D03*
X1555610D03*
X1563090Y1129429D03*
Y1133169D03*
Y1144389D03*
Y1151869D03*
X1555610Y1144389D03*
X1548130Y1151870D03*
Y1148129D03*
Y1144389D03*
X1559350Y1155610D03*
X1555610Y1151870D03*
X1559350Y1148129D03*
X1563090Y1159350D03*
Y1170570D03*
X1548130Y1166830D03*
Y1159350D03*
X1555610Y1170570D03*
X1559350Y1166830D03*
X1555610Y1159350D03*
X1548130Y1174310D03*
Y1178051D03*
Y1181791D03*
X1563090Y1185531D03*
Y1178051D03*
X1555610Y1185531D03*
X1559350Y1174310D03*
Y1181791D03*
X1555610Y1178051D03*
X1563090Y1193011D03*
X1555610Y1215452D03*
X1563090D03*
X1559350D03*
X1574311Y1114468D03*
X1570571D03*
X1578051D03*
X1566830D03*
X1578051Y1136909D03*
X1574311D03*
X1570571D03*
X1574311Y1129429D03*
X1570571D03*
X1578051D03*
X1566830Y1140649D03*
X1578051Y1144389D03*
X1574311D03*
X1570571D03*
X1578051Y1151870D03*
X1574311D03*
X1570571D03*
X1574311Y1155610D03*
X1566830Y1148129D03*
Y1155610D03*
X1578051Y1170570D03*
X1574311Y1166830D03*
X1570571Y1170570D03*
X1566830Y1166830D03*
X1578051Y1159350D03*
X1570571D03*
X1574311Y1185531D03*
X1570571D03*
X1578051D03*
Y1178051D03*
X1574311D03*
X1570571D03*
X1574311Y1174310D03*
X1566830Y1181791D03*
Y1174310D03*
X1570571Y1193011D03*
X1574311D03*
X1578051D03*
X1570571Y1200491D03*
X1578051D03*
X1574311D03*
X1578051Y1215452D03*
X1566830D03*
X1570571Y1211712D03*
X1566830Y1219192D03*
X1574311Y1215452D03*
X1570571D03*
X1578051Y1211712D03*
X1574311D03*
X1593012Y1114468D03*
X1589271D03*
X1581791D03*
X1593011Y1136909D03*
X1589271D03*
X1585531D03*
X1581791D03*
X1589271Y1129429D03*
X1585531D03*
X1581791D03*
X1593011D03*
X1585531Y1144389D03*
X1581791D03*
X1593011D03*
X1589271D03*
X1593012Y1151870D03*
X1589271D03*
X1585531D03*
X1581791D03*
Y1155610D03*
X1589271D03*
X1593011Y1170570D03*
X1585531D03*
X1589271Y1166830D03*
X1581791D03*
X1585531Y1159350D03*
X1593011D03*
X1589271Y1185531D03*
X1585531D03*
X1581791D03*
X1593011D03*
X1581791Y1178051D03*
X1593011D03*
X1589271D03*
X1585531D03*
X1589271Y1174310D03*
X1581791D03*
X1585531Y1193011D03*
X1589271D03*
X1593011D03*
X1581791D03*
X1589271Y1200491D03*
X1585531D03*
X1581791D03*
X1593011D03*
X1593012Y1211712D03*
Y1215452D03*
X1581791D03*
X1589271D03*
X1585531D03*
Y1211712D03*
X1596752Y1114468D03*
X1607972D03*
X1611712Y1118208D03*
X1607972D03*
X1611712Y1114468D03*
X1600492Y1136909D03*
X1596752D03*
X1611712D03*
X1607972D03*
X1611712Y1129429D03*
X1607972D03*
X1600492D03*
X1596752D03*
X1600492Y1144389D03*
X1596752D03*
X1611712Y1151869D03*
X1607972D03*
X1611712Y1144389D03*
X1607972D03*
X1600492Y1151870D03*
X1596752D03*
Y1155610D03*
X1607972D03*
Y1166830D03*
X1611712Y1170570D03*
X1600492D03*
X1596752Y1166830D03*
X1611712Y1159350D03*
X1600492D03*
Y1185531D03*
X1596752D03*
X1600492Y1178051D03*
X1596752D03*
X1611712Y1185531D03*
X1607972D03*
X1611712Y1178051D03*
X1607972D03*
Y1174310D03*
X1596752D03*
X1607972Y1193011D03*
X1611712D03*
X1600492D03*
X1596752D03*
X1600492Y1200491D03*
X1596752D03*
X1611712D03*
X1607972D03*
X1600492Y1211712D03*
Y1215452D03*
X1596752Y1211712D03*
X1611712Y1215452D03*
X1607972D03*
Y1211712D03*
X1609842Y1217322D03*
X1615452Y1118208D03*
X1619193D03*
X1615452Y1114468D03*
X1619193D03*
X1622933D03*
X1626673D03*
Y1118208D03*
X1622933D03*
X1626673Y1136909D03*
X1622933D03*
X1615452D03*
X1619193D03*
X1626673Y1129429D03*
X1622933D03*
X1619193D03*
X1615452D03*
Y1151869D03*
X1619193D03*
X1626673D03*
X1622933D03*
Y1144389D03*
X1615452D03*
X1619193D03*
X1626673D03*
X1622933Y1155610D03*
X1615452D03*
Y1166830D03*
X1619193Y1170570D03*
X1626673Y1159350D03*
X1619193D03*
X1622933Y1166830D03*
X1626673Y1170570D03*
X1619193Y1185531D03*
X1626673D03*
X1622933D03*
Y1178051D03*
X1615452D03*
X1619193D03*
X1626673D03*
X1615452Y1185531D03*
X1622933Y1174310D03*
X1615452D03*
X1622933Y1193011D03*
X1626673D03*
X1615452D03*
X1619193D03*
X1622933Y1200491D03*
X1619193D03*
X1615452D03*
X1626673D03*
X1622933Y1215452D03*
X1619192Y1215451D03*
X1626673Y1215452D03*
X1615452D03*
X1613582Y1217322D03*
X1619192Y1211711D03*
X1622933D03*
X1637893Y1118208D03*
Y1114468D03*
X1634153D03*
X1630413D03*
X1641633D03*
X1634153Y1118208D03*
X1630413D03*
Y1136909D03*
X1637893D03*
X1634153D03*
X1630413Y1129429D03*
X1637893D03*
X1634153D03*
X1630413Y1151869D03*
X1637893D03*
X1634153D03*
Y1144389D03*
X1630413D03*
X1637893D03*
Y1155610D03*
X1630413D03*
X1637893Y1170570D03*
X1641633D03*
X1634153D03*
X1641633Y1166830D03*
X1637893D03*
Y1159350D03*
X1641633D03*
X1634153D03*
X1630413Y1166830D03*
X1641633Y1181791D03*
X1630413Y1185531D03*
X1634153D03*
X1630413Y1178051D03*
X1634153D03*
X1637893Y1185531D03*
Y1178051D03*
Y1174310D03*
X1630413D03*
X1634153Y1193011D03*
X1637893D03*
X1630413D03*
Y1200491D03*
X1637893D03*
X1634153D03*
X1630413Y1215452D03*
X1637893D03*
X1634153D03*
X1656594Y1118208D03*
X1652854D03*
Y1114468D03*
X1645374D03*
X1649114D03*
X1656594D03*
X1645374Y1129429D03*
Y1136909D03*
Y1140649D03*
X1656594Y1133169D03*
Y1140649D03*
Y1136909D03*
X1660334Y1140649D03*
X1649114Y1155610D03*
X1656594D03*
X1645374Y1144389D03*
X1660334Y1148129D03*
X1652854Y1144389D03*
X1656594Y1148129D03*
Y1144389D03*
X1649114Y1159350D03*
Y1170570D03*
Y1166830D03*
X1656594Y1170570D03*
Y1166830D03*
Y1159350D03*
Y1189271D03*
X1649114Y1174310D03*
X1656594D03*
X1652854Y1181791D03*
X1660334Y1189271D03*
X1645374Y1185531D03*
Y1189271D03*
X1660334Y1181791D03*
X1656594Y1178051D03*
X1645374D03*
Y1200491D03*
Y1193011D03*
X1656594Y1196751D03*
Y1204232D03*
X1652854Y1200491D03*
X1649114Y1204232D03*
Y1196751D03*
Y1200491D03*
X1656594D03*
X1645374Y1215452D03*
X1649114D03*
X1652854D03*
X1656594Y1211712D03*
X1645374D03*
X1656594Y1215452D03*
Y1207972D03*
X1649114D03*
X1652854D03*
Y1211712D03*
X1664075Y1140649D03*
X1667815Y1155610D03*
X1664075Y1148129D03*
Y1155610D03*
X1675295Y1144389D03*
Y1151869D03*
Y1166830D03*
Y1159350D03*
X1664075Y1170570D03*
X1667815D03*
X1675295Y1189271D03*
Y1174310D03*
Y1181791D03*
X1686515Y1140649D03*
X1682775D03*
X1679035Y1151869D03*
Y1144389D03*
X1682775Y1148129D03*
X1686515Y1155610D03*
Y1148129D03*
X1682775Y1155610D03*
X1679035Y1166830D03*
X1686515Y1170570D03*
X1682775D03*
X1679035Y1181791D03*
Y1189271D03*
Y1174310D03*
X1686515Y1185531D03*
X1682775Y1178051D03*
X1686515D03*
X1682775Y1185531D03*
X1686515Y1193011D03*
X1682775D03*
Y1222932D03*
X1693996Y1136909D03*
X1697736D03*
X1693996Y1151870D03*
X1697736D03*
X1693996Y1144389D03*
X1697736D03*
Y1159350D03*
X1693996D03*
X1697736Y1174310D03*
X1693996Y1189271D03*
X1697736D03*
Y1181791D03*
X1693996D03*
Y1174310D03*
X1796283Y441086D03*
Y433999D03*
Y437543D03*
X1793483Y441086D03*
Y433999D03*
Y437543D03*
X1796283Y444629D03*
X1793483D03*
G54D53*
X970071Y1365652D03*
Y1409152D03*
G54D33*
X109882Y1622402D03*
X118543Y1452717D03*
X127205Y1622402D03*
X135866Y1452717D03*
X144528Y1622402D03*
X153189Y1452717D03*
X161850Y1622402D03*
X170512Y1452717D03*
X179173Y1489331D03*
Y1494449D03*
Y1504685D03*
Y1509804D03*
Y1560985D03*
Y1566103D03*
Y1576339D03*
Y1581457D03*
Y1591693D03*
Y1596811D03*
Y1607048D03*
Y1612166D03*
Y1622402D03*
X187835Y1452717D03*
Y1493662D03*
Y1498780D03*
Y1509016D03*
Y1514134D03*
Y1565315D03*
Y1570434D03*
Y1580670D03*
Y1585788D03*
X291771Y1452717D03*
X283110Y1622402D03*
X309094Y1452717D03*
X300433Y1622402D03*
X326417Y1452717D03*
X317756Y1622402D03*
X343740Y1452717D03*
X335078Y1622402D03*
X361063Y1452717D03*
X352401Y1458622D03*
Y1463741D03*
X361063Y1462953D03*
Y1468071D03*
X352401Y1473977D03*
Y1479095D03*
X361063Y1478308D03*
Y1483426D03*
X352401Y1489331D03*
Y1494449D03*
X361063Y1493662D03*
Y1498780D03*
X352401Y1504685D03*
Y1509804D03*
X361063Y1509016D03*
Y1514134D03*
X352401Y1560985D03*
Y1566103D03*
X361063Y1565315D03*
Y1570434D03*
X352401Y1576339D03*
Y1581457D03*
X361063Y1580670D03*
Y1585788D03*
X352401Y1591693D03*
Y1596811D03*
Y1607048D03*
Y1612166D03*
Y1622402D03*
X456339D03*
X465000Y1452717D03*
X473662Y1622402D03*
X482323Y1452717D03*
X490985Y1622402D03*
X499646Y1452717D03*
X516969D03*
X508307Y1622402D03*
X534292Y1452717D03*
X525630Y1458622D03*
Y1463741D03*
X534292Y1462953D03*
Y1468071D03*
X525630Y1473977D03*
Y1479095D03*
X534292Y1478308D03*
Y1483426D03*
X525630Y1489331D03*
Y1494449D03*
X534292Y1493662D03*
Y1498780D03*
X525630Y1504685D03*
Y1509804D03*
X534292Y1509016D03*
Y1514134D03*
X525630Y1560985D03*
Y1566103D03*
X534292Y1565315D03*
Y1570434D03*
X525630Y1576339D03*
Y1581457D03*
X534292Y1580670D03*
Y1585788D03*
X525630Y1591693D03*
X534292Y1596024D03*
X525630Y1596811D03*
X534292Y1601142D03*
X525630Y1607048D03*
Y1612166D03*
X534292Y1611378D03*
Y1616496D03*
X525630Y1622402D03*
X629567D03*
X638228Y1452717D03*
X646890Y1622402D03*
X655551Y1452717D03*
X664213Y1622402D03*
X672874Y1452717D03*
X681535Y1622402D03*
X698858Y1458622D03*
Y1463741D03*
X690197Y1452717D03*
X698858Y1473977D03*
Y1479095D03*
Y1489331D03*
Y1494449D03*
Y1504685D03*
Y1509804D03*
Y1560985D03*
Y1566103D03*
Y1576339D03*
Y1581457D03*
Y1591693D03*
Y1596811D03*
Y1607048D03*
Y1612166D03*
Y1622402D03*
X707520Y1452717D03*
Y1462953D03*
Y1468071D03*
Y1478308D03*
Y1483426D03*
Y1493662D03*
Y1498780D03*
Y1509016D03*
Y1514134D03*
Y1565315D03*
Y1570434D03*
Y1580670D03*
Y1585788D03*
Y1596024D03*
Y1601142D03*
Y1611378D03*
Y1616496D03*
X1140511Y1452717D03*
X1131850Y1622402D03*
X1149173D03*
X1157834Y1452717D03*
X1166496Y1622402D03*
X1175157Y1452717D03*
X1183818Y1622402D03*
X1201141Y1458622D03*
Y1463741D03*
X1192480Y1452717D03*
X1201141Y1473977D03*
Y1479095D03*
Y1489331D03*
Y1494449D03*
Y1504685D03*
Y1509804D03*
Y1560985D03*
Y1566103D03*
Y1576339D03*
Y1581457D03*
Y1591693D03*
Y1596811D03*
Y1607048D03*
Y1612166D03*
Y1622402D03*
X1209803Y1452717D03*
Y1462953D03*
Y1468071D03*
Y1478308D03*
Y1483426D03*
Y1493662D03*
Y1498780D03*
Y1509016D03*
Y1514134D03*
Y1565315D03*
Y1570434D03*
Y1580670D03*
Y1585788D03*
Y1596024D03*
Y1601142D03*
Y1611378D03*
Y1616496D03*
X1313740Y1452717D03*
X1305079Y1622402D03*
X1331063Y1452717D03*
X1322402Y1622402D03*
X1348386Y1452717D03*
X1339725Y1622402D03*
X1365709Y1452717D03*
X1357047Y1622402D03*
X1383032Y1452717D03*
X1374370Y1458622D03*
Y1463741D03*
X1383032Y1462953D03*
Y1468071D03*
X1374370Y1473977D03*
Y1479095D03*
X1383032Y1478308D03*
Y1483426D03*
X1374370Y1489331D03*
Y1494449D03*
X1383032Y1493662D03*
Y1498780D03*
X1374370Y1504685D03*
Y1509804D03*
X1383032Y1509016D03*
Y1514134D03*
X1374370Y1560985D03*
Y1566103D03*
X1383032Y1565315D03*
Y1570434D03*
X1374370Y1576339D03*
Y1581457D03*
X1383032Y1580670D03*
Y1585788D03*
X1374370Y1591693D03*
X1383032Y1596024D03*
X1374370Y1596811D03*
X1383032Y1601142D03*
X1374370Y1607048D03*
Y1612166D03*
X1383032Y1611378D03*
Y1616496D03*
X1374370Y1622402D03*
X1478307D03*
X1486968Y1452717D03*
X1495630Y1622402D03*
X1504291Y1452717D03*
X1512953Y1622402D03*
X1521614Y1452717D03*
X1530275Y1622402D03*
X1538937Y1452717D03*
X1556260D03*
X1547598Y1458622D03*
Y1463741D03*
X1556260Y1462953D03*
Y1468071D03*
X1547598Y1473977D03*
Y1479095D03*
X1556260Y1478308D03*
Y1483426D03*
X1547598Y1489331D03*
Y1494449D03*
X1556260Y1493662D03*
Y1498780D03*
X1547598Y1504685D03*
Y1509804D03*
X1556260Y1509016D03*
Y1514134D03*
X1547598Y1560985D03*
Y1566103D03*
X1556260Y1565315D03*
Y1570434D03*
X1547598Y1576339D03*
Y1581457D03*
X1556260Y1580670D03*
Y1585788D03*
X1547598Y1591693D03*
X1556260Y1596024D03*
X1547598Y1596811D03*
X1556260Y1601142D03*
X1547598Y1607048D03*
Y1612166D03*
X1556260Y1611378D03*
Y1616496D03*
X1547598Y1622402D03*
X1660196Y1452717D03*
X1651535Y1622402D03*
X1668858D03*
X1677519Y1452717D03*
X1686181Y1622402D03*
X1694842Y1452717D03*
X1703503Y1622402D03*
X1720826Y1458622D03*
Y1463741D03*
X1712165Y1452717D03*
X1720826Y1473977D03*
Y1479095D03*
Y1489331D03*
Y1494449D03*
Y1504685D03*
Y1509804D03*
Y1560985D03*
Y1566103D03*
Y1576339D03*
Y1581457D03*
Y1591693D03*
Y1596811D03*
Y1607048D03*
Y1612166D03*
Y1622402D03*
X1729488Y1452717D03*
Y1462953D03*
Y1468071D03*
Y1478308D03*
Y1483426D03*
Y1493662D03*
Y1498780D03*
Y1509016D03*
Y1514134D03*
Y1565315D03*
Y1570434D03*
Y1580670D03*
Y1585788D03*
Y1596024D03*
Y1601142D03*
Y1611378D03*
Y1616496D03*
G54D54*
X1030635Y754546D03*
Y774546D03*
Y784546D03*
Y794546D03*
Y804546D03*
Y814546D03*
Y824546D03*
G54D28*
X116731Y1052235D03*
X106619Y1056423D03*
X102431Y1066535D03*
X106619Y1076647D03*
X116731Y1080835D03*
Y1249086D03*
X106619Y1253274D03*
X102431Y1263386D03*
X106619Y1273498D03*
X116731Y1277686D03*
X126843Y1056423D03*
Y1076647D03*
X131031Y1066535D03*
X126843Y1253274D03*
X131031Y1263386D03*
X126843Y1273498D03*
X342840Y1056423D03*
X338652Y1066535D03*
X342840Y1076647D03*
Y1253274D03*
X338652Y1263386D03*
X342840Y1273498D03*
X352952Y1052235D03*
Y1080835D03*
Y1249086D03*
Y1277686D03*
X363064Y1056423D03*
Y1076647D03*
X367252Y1066535D03*
X363064Y1253274D03*
X367252Y1263386D03*
X363064Y1273498D03*
X563706Y1056423D03*
X559518Y1066535D03*
X563706Y1076647D03*
Y1253274D03*
X559518Y1263386D03*
X563706Y1273498D03*
X583930Y1056423D03*
X573818Y1052235D03*
X583930Y1076647D03*
X588118Y1066535D03*
X573818Y1080835D03*
X583930Y1253274D03*
X573818Y1249086D03*
X588118Y1263386D03*
X573818Y1277686D03*
X583930Y1273498D03*
X760433Y1480906D03*
X756274Y1490945D03*
X760433Y1500984D03*
X780511Y1480906D03*
X770472Y1476747D03*
Y1505143D03*
X780511Y1500984D03*
X799926Y1056423D03*
X795738Y1066535D03*
X799926Y1076647D03*
Y1253274D03*
X795738Y1263386D03*
X799926Y1273498D03*
X784670Y1490945D03*
X810040Y378544D03*
X805881Y388583D03*
X810040Y398622D03*
X810038Y1052235D03*
Y1080835D03*
Y1249086D03*
Y1277686D03*
X820079Y374385D03*
X830118Y378544D03*
X820079Y402781D03*
X830118Y398622D03*
X820150Y1056423D03*
Y1076647D03*
X824338Y1066535D03*
X820150Y1253274D03*
X824338Y1263386D03*
X820150Y1273498D03*
X834277Y388583D03*
X1010827Y378544D03*
X1006668Y388583D03*
X1010827Y398622D03*
X1020866Y374385D03*
Y402781D03*
X1020793Y1056423D03*
X1016605Y1066535D03*
X1020793Y1076647D03*
Y1253274D03*
X1016605Y1263386D03*
X1020793Y1273498D03*
X1030905Y378544D03*
X1035064Y388583D03*
X1030905Y398622D03*
X1041017Y1056423D03*
X1030905Y1052235D03*
X1041017Y1076647D03*
X1030905Y1080835D03*
X1041017Y1253274D03*
X1030905Y1249086D03*
Y1277686D03*
X1041017Y1273498D03*
X1045205Y1066535D03*
Y1263386D03*
X1060433Y1480906D03*
X1056274Y1490945D03*
X1060433Y1500984D03*
X1070472Y1476747D03*
Y1505143D03*
X1080511Y1480906D03*
X1084670Y1490945D03*
X1080511Y1500984D03*
X1252825Y1066535D03*
Y1263386D03*
X1267125Y1052235D03*
X1257013Y1056423D03*
Y1076647D03*
X1267125Y1080835D03*
Y1249086D03*
X1257013Y1253274D03*
Y1273498D03*
X1267125Y1277686D03*
X1277237Y1056423D03*
Y1076647D03*
X1281425Y1066535D03*
X1277237Y1253274D03*
X1281425Y1263386D03*
X1277237Y1273498D03*
X1477879Y1056423D03*
X1473691Y1066535D03*
X1477879Y1076647D03*
Y1253274D03*
X1473691Y1263386D03*
X1477879Y1273498D03*
X1498103Y1056423D03*
X1487991Y1052235D03*
X1498103Y1076647D03*
X1487991Y1080835D03*
X1498103Y1253274D03*
X1487991Y1249086D03*
Y1277686D03*
X1498103Y1273498D03*
X1502291Y1066535D03*
Y1263386D03*
X1709912Y1066535D03*
Y1263386D03*
X1724212Y1052235D03*
X1714100Y1056423D03*
Y1076647D03*
X1724212Y1080835D03*
Y1249086D03*
X1714100Y1253274D03*
Y1273498D03*
X1724212Y1277686D03*
X1734324Y1056423D03*
Y1076647D03*
X1738512Y1066535D03*
X1734324Y1253274D03*
X1738512Y1263386D03*
X1734324Y1273498D03*
G54D41*
X281594Y1211712D03*
X270374Y1215452D03*
X393094Y1423600D03*
X395894D03*
X878220Y848442D03*
Y845293D03*
Y835844D03*
Y851592D03*
X877800Y876500D03*
X897118Y848442D03*
X881370Y835844D03*
X893968Y845293D03*
X884519Y848442D03*
X897118Y842143D03*
X893968D03*
X887669Y848442D03*
X886093Y835318D03*
X897118Y845293D03*
X893968Y838994D03*
X890818Y842143D03*
X893968Y835846D03*
X887669Y845293D03*
X890818D03*
X893968Y848442D03*
X884519Y845293D03*
X881370D03*
X884519Y842143D03*
X887669D03*
X881370Y848442D03*
X890818D03*
X887669Y851592D03*
X890818Y854742D03*
X887669D03*
X897118Y851592D03*
X890818Y864189D03*
Y857891D03*
X887669Y864189D03*
X884519Y854742D03*
Y851592D03*
Y857891D03*
X887669D03*
X890818Y851592D03*
X893967Y851591D03*
X881370Y851592D03*
X887669Y867338D03*
X890818Y870488D03*
X887669D03*
X897118Y876787D03*
X890818Y867338D03*
X881370D03*
X897118Y879937D03*
X884519Y873638D03*
X887669D03*
X884519Y876787D03*
X890818Y879937D03*
X881370Y876787D03*
X887669Y879937D03*
X884519Y867338D03*
X890818Y873638D03*
X893968Y876787D03*
Y879937D03*
X890818Y876787D03*
X884519Y879937D03*
Y870488D03*
X881370D03*
Y883086D03*
X884585Y886354D03*
X885126Y889742D03*
X881370Y886236D03*
X906565Y848442D03*
X900267D03*
X906565Y838994D03*
X900267Y838992D03*
X909714Y848442D03*
X906565Y842143D03*
X900267Y845293D03*
Y842143D03*
X906565Y845293D03*
X900266Y835844D03*
X900267Y851592D03*
X906565D03*
X909714D03*
Y876787D03*
X900267Y879937D03*
Y876787D03*
X906565D03*
X912864Y873638D03*
Y879937D03*
X909714D03*
X906565D03*
X912864Y876787D03*
X922313Y845293D03*
X916014Y848442D03*
Y842143D03*
X919163Y845293D03*
X922313Y842143D03*
X916014Y845293D03*
X919163Y835844D03*
Y838994D03*
Y842143D03*
X925462Y845293D03*
X919163Y854742D03*
Y857891D03*
X922313Y854742D03*
X916014Y857891D03*
Y854742D03*
Y851592D03*
Y864189D03*
X925462Y851592D03*
X922313Y864189D03*
Y857891D03*
X925462D03*
X928612Y864189D03*
X919163D03*
X925462D03*
X916014Y870488D03*
X925462Y873638D03*
X922313Y876787D03*
X928612Y870488D03*
X925462D03*
X916014Y873638D03*
X922313D03*
X916014Y876787D03*
X928612Y873638D03*
X925462Y876787D03*
X928612D03*
Y879937D03*
X916014D03*
X922313D03*
X919163D03*
X925462D03*
X916014Y867338D03*
X919163Y873638D03*
Y870488D03*
X922313D03*
X919163Y876787D03*
X922313Y867338D03*
X919163D03*
X925462D03*
X922313Y883086D03*
Y886236D03*
X925462D03*
X919163Y883086D03*
X928612Y886236D03*
X925462Y883086D03*
X928612D03*
X1184547Y1215452D03*
X1316906Y829871D03*
Y833021D03*
Y848769D03*
X1313756Y833021D03*
Y836170D03*
X1316906Y839320D03*
X1310555Y848675D03*
X1313756Y848769D03*
X1316906Y836170D03*
X1313756Y842470D03*
Y858218D03*
X1316906Y855068D03*
X1313756Y855066D03*
X1316906Y858218D03*
X1335803Y829871D03*
X1323205D03*
X1326355Y839320D03*
X1335803D03*
X1329504Y833021D03*
X1332654Y842470D03*
X1329504Y845619D03*
X1332654D03*
X1326355Y836170D03*
X1335803Y842470D03*
X1329504Y836170D03*
X1335803Y845619D03*
Y848769D03*
X1329504Y839320D03*
X1323205Y836170D03*
X1335803D03*
X1329504Y842470D03*
X1335803Y833021D03*
X1323205D03*
X1320055Y845619D03*
X1326355D03*
X1320055Y836170D03*
X1326355Y842470D03*
X1320055Y848769D03*
X1323205Y845619D03*
X1332654Y848769D03*
X1320055Y839320D03*
X1326355Y848769D03*
X1323205D03*
X1329504D03*
X1323204Y839319D03*
X1332654Y839320D03*
X1320055Y842470D03*
X1323205D03*
X1329504Y855068D03*
Y858218D03*
X1320055Y851918D03*
X1332654Y855068D03*
X1326355D03*
Y858218D03*
X1329504Y861367D03*
X1323205Y858218D03*
X1320055D03*
X1332654Y861367D03*
X1329504Y851918D03*
X1323205D03*
X1326355Y861367D03*
X1320055Y855068D03*
X1332654Y858218D03*
X1335803Y855068D03*
Y858218D03*
Y861367D03*
X1320055D03*
X1323204Y855067D03*
X1326355Y851918D03*
X1332654D03*
X1326355Y880263D03*
X1329504Y877114D03*
X1335803Y880263D03*
X1326355Y867665D03*
Y870814D03*
X1323205D03*
X1320055D03*
X1329504Y867665D03*
X1326355Y873964D03*
X1332654Y880263D03*
X1329504D03*
X1332654Y877114D03*
X1326355D03*
X1329504Y870814D03*
X1320055Y873964D03*
X1332654Y870814D03*
X1323204Y873965D03*
X1332654Y867665D03*
X1320055Y880263D03*
Y867665D03*
X1323205Y880263D03*
Y877114D03*
X1320055D03*
X1335803Y867665D03*
Y873964D03*
Y870814D03*
X1332654Y873964D03*
X1329504D03*
X1323205Y867665D03*
Y886562D03*
X1326355Y889712D03*
X1335803Y883413D03*
X1329504Y892862D03*
X1332654Y889712D03*
X1335803Y892862D03*
Y889712D03*
X1326355Y892862D03*
X1329504Y889712D03*
X1320055Y892862D03*
X1323205D03*
X1329504Y886562D03*
X1332654Y883413D03*
X1320055Y886562D03*
X1326355Y883413D03*
X1323205D03*
X1332654Y892862D03*
X1320055Y883413D03*
X1332654Y886562D03*
X1335803D03*
X1320055Y889712D03*
X1323204Y889713D03*
X1329504Y883413D03*
X1342103Y845619D03*
X1345252Y836170D03*
X1338953Y845619D03*
X1345252Y833021D03*
X1342103Y836170D03*
X1351550D03*
X1342103Y842470D03*
X1345252Y845619D03*
X1342103Y839320D03*
X1338953Y848769D03*
X1338952Y839319D03*
X1345252Y842470D03*
X1342103Y848769D03*
X1338953Y842470D03*
X1345252Y848769D03*
X1338953Y836170D03*
X1351550Y842470D03*
Y848769D03*
Y845619D03*
X1345252Y839320D03*
X1351550Y858218D03*
X1345252D03*
Y861367D03*
X1342103Y858218D03*
X1351550Y861367D03*
X1338953Y851918D03*
X1342103D03*
X1345252D03*
X1351550D03*
X1338953Y880263D03*
X1351550D03*
X1345252D03*
X1342103Y870814D03*
X1345252D03*
Y867665D03*
X1351550Y870814D03*
Y867665D03*
X1338953Y877114D03*
X1345252D03*
X1351550D03*
X1342103Y880263D03*
X1338953Y883413D03*
X1345252Y889712D03*
Y886562D03*
X1342103Y883413D03*
X1345252D03*
X1338952Y889713D03*
X1338953Y892862D03*
X1342103Y886562D03*
Y892862D03*
Y889712D03*
X1338953Y886562D03*
X1351550Y883413D03*
Y889712D03*
Y886562D03*
Y892862D03*
X1364148Y829871D03*
X1367298D03*
X1359425Y829000D03*
X1354699Y842470D03*
Y848769D03*
X1357849D03*
X1364148Y845619D03*
X1354699Y836170D03*
X1357849Y833021D03*
X1367298Y845619D03*
X1364148Y842470D03*
X1357850Y839319D03*
X1357849Y836170D03*
X1360999Y842470D03*
X1354699Y845619D03*
X1357849D03*
X1360999Y839320D03*
X1367298Y842470D03*
X1360999Y848769D03*
Y845619D03*
X1367298Y833021D03*
X1354699Y839320D03*
X1360999Y836170D03*
X1367298Y848769D03*
X1364148Y839320D03*
X1357849Y842470D03*
X1364148Y833021D03*
X1367298Y836170D03*
Y839320D03*
X1364148Y848769D03*
Y851918D03*
X1367298Y861367D03*
X1364148Y858218D03*
Y855068D03*
Y861367D03*
X1367298Y858218D03*
Y851918D03*
X1354699Y858218D03*
X1367298Y855068D03*
X1360999D03*
Y858218D03*
Y861367D03*
X1354699Y851918D03*
X1357849D03*
X1364148Y867665D03*
X1367298Y877114D03*
X1364148Y870814D03*
X1367298Y873964D03*
X1364148D03*
Y877114D03*
X1367298Y870814D03*
X1364148Y880263D03*
X1367298D03*
X1357849D03*
X1360999D03*
X1367298Y867665D03*
X1354699Y870814D03*
X1357849Y877114D03*
X1354699Y880263D03*
X1360999Y867665D03*
Y870814D03*
Y873964D03*
X1367298Y883413D03*
X1354699Y892862D03*
X1360999D03*
X1367298D03*
X1360999Y883413D03*
X1357850Y889713D03*
X1364148Y889712D03*
X1357849Y883413D03*
X1367298Y889712D03*
X1354699D03*
X1357849Y886562D03*
X1364148D03*
X1357849Y892862D03*
X1360999Y889712D03*
X1354699Y883413D03*
X1360999Y886562D03*
X1364148Y892862D03*
Y883413D03*
X1367298Y886562D03*
X1354699D03*
X1370447Y829871D03*
Y839320D03*
X1383046Y845619D03*
X1379896D03*
X1373597D03*
Y842470D03*
X1370447Y848769D03*
X1379896D03*
Y839320D03*
X1373597Y848769D03*
X1376747D03*
X1373597Y833021D03*
X1370447D03*
X1373597Y836170D03*
X1370447D03*
X1373598Y839319D03*
X1370447Y842470D03*
Y845619D03*
X1383046Y842470D03*
X1376747Y836170D03*
Y842470D03*
X1379896Y833021D03*
X1383046Y839320D03*
X1376747Y845619D03*
Y839320D03*
X1379896Y855068D03*
Y861367D03*
X1376747Y858218D03*
Y851918D03*
X1373597Y861367D03*
X1376747Y855068D03*
X1373597Y858218D03*
X1376747Y861367D03*
X1383046Y851918D03*
X1373597D03*
X1373598Y855067D03*
X1379896Y851918D03*
X1370447D03*
Y858218D03*
X1383046D03*
Y861367D03*
X1370447Y855068D03*
Y861367D03*
X1383046Y873964D03*
X1376747Y880263D03*
X1370447Y877114D03*
X1373598Y873965D03*
X1370447Y873964D03*
X1379896Y877114D03*
X1373597Y880263D03*
X1383046Y877114D03*
X1370447Y880263D03*
X1376747Y873964D03*
X1383046Y880263D03*
X1370447Y870814D03*
X1376747D03*
X1373597D03*
X1376747Y867665D03*
Y877114D03*
X1373597Y867665D03*
X1379896D03*
X1383046Y870814D03*
X1379896Y880263D03*
X1373597Y877114D03*
X1379896Y873964D03*
X1383046Y892862D03*
X1379896Y886562D03*
X1370447Y883413D03*
X1373598Y889713D03*
X1376747Y886562D03*
X1383046Y883413D03*
X1376747Y889712D03*
X1383046D03*
X1379896D03*
X1373597Y883413D03*
Y886562D03*
X1370447Y892862D03*
X1376747D03*
X1370447Y889712D03*
X1373597Y892862D03*
X1383046Y886562D03*
X1379896Y892862D03*
X1376747Y883413D03*
X1641634Y1215452D03*
G54D45*
X710406Y-26826D03*
Y-36826D03*
D03*
Y-26826D03*
X735406D03*
Y-36826D03*
D03*
Y-26826D03*
X830406Y-76006D03*
D03*
Y-66006D03*
D03*
X855406Y-76006D03*
D03*
Y-66006D03*
D03*
X939542Y-36798D03*
Y-26798D03*
D03*
Y-36798D03*
X964386Y-75978D03*
D03*
Y-65978D03*
D03*
X964542Y-36798D03*
Y-26798D03*
D03*
Y-36798D03*
X989386Y-75978D03*
D03*
Y-65978D03*
D03*
X993906Y-46826D03*
Y-36826D03*
D03*
Y-26826D03*
X1018906Y-46826D03*
Y-36826D03*
D03*
Y-26826D03*
X1063906Y-76006D03*
Y-86006D03*
Y-76006D03*
Y-66006D03*
X1088906Y-76006D03*
Y-86006D03*
Y-76006D03*
Y-66006D03*
X1217686Y-85978D03*
Y-75978D03*
D03*
Y-65978D03*
X1223042Y-46928D03*
Y-36928D03*
Y-26928D03*
Y-36928D03*
X1242686Y-85978D03*
Y-75978D03*
D03*
Y-65978D03*
X1248042Y-46928D03*
Y-36928D03*
Y-26928D03*
Y-36928D03*
X1280406Y-46956D03*
Y-36956D03*
D03*
Y-26956D03*
X1305406Y-46956D03*
Y-36956D03*
D03*
Y-26956D03*
X1320406Y-76006D03*
Y-86006D03*
Y-76006D03*
Y-66006D03*
X1345406Y-76006D03*
Y-86006D03*
Y-76006D03*
Y-66006D03*
X1474186Y-85978D03*
Y-75978D03*
D03*
Y-65978D03*
X1499186Y-85978D03*
Y-75978D03*
D03*
Y-65978D03*
X1509542Y-47058D03*
Y-37058D03*
Y-27058D03*
Y-37058D03*
X1534542Y-47058D03*
Y-37058D03*
Y-27058D03*
Y-37058D03*
X1564906Y-47086D03*
Y-37086D03*
D03*
Y-27086D03*
X1574906Y-76006D03*
Y-86006D03*
Y-76006D03*
Y-66006D03*
X1589906Y-47086D03*
Y-37086D03*
D03*
Y-27086D03*
X1599906Y-76006D03*
Y-86006D03*
Y-76006D03*
Y-66006D03*
X1728686Y-85978D03*
Y-75978D03*
D03*
Y-65978D03*
X1753686Y-85978D03*
Y-75978D03*
D03*
Y-65978D03*
X1794042Y-47188D03*
Y-37188D03*
Y-27188D03*
Y-37188D03*
X1819042Y-47188D03*
Y-37188D03*
Y-27188D03*
Y-37188D03*
G54D10*
X3704Y5374D03*
X3017Y24773D03*
Y44773D03*
Y64773D03*
Y84773D03*
Y104773D03*
Y124773D03*
Y144773D03*
Y164773D03*
Y184773D03*
Y204773D03*
Y224773D03*
Y244773D03*
Y264773D03*
Y284773D03*
Y304773D03*
X3221Y324773D03*
X3035Y978036D03*
Y998036D03*
Y1018036D03*
Y1038036D03*
Y1058036D03*
Y1078036D03*
Y1098036D03*
Y1118036D03*
Y1138036D03*
Y1158036D03*
Y1178036D03*
Y1198036D03*
Y1238036D03*
Y1258036D03*
Y1278036D03*
Y1298036D03*
Y1318036D03*
Y1338036D03*
Y1358036D03*
Y1378036D03*
Y1398036D03*
Y1418036D03*
Y1438036D03*
Y1458036D03*
Y1478036D03*
Y1498036D03*
Y1538036D03*
Y1558036D03*
X15972Y3000D03*
X10971Y333342D03*
X17964Y349298D03*
Y369298D03*
Y389298D03*
Y409298D03*
Y429298D03*
Y449298D03*
Y469298D03*
Y489298D03*
Y509298D03*
Y529298D03*
Y549298D03*
Y569298D03*
Y589298D03*
Y609298D03*
Y629298D03*
Y649298D03*
Y669298D03*
Y689298D03*
Y709298D03*
Y729298D03*
Y749298D03*
Y769298D03*
Y789298D03*
Y809298D03*
Y829298D03*
Y849298D03*
Y869298D03*
Y889298D03*
Y909298D03*
Y929298D03*
X9554Y961954D03*
X17964Y949298D03*
X6161Y1075991D03*
X6108Y1070611D03*
Y1065318D03*
X6059Y1091964D03*
X6055Y1086546D03*
X6053Y1081305D03*
X8042Y1522199D03*
X7922Y1532494D03*
X26956Y4469D03*
X28317Y24773D03*
Y44773D03*
X35638Y53597D03*
X36692Y641817D03*
X27934Y1204311D03*
X30934D03*
X27934Y1215511D03*
X30934D03*
X27934Y1212711D03*
Y1209911D03*
Y1207111D03*
X30934Y1212711D03*
Y1209911D03*
Y1207111D03*
X21544Y1479662D03*
X33536Y1467485D03*
X21544Y1489648D03*
X42192Y641817D03*
X51449Y822718D03*
X47949D03*
X44960Y1190619D03*
X49638Y1203884D03*
X40996Y1467703D03*
X40195Y1511279D03*
X55638Y53597D03*
X66371Y482134D03*
Y484634D03*
X60233Y521804D03*
X68202Y522129D03*
X60233Y524304D03*
X56540Y531378D03*
Y528878D03*
X68202Y527129D03*
Y524629D03*
Y529629D03*
X62789Y608311D03*
X66510Y628242D03*
X60849Y826818D03*
X64649D03*
X58949Y821018D03*
X64849Y840418D03*
X60249D03*
X74432Y5374D03*
X73745Y24773D03*
Y44773D03*
X73509Y110445D03*
Y115401D03*
X83911Y117557D03*
X80660Y103783D03*
X73509Y129574D03*
Y124618D03*
X83911Y122513D03*
Y131731D03*
Y136687D03*
X69816Y475946D03*
Y478446D03*
X78033Y478586D03*
Y481086D03*
Y476086D03*
Y483586D03*
X72549Y838818D03*
X93334Y3000D03*
X95943Y377953D03*
X113334Y3000D03*
X129318Y4469D03*
X130679Y24773D03*
Y44773D03*
X138000Y53597D03*
X146196Y390223D03*
X138194Y397335D03*
X146196Y395179D03*
Y404396D03*
Y409352D03*
X138194Y402291D03*
X135794Y416465D03*
Y411509D03*
X146196Y418569D03*
Y423525D03*
X135794Y425682D03*
Y430638D03*
X146196Y432743D03*
Y437699D03*
X135794Y439855D03*
Y444811D03*
Y468609D03*
Y473565D03*
X146196Y489895D03*
X135794Y487738D03*
X146196Y480677D03*
Y475721D03*
X135794Y482782D03*
X146196Y494851D03*
X135794Y512743D03*
Y517699D03*
X146196Y519855D03*
X135794Y526916D03*
Y531872D03*
X146196Y524811D03*
Y538984D03*
Y534028D03*
X158000Y53597D03*
X176794Y5374D03*
X176107Y24773D03*
Y44773D03*
X195697Y3000D03*
X183022Y103783D03*
X215697Y3000D03*
X231681Y4469D03*
X229745Y1446675D03*
X224753D03*
Y1462631D03*
X229745Y1457675D03*
X224753D03*
X229745Y1451631D03*
Y1462631D03*
X224753Y1451631D03*
X233042Y24773D03*
Y44773D03*
X240363Y53597D03*
X260363D03*
X279156Y5374D03*
X278469Y24773D03*
Y44773D03*
X265945Y440098D03*
Y437598D03*
Y435098D03*
Y432598D03*
Y430098D03*
X294959Y11097D03*
X285384Y103783D03*
X298059Y3000D03*
X301943Y332017D03*
X318059Y3000D03*
X318497Y466528D03*
Y471484D03*
X328899Y473640D03*
Y487813D03*
Y478596D03*
X318497Y480701D03*
Y485657D03*
X328899Y492769D03*
Y517774D03*
X318497Y510661D03*
Y515617D03*
X328899Y522730D03*
X318497Y524835D03*
X328899Y536903D03*
Y531947D03*
X318497Y529791D03*
X328899Y572769D03*
X318497Y565657D03*
Y560701D03*
X328899Y567813D03*
X318497Y579830D03*
Y574874D03*
X328899Y581987D03*
X318497Y589047D03*
X328899Y586943D03*
X318497Y594003D03*
X328899Y596160D03*
X318497Y603221D03*
X328899Y601116D03*
Y610333D03*
X318497Y608177D03*
X328899Y615289D03*
X334043Y4469D03*
X335404Y24773D03*
Y44773D03*
X342725Y53597D03*
X348737Y375386D03*
X354486Y377173D03*
X357173Y392183D03*
X357218Y396866D03*
X361234Y402867D03*
X358042Y442518D03*
Y439718D03*
X362725Y53597D03*
X361767Y392228D03*
X376992Y395248D03*
X368587Y409016D03*
X364551Y409032D03*
X361811Y396866D03*
X375919Y449118D03*
Y446318D03*
X367919Y449118D03*
Y446318D03*
X376099Y458309D03*
Y454309D03*
Y462309D03*
X369282Y468088D03*
Y465288D03*
X367816Y1310586D03*
Y1315542D03*
X388059Y3000D03*
X381518Y5374D03*
X388487Y24069D03*
X380831Y24773D03*
X383612Y30618D03*
X380831Y44773D03*
X387746Y103783D03*
X389237Y371070D03*
X385237Y370976D03*
X396373Y407104D03*
X385584Y450041D03*
Y452841D03*
Y455641D03*
X387587Y1296675D03*
X387644Y1302089D03*
X389458Y1365466D03*
X389188Y1369033D03*
X388600Y1395500D03*
X389985Y1405762D03*
X408059Y3000D03*
X396373Y409904D03*
X395577Y455641D03*
Y450041D03*
Y452841D03*
X397315Y479560D03*
X400914Y762675D03*
X408300Y755487D03*
X407965Y770196D03*
X408400Y795200D03*
Y792200D03*
X406600Y789000D03*
X402376Y842677D03*
X399876D03*
X402376Y850677D03*
X399876D03*
X395959Y1352153D03*
X403029Y1379716D03*
X403111Y1384920D03*
X408212Y1379695D03*
X394657Y1377875D03*
X403111Y1390103D03*
X408212Y1390083D03*
X410152Y1410928D03*
X398112Y1403741D03*
X415453Y455039D03*
X419040Y533690D03*
Y528390D03*
Y530990D03*
Y536290D03*
Y538890D03*
X423266Y631438D03*
X420266D03*
X417666D03*
X420266Y637038D03*
Y634238D03*
X417666Y637038D03*
Y634238D03*
X423266Y637038D03*
Y634238D03*
Y642638D03*
X420266D03*
X417666D03*
X423266Y639838D03*
X420266D03*
X417666D03*
X415696Y762466D03*
X424649Y842644D03*
X422149D03*
Y850644D03*
X424649D03*
X422149Y858644D03*
X424649D03*
X414280Y1362561D03*
X413437Y1379736D03*
Y1384899D03*
X413395Y1390062D03*
X428059Y3000D03*
X433724Y433975D03*
X432310Y436164D03*
X428740Y533690D03*
X442704Y533790D03*
X428740Y528390D03*
Y530990D03*
X442704Y528490D03*
Y531090D03*
X428740Y536290D03*
Y538890D03*
X442704Y536390D03*
Y538990D03*
X436369Y622883D03*
X441612Y631011D03*
X435881Y1394934D03*
Y1398800D03*
X448059Y3000D03*
X452404Y533690D03*
Y528390D03*
Y530990D03*
Y536290D03*
Y538890D03*
X468059Y3000D03*
X468850Y537507D03*
X461849Y668016D03*
X459349D03*
X466849D03*
X469349D03*
X464349D03*
X469349Y678016D03*
X466849D03*
X459349D03*
X461849D03*
X464349D03*
X484043Y4469D03*
X485404Y24773D03*
Y44773D03*
X482193Y472784D03*
Y468784D03*
Y476784D03*
X484341Y700528D03*
Y705484D03*
X492725Y53597D03*
X499278Y641817D03*
X493778D03*
X512725Y53597D03*
X523457Y482134D03*
Y484634D03*
X517319Y521804D03*
X513626Y528578D03*
Y531378D03*
X517319Y524304D03*
X519875Y608311D03*
X523596Y628242D03*
X531518Y5374D03*
X530831Y24773D03*
Y44773D03*
X537747Y103783D03*
X535119Y483886D03*
Y481086D03*
Y478586D03*
X526902Y478446D03*
Y475946D03*
X535119Y476086D03*
X525288Y522129D03*
Y524629D03*
Y527129D03*
Y529929D03*
X542275Y760782D03*
X532449Y782389D03*
X534672Y785037D03*
X536641Y838649D03*
X550421Y3000D03*
X542599Y782389D03*
X542546Y784911D03*
X554357Y784889D03*
X551524D03*
X570421Y3000D03*
X562231Y784911D03*
X558294D03*
X560263Y829989D03*
X568503Y936807D03*
X565003D03*
X586405Y4469D03*
X587766Y24773D03*
Y44773D03*
X583501Y800831D03*
X577903Y940907D03*
X581703D03*
X576003Y935107D03*
X581903Y954507D03*
X577303D03*
X595087Y53597D03*
X603282Y390223D03*
Y395179D03*
Y404396D03*
Y409352D03*
X595280Y402291D03*
Y397335D03*
X592880Y416465D03*
Y411509D03*
X603282Y418569D03*
Y423525D03*
X592880Y425682D03*
X603282Y432743D03*
Y437699D03*
X592880Y439855D03*
Y430638D03*
Y444811D03*
Y468609D03*
Y473565D03*
X603282Y489895D03*
X592880Y487738D03*
X603282Y480677D03*
Y475721D03*
X592880Y482782D03*
X603282Y494851D03*
X592880Y517699D03*
X603282Y519855D03*
X592880Y526916D03*
Y531872D03*
X603282Y524811D03*
Y538984D03*
Y534028D03*
X589603Y952907D03*
X615087Y53597D03*
X633248Y44884D03*
X640109Y103783D03*
X690073Y44662D03*
X697387Y53619D03*
X717387D03*
X723031Y440098D03*
Y437598D03*
Y435098D03*
Y432598D03*
Y430098D03*
X736242Y5374D03*
X735555Y24773D03*
Y44773D03*
X742471Y103783D03*
X755145Y3000D03*
X759029Y332017D03*
X775145Y3000D03*
X775584Y466528D03*
X775583Y471484D03*
Y480701D03*
Y485657D03*
Y515617D03*
Y510661D03*
Y524835D03*
Y529791D03*
Y560701D03*
Y565657D03*
Y579830D03*
Y574874D03*
Y589047D03*
Y594003D03*
Y603221D03*
Y608177D03*
X791129Y4469D03*
X792490Y24773D03*
Y44773D03*
X799811Y53597D03*
X785985Y473640D03*
Y487813D03*
Y478596D03*
Y492769D03*
Y517774D03*
Y522730D03*
Y531947D03*
Y536903D03*
Y572769D03*
Y567813D03*
Y581987D03*
Y586943D03*
Y601116D03*
Y596160D03*
Y615289D03*
Y610333D03*
X806318Y1401661D03*
X806874Y1447457D03*
X812474D03*
X806874Y1452587D03*
Y1457717D03*
X812474D03*
X815096Y1464387D03*
X812009Y1473432D03*
Y1470432D03*
X815096Y1467387D03*
X812096Y1479587D03*
Y1476587D03*
X815096Y1473387D03*
Y1479587D03*
Y1476587D03*
Y1470387D03*
X819811Y53597D03*
X829791Y839020D03*
X825721Y836666D03*
X823234Y867680D03*
X825774Y895553D03*
X816648Y1377608D03*
X817974Y1447457D03*
Y1452587D03*
Y1457717D03*
X818096Y1464387D03*
X821096D03*
X818096Y1473387D03*
X821096D03*
X824096D03*
X818096Y1479587D03*
X821096D03*
X824096D03*
X818096Y1476587D03*
X821096D03*
X824096D03*
X818096Y1467387D03*
Y1470387D03*
X821096D03*
Y1467387D03*
X824096D03*
Y1470387D03*
X838606Y5374D03*
X837919Y24773D03*
Y44773D03*
X844833Y103783D03*
X833185Y456309D03*
Y452309D03*
Y448309D03*
X850145Y3000D03*
X857973Y404867D03*
X862522Y400229D03*
X862566Y404867D03*
X857928Y400184D03*
X862020Y410899D03*
X862882Y468791D03*
Y465991D03*
X854882D03*
Y468791D03*
X861468Y491303D03*
X859071Y1447459D03*
X864671D03*
X859071Y1452589D03*
Y1457719D03*
X864671D03*
X864644Y1464759D03*
X861644D03*
X855644D03*
X858644D03*
Y1467759D03*
X855644Y1470759D03*
X858644D03*
X864644Y1467759D03*
Y1470759D03*
X861644Y1467759D03*
Y1470759D03*
X855644Y1467759D03*
Y1473759D03*
X858644D03*
X864644D03*
X861644D03*
X855644Y1476759D03*
X858644D03*
X864644D03*
X861644D03*
X872736Y383125D03*
X872318Y408589D03*
X866128Y417532D03*
X869342Y417399D03*
X880910Y471982D03*
Y469182D03*
Y466382D03*
X870882Y465991D03*
Y468791D03*
X878610Y747171D03*
X871294Y771809D03*
X871624Y1213314D03*
X874624D03*
X871624Y1221714D03*
Y1218914D03*
Y1216114D03*
X874624Y1221714D03*
Y1218914D03*
Y1216114D03*
X871624Y1224514D03*
X874624D03*
X870171Y1447459D03*
Y1452589D03*
Y1457719D03*
X867644Y1464759D03*
X870644D03*
X867644Y1467759D03*
X870644D03*
X867644Y1470759D03*
X870644D03*
X867644Y1473759D03*
X870644D03*
X867644Y1476759D03*
X870644D03*
X884736Y383125D03*
X893736D03*
X888736D03*
X891699Y420445D03*
Y423245D03*
X890903Y469182D03*
Y471982D03*
Y466382D03*
X896431Y534093D03*
X897118Y857891D03*
Y864189D03*
Y854742D03*
X893968Y864189D03*
Y857891D03*
Y854742D03*
X897118Y873638D03*
Y870488D03*
Y867338D03*
X893968Y870488D03*
Y873638D03*
Y867338D03*
X887669Y876787D03*
X888650Y1199622D03*
X893328Y1212887D03*
X912278Y343881D03*
X910779Y471380D03*
X903431Y534093D03*
X912462Y695770D03*
X912864Y848442D03*
Y845293D03*
Y842143D03*
X909714Y845293D03*
Y842143D03*
X900267Y864189D03*
X909714Y854742D03*
X906565Y857891D03*
X909714D03*
X906565Y864189D03*
X909714D03*
X906565Y854742D03*
X900267Y857891D03*
Y854742D03*
X912864Y851592D03*
Y857891D03*
Y854742D03*
X909714Y873638D03*
Y870488D03*
X906565Y873638D03*
Y870488D03*
Y867338D03*
X900267Y873638D03*
Y870488D03*
Y867338D03*
X909714D03*
X912171Y1447459D03*
X906671D03*
X901071D03*
X912171Y1457719D03*
Y1452589D03*
X906671Y1457719D03*
X901071D03*
Y1452589D03*
X908370Y1464583D03*
X905370D03*
X899370D03*
X902370D03*
X911370D03*
X905370Y1476583D03*
X908370D03*
X902370D03*
X899370D03*
X905370Y1473583D03*
X908370D03*
X902370D03*
X899370D03*
X902370Y1467583D03*
X899370Y1470583D03*
X902370D03*
X908370Y1467583D03*
Y1470583D03*
X905370Y1467583D03*
Y1470583D03*
X899370Y1467583D03*
X911370Y1476583D03*
Y1473583D03*
Y1467583D03*
Y1470583D03*
X930145Y3000D03*
X921847Y346622D03*
X927636Y452505D03*
X929050Y450316D03*
X928612Y835844D03*
X922313Y851592D03*
X929611Y858669D03*
X914370Y1464583D03*
Y1476583D03*
Y1473583D03*
Y1467583D03*
Y1470583D03*
X941129Y4469D03*
X942490Y24773D03*
Y44773D03*
X931620Y584417D03*
X931594Y599420D03*
X931647Y593271D03*
X931578Y590669D03*
X933810Y972433D03*
X935601Y1221714D03*
Y1218914D03*
Y1216114D03*
Y1213314D03*
X938601Y1221714D03*
Y1218914D03*
Y1216114D03*
Y1213314D03*
X935601Y1224514D03*
X938601D03*
X949811Y53597D03*
X956365Y641817D03*
X950865D03*
X950567Y927654D03*
X952627Y1199622D03*
X957305Y1212887D03*
X969811Y53597D03*
X976763Y307303D03*
X969623Y405614D03*
X963577Y426391D03*
X974406Y521804D03*
Y524304D03*
X970713Y531378D03*
Y528878D03*
X976962Y608311D03*
X980683Y628242D03*
X972278Y934429D03*
X988606Y5374D03*
X987919Y24773D03*
Y44773D03*
X994833Y103783D03*
X993132Y310942D03*
X993243Y321325D03*
X987055Y320273D03*
X993920Y335454D03*
X993420Y337954D03*
X992206Y478586D03*
Y481086D03*
Y483886D03*
X980544Y482134D03*
Y484634D03*
X992206Y476086D03*
X983989Y475946D03*
Y478446D03*
X982375Y522129D03*
Y527129D03*
Y524629D03*
Y529929D03*
X1007508Y3000D03*
X1004635Y300276D03*
X1008635D03*
X998667Y322239D03*
X1000420Y348954D03*
X1010119Y933822D03*
X1006619D03*
X1013683Y-44304D03*
Y-39348D03*
Y-29348D03*
Y-34304D03*
X1027508Y3000D03*
X1021895Y771974D03*
X1019519Y937922D03*
X1023319D03*
X1017619Y932122D03*
X1023519Y951522D03*
X1018919D03*
X1043492Y4469D03*
X1041496Y300276D03*
X1031354Y322905D03*
X1031219Y949922D03*
X1044853Y24773D03*
Y44773D03*
X1052174Y53597D03*
X1046674Y340031D03*
X1045966Y346808D03*
X1052367Y402291D03*
Y397335D03*
X1049967Y416465D03*
Y411509D03*
Y425682D03*
Y439855D03*
Y430638D03*
Y444811D03*
Y468609D03*
Y473565D03*
Y487738D03*
Y482782D03*
Y512743D03*
Y517699D03*
Y526916D03*
Y531872D03*
X1072174Y53597D03*
X1060369Y390223D03*
Y395179D03*
Y404396D03*
Y409352D03*
Y418569D03*
Y423525D03*
Y432743D03*
Y437699D03*
Y489895D03*
Y480677D03*
Y475721D03*
Y494851D03*
Y519855D03*
Y524811D03*
Y538984D03*
Y534028D03*
X1083683Y-78528D03*
Y-83484D03*
Y-73484D03*
Y-68528D03*
X1090280Y44773D03*
X1083483Y1523433D03*
X1097195Y103783D03*
X1147214Y44773D03*
X1154535Y53597D03*
X1174535D03*
X1176858Y306534D03*
X1180118Y430098D03*
Y440098D03*
Y437598D03*
Y435098D03*
Y432598D03*
X1193330Y5374D03*
X1192643Y24773D03*
Y44773D03*
X1199557Y103783D03*
X1192500Y322400D03*
X1199615Y950670D03*
X1201794Y985289D03*
X1212232Y3000D03*
X1221337Y332017D03*
X1232232Y3000D03*
X1232670Y466528D03*
Y471484D03*
Y480701D03*
Y485657D03*
Y515617D03*
Y510661D03*
Y524835D03*
Y529791D03*
Y565657D03*
Y560701D03*
Y579830D03*
Y589047D03*
Y574874D03*
Y603221D03*
Y594003D03*
Y608177D03*
X1248216Y4469D03*
X1249577Y24773D03*
Y44773D03*
X1243072Y473640D03*
Y487813D03*
Y478596D03*
Y492769D03*
Y522730D03*
Y517774D03*
Y536903D03*
Y531947D03*
Y567813D03*
Y572769D03*
Y586943D03*
Y581987D03*
Y601116D03*
Y596160D03*
Y610333D03*
Y615289D03*
X1256898Y53597D03*
X1266219Y374300D03*
X1268659Y377173D03*
X1276898Y53597D03*
X1275940Y392228D03*
X1271346Y392183D03*
X1275407Y402867D03*
X1271391Y396866D03*
X1275984D03*
X1282760Y409016D03*
X1278724Y409032D03*
X1272215Y442518D03*
Y439718D03*
X1282092Y449118D03*
Y446318D03*
X1283455Y468088D03*
Y465288D03*
X1300183Y-44434D03*
Y-29478D03*
Y-34434D03*
Y-39478D03*
X1302232Y3000D03*
X1295692Y5374D03*
X1303229Y23274D03*
X1295005Y24773D03*
X1297785Y30618D03*
X1295005Y44773D03*
X1301919Y103783D03*
X1303158Y371043D03*
X1299410Y370976D03*
X1291165Y395248D03*
X1290092Y449118D03*
Y446318D03*
X1299757Y450041D03*
Y452841D03*
Y455641D03*
X1290272Y458309D03*
Y454309D03*
Y462309D03*
X1310546Y409904D03*
Y407104D03*
X1309750Y455641D03*
Y450041D03*
Y452841D03*
X1311488Y479560D03*
X1309856Y899161D03*
X1305761D03*
X1313756D03*
X1322232Y3000D03*
X1320903Y370995D03*
X1333331Y370905D03*
X1329064Y370951D03*
X1329626Y455039D03*
X1340183Y-83484D03*
Y-78528D03*
Y-68528D03*
Y-73484D03*
X1342232Y3000D03*
X1338287Y370905D03*
X1347897Y433975D03*
X1346483Y436164D03*
X1362232Y3000D03*
X1382232D03*
X1373748Y397758D03*
X1375375Y428995D03*
X1398216Y4469D03*
X1399577Y24773D03*
Y44773D03*
X1397550Y390484D03*
X1387814Y397136D03*
X1389295Y408443D03*
X1386809Y414173D03*
X1388788Y428348D03*
X1406898Y53597D03*
X1416830Y407134D03*
X1411400Y398032D03*
X1413889Y415642D03*
X1413452Y641817D03*
X1407952D03*
X1426898Y53597D03*
X1431493Y521804D03*
X1427800Y528578D03*
X1431493Y524304D03*
X1427800Y531378D03*
X1422176Y1491198D03*
X1423806Y1524252D03*
X1445692Y5374D03*
X1445005Y24773D03*
Y44773D03*
X1440568Y369566D03*
X1449619Y363290D03*
X1438588Y380589D03*
X1437631Y482134D03*
Y484634D03*
X1449293Y476086D03*
X1441076Y475946D03*
Y478446D03*
X1449293Y478586D03*
Y481086D03*
Y483886D03*
X1439462Y522129D03*
Y529929D03*
Y527129D03*
Y524629D03*
X1434049Y608311D03*
X1437770Y628242D03*
X1464594Y3000D03*
X1462675Y14334D03*
X1451920Y103783D03*
X1455979Y391756D03*
X1458212Y403374D03*
X1473364Y410724D03*
X1472403Y417338D03*
X1469293Y428815D03*
X1484594Y3000D03*
X1498446Y912370D03*
X1497208Y909740D03*
X1500578Y4469D03*
X1501939Y24773D03*
Y44773D03*
X1509260Y53597D03*
X1509454Y402291D03*
Y397335D03*
X1507054Y416465D03*
Y411509D03*
Y425682D03*
Y439855D03*
Y430638D03*
Y444811D03*
Y468609D03*
Y473565D03*
Y487738D03*
Y482782D03*
Y517699D03*
Y512743D03*
Y526916D03*
Y531872D03*
X1507034Y888133D03*
X1507358Y909740D03*
X1507305Y912262D03*
X1501400Y966000D03*
X1529260Y53597D03*
X1517456Y390223D03*
Y395179D03*
Y404396D03*
Y409352D03*
Y418569D03*
Y423525D03*
Y432743D03*
Y437699D03*
Y489895D03*
Y480677D03*
Y475721D03*
Y494851D03*
Y519855D03*
Y538984D03*
Y524811D03*
Y534028D03*
X1516283Y912240D03*
X1519116D03*
X1523053Y912262D03*
X1525022Y957340D03*
X1547367Y44773D03*
X1554282Y103783D03*
X1594683Y-83484D03*
Y-78528D03*
Y-68528D03*
Y-73484D03*
X1584683Y-44564D03*
Y-29608D03*
Y-34564D03*
Y-39608D03*
X1604301Y44773D03*
X1611622Y53597D03*
X1631622D03*
X1637205Y440098D03*
Y437598D03*
Y435098D03*
Y432598D03*
Y430098D03*
X1650417Y5374D03*
X1649730Y24773D03*
Y44773D03*
X1656644Y103783D03*
X1669319Y3001D03*
X1673203Y332017D03*
X1689319Y3001D03*
X1689757Y466528D03*
Y471484D03*
Y480701D03*
Y485657D03*
Y515617D03*
Y510661D03*
Y524835D03*
Y529791D03*
Y565657D03*
Y560701D03*
Y589047D03*
Y574874D03*
Y579830D03*
Y603221D03*
Y594003D03*
Y608177D03*
X1705303Y4470D03*
X1706664Y24774D03*
Y44774D03*
X1700159Y473640D03*
Y487813D03*
Y478596D03*
Y492769D03*
Y517774D03*
Y522730D03*
Y536903D03*
Y531947D03*
Y572769D03*
Y567813D03*
Y586943D03*
Y581987D03*
Y601116D03*
Y596160D03*
Y610333D03*
Y615289D03*
X1713985Y53598D03*
X1725746Y377173D03*
X1723964Y370935D03*
X1733985Y53598D03*
X1733027Y392228D03*
X1728433Y392183D03*
X1739847Y409016D03*
X1735811Y409032D03*
X1732494Y402867D03*
X1728478Y396866D03*
X1733071D03*
X1729302Y439718D03*
Y442518D03*
X1739179Y449118D03*
Y446318D03*
X1740542Y468088D03*
Y465288D03*
X1752778Y5374D03*
X1752091Y24773D03*
Y44773D03*
X1756497Y370976D03*
X1748252Y395248D03*
X1756844Y450041D03*
Y452841D03*
Y455641D03*
X1747179Y449118D03*
Y446318D03*
X1747359Y454309D03*
Y458309D03*
Y462309D03*
X1765559Y3001D03*
X1759006Y103783D03*
X1760497Y371070D03*
X1767633Y409904D03*
Y407104D03*
X1766837Y450041D03*
Y452841D03*
Y455641D03*
X1768575Y479560D03*
X1773600Y888100D03*
X1773614Y895275D03*
X1773600Y902800D03*
X1786713Y455039D03*
X1788400Y888100D03*
X1781000Y888087D03*
X1788396Y895066D03*
X1788300Y902800D03*
X1780665Y902796D03*
X1781263Y964660D03*
X1784763D03*
X1779581Y1222200D03*
Y1219400D03*
Y1216600D03*
Y1213800D03*
X1782581Y1222200D03*
Y1219400D03*
Y1216600D03*
Y1213800D03*
X1779581Y1225000D03*
X1782581D03*
X1804984Y433975D03*
X1803570Y436164D03*
X1794163Y968760D03*
X1797963D03*
X1792263Y962960D03*
X1798163Y982360D03*
X1793563D03*
X1805863Y980760D03*
X1796607Y1200108D03*
X1801285Y1213373D03*
X1822983Y346053D03*
Y366053D03*
Y386053D03*
Y406053D03*
Y426053D03*
Y446053D03*
Y466053D03*
Y486053D03*
Y506053D03*
Y526053D03*
Y546053D03*
Y566053D03*
Y586053D03*
Y606053D03*
Y626053D03*
Y646053D03*
Y666053D03*
Y686053D03*
Y706053D03*
Y726053D03*
Y746053D03*
Y766053D03*
Y786053D03*
Y806053D03*
Y826053D03*
Y846053D03*
Y866053D03*
Y886053D03*
Y906053D03*
Y926053D03*
Y946053D03*
X1825559Y3001D03*
X1836543Y4470D03*
X1837904Y24774D03*
Y44774D03*
Y64774D03*
Y84774D03*
Y104774D03*
Y124774D03*
Y144774D03*
Y164774D03*
Y184774D03*
Y204774D03*
Y224774D03*
Y244774D03*
Y264774D03*
Y284774D03*
Y304774D03*
X1837728Y324733D03*
X1830094Y333210D03*
X1830472Y960970D03*
X1837937Y973244D03*
Y993244D03*
Y1013244D03*
Y1033244D03*
Y1053244D03*
Y1073244D03*
X1824733Y1102830D03*
X1837937Y1093244D03*
X1825832Y1097589D03*
X1837937Y1113244D03*
Y1133244D03*
Y1153244D03*
Y1173244D03*
Y1193244D03*
Y1213244D03*
Y1253244D03*
Y1273244D03*
Y1293244D03*
Y1313244D03*
Y1333244D03*
Y1353244D03*
Y1373244D03*
Y1393244D03*
Y1433244D03*
Y1453244D03*
Y1473244D03*
Y1493244D03*
Y1513244D03*
Y1533244D03*
Y1553244D03*
Y1573244D03*
G54D14*
X20408Y51296D03*
Y55296D03*
X9057Y138939D03*
X19184Y144728D03*
X15184D03*
X15520Y195176D03*
X18320D03*
X13020D03*
X10520D03*
X12880Y203393D03*
X10380D03*
X19068Y206838D03*
X16568D03*
X13606Y1476707D03*
X19365Y1494298D03*
X24316Y67527D03*
Y63527D03*
Y59527D03*
X23184Y144728D03*
X35650Y487982D03*
Y478982D03*
Y483982D03*
Y499982D03*
X25819Y531726D03*
Y536726D03*
Y552726D03*
Y540726D03*
X30410Y1218497D03*
Y1220997D03*
Y1234797D03*
Y1232297D03*
Y1227897D03*
Y1225397D03*
Y1241697D03*
Y1239197D03*
X25674Y1486291D03*
X32195Y1511279D03*
X32079Y1521641D03*
X31237Y1532096D03*
X46240Y109410D03*
X45988Y102323D03*
X46240Y116496D03*
X46931Y130670D03*
X49236Y121658D03*
X46932Y137756D03*
X49839Y546830D03*
X44195Y1511279D03*
X39237Y1532096D03*
X64098Y102323D03*
Y109410D03*
Y116496D03*
Y123583D03*
Y130670D03*
Y137756D03*
X69139Y236611D03*
X68841Y248891D03*
X66224Y473045D03*
X58224D03*
X53643Y472905D03*
X59670Y500086D03*
X64495Y527449D03*
X61695D03*
X60554Y1612002D03*
X66291Y1633801D03*
X74139Y236611D03*
X71639D03*
X71341Y248891D03*
X73841D03*
X74326Y480705D03*
X71995Y532749D03*
X74795D03*
X74291Y1633801D03*
X86291D03*
X119582Y102249D03*
X111582D03*
X115582D03*
X115382Y195176D03*
X112882D03*
X117882D03*
X115242Y203393D03*
X112742D03*
X120682Y195176D03*
X118930Y206838D03*
X121430D03*
X148602Y109410D03*
Y116496D03*
X148350Y102323D03*
X148774Y124576D03*
X149827Y130670D03*
X149822Y137756D03*
X166460Y116496D03*
Y109410D03*
Y102323D03*
Y123583D03*
Y130670D03*
Y137756D03*
X174001Y236611D03*
X176501D03*
X171501D03*
X176203Y248891D03*
X173703D03*
X171203D03*
X185169Y389154D03*
Y396240D03*
X186448Y404911D03*
X186589Y426299D03*
X185402Y412571D03*
X186900Y445847D03*
X185169Y467539D03*
Y474626D03*
X185430Y480828D03*
X187380Y498834D03*
X185169Y518760D03*
Y511673D03*
Y525847D03*
X191125Y602400D03*
Y598400D03*
Y594400D03*
Y606400D03*
Y614400D03*
X203591Y91951D03*
X213944Y102249D03*
X215244Y195176D03*
X215104Y203393D03*
X203280Y389154D03*
Y396240D03*
Y403327D03*
Y410413D03*
Y417500D03*
Y424586D03*
Y431673D03*
Y438760D03*
Y445847D03*
Y467539D03*
Y474626D03*
Y488799D03*
Y481713D03*
Y495886D03*
Y511673D03*
Y518760D03*
Y525847D03*
Y532933D03*
Y540020D03*
Y547106D03*
Y554193D03*
Y602205D03*
Y595118D03*
X221944Y102249D03*
X217944D03*
X220244Y195176D03*
X217744D03*
X223044D03*
X223792Y206838D03*
X221292D03*
X217604Y203393D03*
X228267Y392718D03*
Y408718D03*
Y400718D03*
Y404718D03*
Y412718D03*
X250964Y109410D03*
X250712Y102323D03*
X250964Y116496D03*
X251136Y124576D03*
X252189Y130670D03*
X252184Y137756D03*
X268822Y116496D03*
Y109410D03*
Y102323D03*
Y130670D03*
Y123583D03*
Y137756D03*
X276363Y236611D03*
X278863D03*
X273863D03*
X276065Y248891D03*
X273565D03*
X278565D03*
X274205Y466027D03*
X274347Y475262D03*
Y489435D03*
Y482666D03*
X274163Y495088D03*
X274205Y509626D03*
X274820Y522134D03*
X274898Y514608D03*
X275463Y529136D03*
X275302Y535677D03*
X274586Y565574D03*
X274205Y559665D03*
X274233Y574338D03*
X274332Y616358D03*
X292500Y410394D03*
Y403307D03*
X284295Y430760D03*
X284316Y433570D03*
X284132Y437072D03*
X284173Y439963D03*
X284417Y443180D03*
X284437Y454744D03*
X284379Y452018D03*
X292316Y458406D03*
Y465492D03*
Y472579D03*
Y479665D03*
Y486752D03*
Y493839D03*
Y523799D03*
Y516713D03*
Y509626D03*
Y537973D03*
Y530886D03*
Y559665D03*
Y566752D03*
Y573839D03*
Y588012D03*
Y580925D03*
Y595099D03*
Y602185D03*
Y616358D03*
Y609272D03*
X324306Y102249D03*
X320306D03*
X316306D03*
X322606Y195176D03*
X325406D03*
X320106D03*
X317606D03*
X323654Y206838D03*
X319966Y203393D03*
X317466D03*
X326154Y206838D03*
X319857Y321649D03*
X324291Y556775D03*
X353074Y102323D03*
X353326Y109410D03*
Y116496D03*
X353498Y124576D03*
X354551Y130670D03*
X354546Y137756D03*
X371184Y116496D03*
Y109410D03*
Y102323D03*
Y130670D03*
Y123583D03*
Y137756D03*
X376225Y236611D03*
X375927Y248891D03*
X373101Y779608D03*
X376300Y779800D03*
X370214Y959812D03*
Y967812D03*
X381225Y236611D03*
X378725D03*
X378427Y248891D03*
X380927D03*
X379800Y778000D03*
X387692Y790056D03*
X393547D03*
X386614Y868286D03*
X385512Y955356D03*
X390150Y955312D03*
Y959905D03*
X385467Y959950D03*
X409268Y408240D03*
X409386Y420393D03*
X400900Y755400D03*
Y770100D03*
X407193Y883566D03*
X396182Y955858D03*
X402682Y948536D03*
X402815Y951750D03*
X404004Y1198321D03*
Y1200821D03*
X407469Y1495035D03*
X407854Y1492118D03*
X406377Y1499142D03*
X411768Y408240D03*
X414268D03*
X411847Y424240D03*
X414386Y420393D03*
X411886D03*
X411847Y426740D03*
X415700Y755400D03*
Y770200D03*
X422430Y834800D03*
X422379Y867229D03*
X420661Y1119422D03*
X423141Y1113822D03*
Y1119422D03*
X418181Y1113822D03*
Y1119422D03*
X420661Y1113822D03*
X417469Y1200821D03*
Y1198321D03*
X439804Y536682D03*
Y539182D03*
X430934Y1200821D03*
Y1198321D03*
X430657Y1563562D03*
X446179Y447101D03*
X448726Y653288D03*
Y646480D03*
Y648980D03*
Y655788D03*
X450244Y1090268D03*
Y1093068D03*
X455269Y1119422D03*
X450309Y1113822D03*
Y1119422D03*
X452789Y1113822D03*
Y1119422D03*
X455269Y1113822D03*
X474307Y102249D03*
X470307D03*
X466307D03*
X470107Y195176D03*
X467607D03*
X472607D03*
X475407D03*
X473655Y206838D03*
X467467Y203393D03*
X469967D03*
X463104Y536582D03*
Y539082D03*
X476155Y206838D03*
X492736Y478982D03*
X482905Y531726D03*
X482737Y537215D03*
X482905Y552726D03*
Y540726D03*
X488728Y1119422D03*
X483768Y1113822D03*
X486248D03*
Y1119422D03*
X483768D03*
X488728Y1113822D03*
X477206Y1198321D03*
X490671D03*
Y1200821D03*
X477206D03*
X503075Y102323D03*
X503327Y109410D03*
Y116496D03*
X506653Y121652D03*
X504552Y130670D03*
X504547Y137756D03*
X493485Y439903D03*
X492736Y487982D03*
Y483982D03*
Y499982D03*
X506925Y546830D03*
X504136Y1198321D03*
Y1200821D03*
X521185Y116496D03*
Y109410D03*
Y102323D03*
Y130670D03*
Y123583D03*
Y137756D03*
X508729Y469905D03*
X521310Y470045D03*
X513310D03*
X516756Y500086D03*
X518781Y527449D03*
X521581D03*
X518812Y665867D03*
X515831Y1090568D03*
Y1093068D03*
X518376Y1113822D03*
Y1119422D03*
X520856Y1113822D03*
Y1119422D03*
X515896Y1113822D03*
Y1119422D03*
X526226Y236611D03*
X531226D03*
X528726D03*
X528428Y248891D03*
X530928D03*
X525928D03*
X531412Y480705D03*
X528612D03*
X529481Y532849D03*
X532281D03*
X533486Y664052D03*
X538442D03*
X524941Y661387D03*
X530796D03*
X572669Y102249D03*
X568669D03*
X572469Y195176D03*
X572329Y203393D03*
X567559Y812850D03*
X576669Y102249D03*
X574969Y195176D03*
X577769D03*
X578517Y206838D03*
X576017D03*
X605437Y102323D03*
X605689Y109410D03*
Y116496D03*
X605861Y124576D03*
X606914Y130670D03*
X606909Y137756D03*
X623547Y109410D03*
Y116496D03*
Y102323D03*
Y123583D03*
Y130670D03*
Y137756D03*
X633588Y236611D03*
X631088D03*
X628588D03*
X630790Y248891D03*
X633290D03*
X628290D03*
X642255Y389154D03*
Y396240D03*
X643534Y404911D03*
X642488Y412571D03*
X643675Y426299D03*
X643986Y445847D03*
X642255Y467539D03*
Y474626D03*
X642516Y480828D03*
X644466Y498834D03*
X642255Y518760D03*
Y511673D03*
Y525847D03*
X648211Y602400D03*
Y598400D03*
Y594400D03*
Y606400D03*
Y614400D03*
X660366Y389154D03*
Y403327D03*
Y410413D03*
Y396240D03*
Y417500D03*
Y424586D03*
Y431673D03*
Y438760D03*
Y445847D03*
Y467539D03*
Y474626D03*
Y488799D03*
Y481713D03*
Y495886D03*
Y511673D03*
Y518760D03*
Y525847D03*
Y532933D03*
Y540020D03*
Y554193D03*
Y547106D03*
Y602205D03*
Y595118D03*
X679031Y102249D03*
X672331Y195176D03*
X674831D03*
X680131D03*
X672191Y203393D03*
X674691D03*
X678379Y206838D03*
X680879D03*
X685353Y392718D03*
Y408718D03*
Y400718D03*
Y404718D03*
Y412718D03*
X707799Y102323D03*
X708051Y109410D03*
Y116496D03*
X708223Y124576D03*
X709276Y130670D03*
X709271Y137756D03*
X725909Y102323D03*
Y116496D03*
Y109410D03*
Y130670D03*
Y123583D03*
Y137756D03*
X733450Y236611D03*
X730950D03*
X733152Y248891D03*
X730652D03*
X731291Y466027D03*
X731433Y475262D03*
Y489435D03*
Y482666D03*
X731249Y495088D03*
X731984Y514608D03*
X731906Y522134D03*
X731291Y509626D03*
X732549Y529136D03*
X732388Y535677D03*
X731291Y559665D03*
X731672Y565574D03*
X731319Y574338D03*
X731418Y616358D03*
X735950Y236611D03*
X735652Y248891D03*
X749586Y410394D03*
Y403307D03*
X741259Y439963D03*
X741381Y430760D03*
X741402Y433570D03*
X741218Y437072D03*
X741503Y443180D03*
X741523Y454744D03*
X741465Y452018D03*
X749402Y458406D03*
Y465492D03*
Y472579D03*
Y479665D03*
Y486752D03*
Y493839D03*
Y523799D03*
Y516713D03*
Y509626D03*
Y537973D03*
Y530886D03*
Y559665D03*
Y566752D03*
Y573839D03*
Y588012D03*
Y580925D03*
Y602185D03*
Y595099D03*
Y609272D03*
Y616358D03*
X751140Y1581335D03*
X740640Y1586885D03*
X748924Y1617709D03*
X735878Y1617010D03*
X763040Y91951D03*
X781393Y102249D03*
X777393D03*
X773393D03*
X779693Y195176D03*
X777193D03*
X782493D03*
X774693D03*
X780741Y206838D03*
X783241D03*
X777053Y203393D03*
X774553D03*
X776943Y321649D03*
X778985Y442498D03*
X778881Y446510D03*
X779029Y450510D03*
X777033Y1595215D03*
X781545Y1602835D03*
X774658Y1601012D03*
X792564Y406410D03*
X784586Y421000D03*
Y418500D03*
Y413500D03*
Y416000D03*
X784665Y564843D03*
X787447Y1593586D03*
X791610Y1593708D03*
X810161Y102323D03*
X810413Y109410D03*
Y116496D03*
X810585Y124576D03*
X811638Y130670D03*
X811633Y137756D03*
X828271Y116496D03*
Y109410D03*
Y102323D03*
Y130670D03*
Y123583D03*
Y137756D03*
X835812Y236611D03*
X838312D03*
X833312D03*
X833014Y248891D03*
X838014D03*
X835514D03*
X867093Y570703D03*
Y582828D03*
Y558703D03*
Y562703D03*
Y566703D03*
Y578703D03*
X872440Y1230083D03*
Y1227583D03*
Y1234483D03*
Y1236983D03*
Y1243883D03*
Y1241383D03*
Y1248283D03*
Y1250783D03*
X889436Y715970D03*
X905094Y424581D03*
X902594D03*
X907594D03*
X905212Y436734D03*
X902712D03*
X907712D03*
X907173Y440581D03*
Y443081D03*
X909024Y578394D03*
Y574394D03*
X909714Y838994D03*
X931393Y102249D03*
X923393D03*
X927393D03*
X925359Y180347D03*
X927859D03*
X925219Y188564D03*
X927719D03*
X919606Y231000D03*
X919577Y245669D03*
Y233858D03*
X919682Y236921D03*
X919577Y259843D03*
Y255118D03*
X919729Y274580D03*
X930359Y180347D03*
X933159D03*
X931407Y192009D03*
X933907D03*
X941505Y463442D03*
X939827Y531104D03*
X939992Y536726D03*
Y540726D03*
Y552726D03*
X936417Y1234483D03*
Y1236983D03*
Y1230083D03*
Y1227583D03*
Y1243883D03*
Y1241383D03*
Y1248283D03*
Y1250783D03*
X956460Y-35982D03*
X953207Y-35996D03*
X956445Y-38497D03*
X953192Y-38511D03*
X950167Y-37191D03*
X960161Y102323D03*
X960413Y109410D03*
Y116496D03*
X961638Y130670D03*
X961633Y137756D03*
X950315Y464851D03*
X949823Y487982D03*
X949876Y478486D03*
X949823Y483982D03*
Y499982D03*
X978036Y-77691D03*
X978051Y-75176D03*
X975011Y-76371D03*
X978271Y109410D03*
Y102323D03*
Y116496D03*
Y130670D03*
Y123583D03*
X963360Y121459D03*
X978271Y137756D03*
X977150Y328472D03*
Y335472D03*
X967816Y472905D03*
X972397Y472954D03*
X973843Y500086D03*
X978668Y527449D03*
X975868D03*
X964012Y546830D03*
X978857Y1360945D03*
X981289Y-77677D03*
X981304Y-75162D03*
X985812Y236611D03*
X988312D03*
X983312D03*
X983014Y248891D03*
X988014D03*
X985514D03*
X980397Y473045D03*
X985699Y480705D03*
X988499D03*
X989068Y532949D03*
X986268D03*
X981857Y1360945D03*
X978944Y1413859D03*
X981944D03*
X1007611Y1561247D03*
Y1558247D03*
Y1555247D03*
Y1552247D03*
X1004611Y1561247D03*
Y1558247D03*
Y1555247D03*
Y1552247D03*
X1015402Y91951D03*
X1025755Y102249D03*
X1027055Y195176D03*
X1033755Y102249D03*
X1029755D03*
X1032055Y195176D03*
X1029555D03*
X1034855D03*
X1033103Y206838D03*
X1035603D03*
X1029415Y203393D03*
X1062523Y102323D03*
X1062775Y109410D03*
Y116496D03*
X1062947Y124576D03*
X1064000Y130670D03*
X1063995Y137756D03*
X1080633Y102323D03*
Y116496D03*
Y109410D03*
Y130670D03*
Y123583D03*
Y137756D03*
X1085674Y236611D03*
X1088174D03*
X1090674D03*
X1090376Y248891D03*
X1087876D03*
X1085376D03*
X1077855Y327478D03*
X1077252Y323521D03*
Y318565D03*
X1077855Y332434D03*
X1099342Y389154D03*
Y396240D03*
X1100621Y404911D03*
X1099575Y412571D03*
X1100762Y426299D03*
X1101073Y445847D03*
X1099342Y467539D03*
Y474626D03*
X1099603Y480828D03*
X1101553Y498834D03*
X1099342Y518760D03*
Y511673D03*
Y525847D03*
X1105298Y598400D03*
Y602400D03*
Y594400D03*
Y614400D03*
Y606400D03*
X1117764Y91951D03*
X1117453Y389154D03*
Y396240D03*
Y403327D03*
Y410413D03*
Y417500D03*
Y424586D03*
Y431673D03*
Y438760D03*
Y445847D03*
Y467539D03*
Y474626D03*
Y488799D03*
Y481713D03*
Y495886D03*
Y511673D03*
Y518760D03*
Y525847D03*
Y532933D03*
Y540020D03*
Y554193D03*
Y547106D03*
Y602205D03*
Y595118D03*
X1136117Y102249D03*
X1132117D03*
X1128117D03*
X1134417Y195176D03*
X1131917D03*
X1137217D03*
X1129417D03*
X1137965Y206838D03*
X1131777Y203393D03*
X1135465Y206838D03*
X1142440Y404718D03*
Y412718D03*
X1125287Y592897D03*
X1142440Y392718D03*
Y400718D03*
Y408718D03*
X1164885Y102323D03*
X1165137Y109410D03*
Y116496D03*
X1165309Y124576D03*
X1166362Y130670D03*
X1166357Y137756D03*
X1182995Y116496D03*
Y109410D03*
Y102323D03*
Y130670D03*
Y123583D03*
Y137756D03*
X1188036Y236611D03*
X1187738Y248891D03*
X1188378Y466027D03*
X1188520Y475262D03*
Y489435D03*
Y482666D03*
X1188336Y495088D03*
X1189071Y514608D03*
X1188993Y522134D03*
X1188378Y509626D03*
X1189475Y535677D03*
X1189636Y529136D03*
X1188378Y559665D03*
X1188759Y565574D03*
X1188406Y574338D03*
X1188505Y616358D03*
X1190536Y236611D03*
X1193036D03*
X1192738Y248891D03*
X1190238D03*
X1198468Y430760D03*
X1198489Y433570D03*
X1198305Y437072D03*
X1198346Y439963D03*
X1198552Y452018D03*
X1198590Y443180D03*
X1198610Y454744D03*
X1220126Y91951D03*
X1206673Y410394D03*
Y403307D03*
X1206489Y458406D03*
Y465492D03*
Y472579D03*
Y479665D03*
Y486752D03*
Y493839D03*
Y523799D03*
Y516713D03*
Y509626D03*
Y537973D03*
Y530886D03*
Y566752D03*
Y559665D03*
Y580925D03*
Y588012D03*
Y573839D03*
Y602185D03*
Y595099D03*
Y616358D03*
Y609272D03*
X1231336Y-87691D03*
X1234589Y-87777D03*
X1231351Y-85176D03*
X1234604Y-85262D03*
X1228311Y-86371D03*
X1236692Y-48727D03*
X1236707Y-46212D03*
X1233667Y-47421D03*
X1238479Y102249D03*
X1230479D03*
X1234479D03*
X1236779Y195176D03*
X1234279D03*
X1239579D03*
X1231779D03*
X1234139Y203393D03*
X1231639D03*
X1237827Y206838D03*
X1234100Y322924D03*
X1239945Y-48727D03*
X1239960Y-46212D03*
X1240327Y206838D03*
X1241752Y564843D03*
X1267499Y116496D03*
X1267247Y102323D03*
X1267499Y109410D03*
X1267671Y124576D03*
X1268724Y130670D03*
X1268719Y137756D03*
X1259500Y330000D03*
X1285357Y116496D03*
Y109410D03*
Y102323D03*
Y123583D03*
Y130670D03*
Y137756D03*
X1281834Y374839D03*
X1290398Y236611D03*
X1295398D03*
X1292898D03*
X1290100Y248891D03*
X1292600D03*
X1295100D03*
X1301500Y329000D03*
X1292731Y331820D03*
X1300400Y339619D03*
Y344575D03*
X1290066Y804246D03*
X1319000Y566500D03*
Y582500D03*
Y613000D03*
Y629000D03*
Y657500D03*
Y673500D03*
Y704500D03*
Y720500D03*
X1305412Y799061D03*
X1318178Y1198321D03*
Y1200821D03*
X1325941Y408240D03*
X1328441D03*
X1323441D03*
X1326059Y420393D03*
X1326020Y424240D03*
X1323559Y420393D03*
X1328559D03*
X1326020Y426740D03*
X1335802Y896011D03*
X1332355Y1113822D03*
Y1119422D03*
X1334835Y1113822D03*
Y1119422D03*
X1331643Y1200821D03*
Y1198321D03*
X1344768Y769675D03*
X1337315Y1113822D03*
Y1119422D03*
X1345108Y1200821D03*
Y1198321D03*
X1361039Y327099D03*
Y332055D03*
X1364039Y334973D03*
Y339929D03*
X1361039Y342847D03*
X1364039Y350721D03*
X1361039Y347803D03*
X1364039Y355677D03*
X1360352Y447101D03*
X1364148Y896011D03*
X1364418Y1090568D03*
Y1093068D03*
X1366963Y1119422D03*
Y1113822D03*
X1364483Y1119422D03*
Y1113822D03*
X1380480Y102249D03*
X1384480D03*
X1384280Y195176D03*
X1381780D03*
X1384140Y203393D03*
X1381640D03*
X1384253Y346826D03*
X1384447Y356871D03*
X1384174Y362641D03*
X1379896Y870814D03*
Y883413D03*
X1383046Y899161D03*
X1369443Y1119422D03*
Y1113822D03*
X1388480Y102249D03*
X1389580Y195176D03*
X1386780D03*
X1390328Y206838D03*
X1387828D03*
X1385943Y323222D03*
X1385971Y327688D03*
X1386143Y331982D03*
X1386057Y341200D03*
X1385971Y336791D03*
X1386286Y350218D03*
X1397079Y531726D03*
Y536726D03*
Y552726D03*
Y540726D03*
X1397942Y1119422D03*
X1400422D03*
Y1113822D03*
X1397942D03*
X1391380Y1200821D03*
Y1198321D03*
X1417248Y102323D03*
X1416347Y384373D03*
X1406910Y487982D03*
Y478982D03*
Y483982D03*
Y499982D03*
X1410000Y689000D03*
Y705000D03*
Y733000D03*
Y749000D03*
X1402902Y1119422D03*
Y1113822D03*
X1404845Y1198321D03*
Y1200821D03*
X1404239Y1547755D03*
X1403747Y1570433D03*
X1417500Y109410D03*
Y116496D03*
X1421700Y122900D03*
X1418725Y130670D03*
X1418720Y137756D03*
X1427484Y470045D03*
X1422903Y469905D03*
X1430930Y500086D03*
X1432955Y527449D03*
X1421099Y546830D03*
X1427000Y774500D03*
Y790500D03*
Y818500D03*
Y834500D03*
X1430005Y1090568D03*
Y1093068D03*
X1432550Y1119422D03*
Y1113822D03*
X1430070Y1119422D03*
Y1113822D03*
X1418310Y1198321D03*
Y1200821D03*
X1435358Y116496D03*
Y109410D03*
Y102323D03*
Y130670D03*
Y123583D03*
Y137756D03*
X1440399Y236611D03*
X1442899D03*
X1445399D03*
X1440101Y248891D03*
X1442601D03*
X1445101D03*
X1435484Y470045D03*
X1442786Y480705D03*
X1445586D03*
X1435755Y527449D03*
X1443555Y532949D03*
X1446355D03*
X1435030Y1119422D03*
Y1113822D03*
X1437293Y1546125D03*
X1436801Y1568803D03*
X1451215Y323193D03*
X1451330Y327588D03*
X1451272Y340971D03*
X1451344Y336620D03*
X1451300Y332225D03*
X1451387Y345609D03*
X1451186Y350447D03*
X1472489Y91951D03*
X1479500Y706500D03*
Y750500D03*
X1487836Y-87777D03*
X1491089D03*
X1487851Y-85262D03*
X1491104D03*
X1484811Y-86371D03*
X1490842Y102249D03*
X1486842D03*
X1482842D03*
X1486642Y195176D03*
X1489142D03*
X1484142D03*
X1491942D03*
X1492690Y206838D03*
X1490190D03*
X1484002Y203393D03*
X1486502D03*
X1484796Y320359D03*
X1484968Y325025D03*
X1484876Y329377D03*
X1488255Y342921D03*
X1484682Y338394D03*
X1497760Y336543D03*
X1487926Y347387D03*
X1496500Y792000D03*
Y836000D03*
X1500480Y295727D03*
X1523192Y-48857D03*
X1526445D03*
X1523207Y-46342D03*
X1526460D03*
X1520167Y-47451D03*
X1519610Y102323D03*
X1519862Y109410D03*
Y116496D03*
X1520034Y124576D03*
X1521087Y130670D03*
X1521082Y137756D03*
X1527876Y939439D03*
X1537720Y116496D03*
Y109410D03*
Y102323D03*
Y130670D03*
Y123583D03*
Y137756D03*
X1542761Y236611D03*
X1545261D03*
X1542463Y248891D03*
X1544963D03*
X1541534Y322850D03*
X1547761Y236611D03*
X1547463Y248891D03*
X1547972Y304906D03*
X1556151Y318596D03*
X1556294Y327814D03*
X1556437Y332022D03*
X1556380Y336917D03*
X1556498Y340958D03*
X1556353Y345636D03*
X1556429Y389154D03*
Y396240D03*
X1557708Y404911D03*
X1556662Y412571D03*
X1557849Y426299D03*
X1558160Y445847D03*
X1556429Y467539D03*
Y474626D03*
X1556690Y480828D03*
X1558640Y498834D03*
X1556429Y518760D03*
Y511673D03*
Y525847D03*
X1562385Y598400D03*
Y602400D03*
Y594400D03*
Y614400D03*
Y606400D03*
X1574851Y91951D03*
X1574845Y338843D03*
X1574540Y389154D03*
Y396240D03*
Y403327D03*
Y410413D03*
Y417500D03*
Y424586D03*
Y438760D03*
Y431673D03*
Y445847D03*
Y467539D03*
Y474626D03*
Y488799D03*
Y481713D03*
Y495886D03*
Y511673D03*
Y518760D03*
Y540020D03*
Y525847D03*
Y532933D03*
Y547106D03*
Y554193D03*
Y602205D03*
Y595118D03*
X1593204Y102249D03*
X1585204D03*
X1589204D03*
X1586504Y195176D03*
X1594304D03*
X1589004D03*
X1591504D03*
X1586364Y203393D03*
X1588864D03*
X1595052Y206838D03*
X1592552D03*
X1593290Y339876D03*
X1597006Y290417D03*
X1599527Y392718D03*
Y408718D03*
Y400718D03*
Y404718D03*
Y412718D03*
X1621972Y102323D03*
X1622224Y109410D03*
Y116496D03*
X1622396Y124576D03*
X1623449Y130670D03*
X1623444Y137756D03*
X1640082Y116496D03*
Y109410D03*
Y102323D03*
Y130670D03*
Y123583D03*
Y137756D03*
X1644825Y248891D03*
X1632230Y330400D03*
X1645123Y236611D03*
X1650123D03*
X1647623D03*
X1647325Y248891D03*
X1649825D03*
X1655555Y430760D03*
X1655576Y433570D03*
X1655392Y437072D03*
X1655433Y439963D03*
X1655677Y443180D03*
X1655697Y454744D03*
X1655639Y452018D03*
X1645465Y466027D03*
X1645607Y475262D03*
Y489435D03*
Y482666D03*
X1645423Y495088D03*
X1646158Y514608D03*
X1646080Y522134D03*
X1645465Y509626D03*
X1646562Y535677D03*
X1646723Y529136D03*
X1645465Y559665D03*
X1645846Y565574D03*
X1645493Y574338D03*
X1645592Y616358D03*
X1677213Y91951D03*
X1663760Y410394D03*
Y403307D03*
X1663576Y458406D03*
Y465492D03*
Y472579D03*
Y479665D03*
Y486752D03*
Y493839D03*
Y523799D03*
Y516713D03*
Y509626D03*
Y537973D03*
Y530886D03*
Y559665D03*
Y566752D03*
Y580925D03*
Y588012D03*
Y573839D03*
Y602185D03*
Y595099D03*
Y616358D03*
Y609272D03*
X1695566Y102249D03*
X1687566D03*
X1691566D03*
X1691366Y195176D03*
X1688866D03*
X1691226Y203393D03*
X1688726D03*
X1691117Y321649D03*
X1696666Y195176D03*
X1693866D03*
X1697414Y206838D03*
X1694914D03*
X1698839Y564843D03*
X1724334Y102323D03*
X1724586Y109410D03*
Y116496D03*
X1724758Y124576D03*
X1725811Y130670D03*
X1725806Y137756D03*
X1715705Y328692D03*
X1712734Y340534D03*
X1742336Y-87777D03*
X1739311Y-86371D03*
X1734826Y376499D03*
X1745589Y-87777D03*
X1742351Y-85262D03*
X1745604D03*
X1742444Y102323D03*
Y116496D03*
Y109410D03*
Y130670D03*
Y123583D03*
Y137756D03*
X1752485Y236611D03*
X1749985D03*
X1747485D03*
X1747187Y248891D03*
X1749687D03*
X1752187D03*
X1747561Y385161D03*
X1758583Y1581027D03*
X1750685Y1618504D03*
X1756422Y1640303D03*
X1770680Y926322D03*
X1763818Y926241D03*
X1765294Y1575434D03*
X1759092Y1588137D03*
X1767142Y1588219D03*
X1764422Y1640303D03*
X1779575Y91951D03*
X1790533Y303750D03*
X1783028Y408240D03*
X1785528D03*
X1780528D03*
X1783107Y424240D03*
X1780646Y420393D03*
X1785646D03*
X1783146D03*
X1783107Y426740D03*
X1780397Y1237469D03*
Y1230569D03*
Y1228069D03*
Y1234969D03*
Y1241869D03*
Y1244369D03*
Y1248769D03*
Y1251269D03*
X1776422Y1640303D03*
X1804667Y-47581D03*
X1804993Y297591D03*
X1807692Y-49001D03*
X1810945Y-48987D03*
X1807707Y-46486D03*
X1810960Y-46472D03*
X1817439Y447101D03*
G54D30*
X106586Y1204932D03*
X563673D03*
X1020434Y1205579D03*
X1477846Y1204932D03*
G54D38*
X190325Y368760D03*
Y455492D03*
Y503760D03*
Y583957D03*
Y636752D03*
X647411Y368760D03*
Y455492D03*
Y503760D03*
Y583957D03*
Y636752D03*
X1104498Y368760D03*
Y455492D03*
Y503760D03*
Y583957D03*
Y636752D03*
X1561585Y368760D03*
Y455492D03*
Y503760D03*
Y583957D03*
Y636752D03*
G54D43*
X515573Y692515D03*
X518299Y692384D03*
X520799D03*
X529493Y692443D03*
Y697443D03*
Y699943D03*
X529501Y702622D03*
X526993Y692443D03*
X529493Y694943D03*
X524493Y692443D03*
X1809078Y2165771D03*
X1806706Y2180760D03*
X1812366Y2063809D03*
X1822066Y2054109D03*
X1812366D03*
X1813087Y2087512D03*
X1825427Y2104853D03*
X1817378Y2165771D03*
X1815006Y2180760D03*
X1841295Y2065122D03*
X1832995D03*
X1833649Y2057507D03*
X1830872Y2083503D03*
X1840875Y2083215D03*
X1837649Y2072324D03*
X1829349D03*
X1833727Y2104853D03*
X1835862Y2121040D03*
X1833506Y2185252D03*
X1852032Y2052576D03*
X1854559Y2077931D03*
X1851762Y2121040D03*
X1854796Y2170548D03*
X1846496D03*
X1855978Y2185118D03*
X1847678D03*
X1859032Y2052576D03*
X1870505Y2064156D03*
X1860338Y2071384D03*
X1874505Y2078973D03*
X1860234Y2157701D03*
X1867072Y2174962D03*
X1864547Y2185020D03*
X1890039Y2066092D03*
X1878805Y2064156D03*
X1886128Y2075919D03*
X1882805Y2078973D03*
X1876497Y2070684D03*
X1884535Y2155415D03*
X1882972Y2174962D03*
X1882111Y2179074D03*
X1874932Y2180585D03*
X1881852Y2196600D03*
X1886699Y2183170D03*
X1876697D03*
X1905939Y2066092D03*
X1893118Y2054585D03*
X1905944Y2055424D03*
X1898342Y2062143D03*
X1901295Y2072745D03*
X1892835Y2155415D03*
X1902872Y2178531D03*
X1894572D03*
X1893087Y2168011D03*
X1896403Y2185019D03*
X1917195Y2072745D03*
X1917550Y2158451D03*
X1909250D03*
X1922010Y2151829D03*
X1913710D03*
X1921855Y2172152D03*
X1936295Y2074343D03*
X1935195Y2155918D03*
X1936377Y2163810D03*
X1924735Y2178131D03*
X1936212Y2173508D03*
X1930155Y2172152D03*
X1931738Y2182647D03*
X1923438D03*
X1941040Y2070124D03*
X1951095Y2155918D03*
X1946077Y2163810D03*
X1969128Y2161283D03*
X1959428D03*
X1969128Y2151583D03*
X1959428D03*
G54D51*
X909360Y230906D03*
Y274606D03*
G54D22*
X51043Y144095D03*
X57933Y66811D03*
X160295D03*
X153405Y144095D03*
X183435Y630650D03*
X190325Y374862D03*
X262657Y66811D03*
X255767Y144095D03*
X279360Y630650D03*
X286250Y374862D03*
X358129Y144095D03*
X365019Y66811D03*
X508130Y144095D03*
X515020Y66811D03*
X617382D03*
X610492Y144095D03*
X647411Y374862D03*
X640521Y630650D03*
X719744Y66811D03*
X712854Y144095D03*
X736446Y630650D03*
X743336Y374862D03*
X815216Y144095D03*
X822106Y66811D03*
X972106D03*
X965216Y144095D03*
X1074468Y66811D03*
X1067578Y144095D03*
X1104498Y374862D03*
X1097608Y630650D03*
X1169940Y144095D03*
X1176830Y66811D03*
X1200423Y374862D03*
X1193533Y630650D03*
X1272302Y144095D03*
X1279192Y66811D03*
X1429193D03*
X1422303Y144095D03*
X1531555Y66811D03*
X1524665Y144095D03*
X1561585Y374862D03*
X1554695Y630650D03*
X1627027Y144095D03*
X1633917Y66811D03*
X1657510Y374862D03*
X1650620Y630650D03*
X1736279Y66811D03*
X1729389Y144095D03*
G54D25*
X46248Y1760941D03*
Y1750941D03*
Y1806941D03*
Y1796941D03*
X143208Y1084547D03*
Y1092027D03*
X146948Y1077066D03*
Y1084547D03*
Y1092027D03*
X143208Y1095767D03*
X146948D03*
X143208Y1110728D03*
Y1118208D03*
X146948Y1110728D03*
Y1118208D03*
X146949Y1166830D03*
X154429Y1073326D03*
X161909D03*
X154429Y1092027D03*
X161909Y1077066D03*
X165649Y1080807D03*
Y1088287D03*
X161909D03*
Y1092027D03*
X154429Y1077066D03*
X158169Y1080807D03*
X150689D03*
X158169Y1084547D03*
X150689D03*
X158169Y1088287D03*
X154429D03*
X150689D03*
X165649Y1084547D03*
X158169Y1099507D03*
X150689D03*
X158169Y1103247D03*
X150689D03*
X161909Y1095767D03*
X165649Y1099507D03*
Y1103247D03*
X154429Y1106988D03*
X150689D03*
X154429Y1095767D03*
X158169Y1110728D03*
Y1114468D03*
X154429D03*
X150689D03*
X158169Y1129429D03*
X165649Y1166830D03*
Y1170570D03*
Y1178050D03*
Y1174310D03*
X163779Y1213582D03*
X160039D03*
X214271Y1114468D03*
X238582Y1078936D03*
X242322Y1082677D03*
X238582Y1097637D03*
X246062Y1254724D03*
X238582D03*
Y1250984D03*
X234842Y1247243D03*
X242322Y1243503D03*
Y1247243D03*
X246062Y1250984D03*
X249803Y1082677D03*
X257283D03*
X249803Y1101377D03*
X253543Y1250984D03*
Y1254724D03*
X249803Y1247243D03*
X253543Y1239763D03*
X249803D03*
X257283Y1247243D03*
X261023Y1250984D03*
Y1239763D03*
Y1254724D03*
X279724Y1082677D03*
Y1086417D03*
X275984Y1078936D03*
X264763Y1082677D03*
X275984Y1097637D03*
X274114Y1121948D03*
X277854Y1133169D03*
Y1125688D03*
X274114Y1204232D03*
X279724Y1247243D03*
X272244Y1243503D03*
Y1247243D03*
X264763D03*
X268503Y1250984D03*
X264763Y1243503D03*
X272244Y1239763D03*
X275984Y1250984D03*
X279724Y1243503D03*
X268503Y1254724D03*
X275984D03*
X294684Y1082677D03*
Y1090157D03*
X294685Y1086417D03*
X290944Y1078936D03*
X287204Y1082677D03*
X283464Y1093897D03*
X290944Y1097637D03*
X294685Y1247243D03*
Y1243503D03*
X283464Y1250984D03*
X287204Y1247243D03*
Y1243503D03*
Y1239763D03*
X290944Y1250984D03*
X283464Y1254724D03*
X290944D03*
X302164Y1082677D03*
X302165Y1086417D03*
X309644Y1082677D03*
X309645Y1086417D03*
X298425Y1097637D03*
X305905D03*
X300295Y1155610D03*
X309645Y1247243D03*
Y1243503D03*
X298425Y1250984D03*
X302165Y1247243D03*
Y1243503D03*
Y1239763D03*
X305905Y1250984D03*
X298425Y1254724D03*
X305905D03*
X320866Y1086417D03*
X317126D03*
X317125Y1082677D03*
X324606Y1086417D03*
X320866Y1093897D03*
X324606D03*
Y1105117D03*
Y1097637D03*
X320866Y1105117D03*
Y1097637D03*
X313385D03*
X324606Y1112598D03*
Y1120078D03*
X320866Y1112598D03*
Y1120078D03*
X317125Y1108858D03*
X320866Y1127558D03*
Y1135039D03*
X322736Y1140649D03*
X324606Y1127558D03*
Y1135039D03*
X326476Y1140649D03*
X322736Y1155610D03*
X326476Y1148129D03*
Y1155610D03*
X322736Y1148129D03*
X326476Y1170570D03*
Y1178051D03*
Y1185531D03*
X320866Y1250984D03*
X313385D03*
X317125Y1247243D03*
Y1243503D03*
X313385Y1254724D03*
X317125Y1239763D03*
X320866Y1254724D03*
X333286Y1728583D03*
Y1738583D03*
X333212Y1774624D03*
Y1784624D03*
X438162Y1348187D03*
Y1360099D03*
Y1384297D03*
Y1372385D03*
X450402Y1348187D03*
Y1360099D03*
Y1384297D03*
Y1372385D03*
Y1396583D03*
Y1408495D03*
X462642Y1348187D03*
X474882D03*
X462642Y1360099D03*
X474882D03*
X462642Y1384297D03*
X474882D03*
X462642Y1372385D03*
X474882D03*
Y1396583D03*
X462642D03*
X474882Y1408495D03*
X462642D03*
X487122Y1348187D03*
Y1360099D03*
Y1372385D03*
Y1384297D03*
Y1396583D03*
Y1408495D03*
X499362Y1348187D03*
Y1360099D03*
Y1372385D03*
Y1384297D03*
Y1396583D03*
Y1408495D03*
X511602Y1348187D03*
Y1360099D03*
Y1372385D03*
Y1384297D03*
Y1396583D03*
Y1408495D03*
X536082Y1348187D03*
X523842D03*
X536082Y1360099D03*
X523842D03*
Y1384297D03*
Y1372385D03*
X536082Y1384297D03*
Y1372385D03*
Y1396583D03*
X523842D03*
X536082Y1408495D03*
X523842D03*
X548322Y1348187D03*
Y1360099D03*
Y1384297D03*
Y1372385D03*
Y1396583D03*
Y1408495D03*
X560562Y1348187D03*
Y1360099D03*
Y1384297D03*
Y1372385D03*
Y1396583D03*
Y1408495D03*
X600295Y1084547D03*
Y1092027D03*
X604035Y1077066D03*
Y1084547D03*
Y1092027D03*
X600295Y1095767D03*
X604035D03*
X600295Y1110728D03*
Y1118208D03*
X604035Y1110728D03*
Y1118208D03*
X604036Y1166830D03*
X611516Y1073326D03*
X618996D03*
Y1088287D03*
Y1092027D03*
X611516Y1077066D03*
X615256Y1080807D03*
X607776D03*
X615256Y1084547D03*
X607776D03*
X615256Y1088287D03*
X611516D03*
X607776D03*
X611516Y1092027D03*
X618996Y1077066D03*
X611516Y1106988D03*
X607776D03*
X611516Y1095767D03*
X615256Y1099507D03*
X607776D03*
X615256Y1103247D03*
X607776D03*
X618996Y1095767D03*
X615256Y1110728D03*
Y1114468D03*
X611516D03*
X607776D03*
X615256Y1129429D03*
X617126Y1213582D03*
X620866D03*
X620083Y1728286D03*
Y1738286D03*
X619711Y1775438D03*
Y1785438D03*
X626476Y1088287D03*
X622736Y1080807D03*
Y1084547D03*
Y1088287D03*
Y1099507D03*
Y1103247D03*
Y1166830D03*
Y1170570D03*
Y1174310D03*
Y1178050D03*
X636288Y1372385D03*
Y1384297D03*
Y1396583D03*
X624048D03*
X636288Y1408495D03*
X624048D03*
X648528Y1348187D03*
Y1360099D03*
Y1372385D03*
Y1384297D03*
Y1396583D03*
Y1408495D03*
X660768Y1348187D03*
Y1360099D03*
Y1372385D03*
Y1384297D03*
Y1396583D03*
Y1408495D03*
X671358Y1114468D03*
X673008Y1348187D03*
X685248D03*
X673008Y1360099D03*
X685248D03*
Y1372385D03*
Y1384297D03*
X673008Y1372385D03*
Y1384297D03*
X685248Y1396583D03*
X673008D03*
X685248Y1408495D03*
X673008D03*
X695669Y1078936D03*
X699409Y1082677D03*
X695669Y1097637D03*
X699409Y1247243D03*
Y1243503D03*
X691929Y1247243D03*
X695669Y1250984D03*
Y1254724D03*
X697488Y1348187D03*
Y1360099D03*
Y1384297D03*
Y1372385D03*
Y1396583D03*
Y1408495D03*
X706890Y1082677D03*
X714370D03*
X706890Y1101377D03*
X703149Y1254724D03*
Y1250984D03*
X718110D03*
Y1239763D03*
X714370Y1247243D03*
X710630Y1254724D03*
Y1250984D03*
Y1239763D03*
X706890Y1247243D03*
Y1239763D03*
X718110Y1254724D03*
X709728Y1348187D03*
Y1360099D03*
Y1384297D03*
Y1372385D03*
Y1396583D03*
Y1408495D03*
X721850Y1082677D03*
X733071Y1078936D03*
Y1097637D03*
X731201Y1121948D03*
X734941Y1125688D03*
Y1133169D03*
X731201Y1204232D03*
X729331Y1243503D03*
X721850D03*
X729331Y1239763D03*
Y1247243D03*
X733071Y1250984D03*
Y1254724D03*
X725590D03*
Y1250984D03*
X721850Y1247243D03*
X734208Y1348187D03*
X721968D03*
X734208Y1360099D03*
X721968D03*
Y1384297D03*
Y1372385D03*
X734208D03*
Y1384297D03*
X721968Y1396489D03*
X734208D03*
X721968Y1408401D03*
X734208D03*
X744291Y1082677D03*
X748031Y1078936D03*
X736811Y1086417D03*
Y1082677D03*
X748031Y1097637D03*
X740551Y1093897D03*
X736811Y1243503D03*
Y1247243D03*
X744291Y1243503D03*
Y1239763D03*
X748031Y1254724D03*
Y1250984D03*
X744291Y1247243D03*
X740551Y1254724D03*
Y1250984D03*
X746448Y1348187D03*
Y1360099D03*
Y1372385D03*
Y1384297D03*
X759251Y1082677D03*
X751772Y1086417D03*
X751771Y1090157D03*
Y1082677D03*
X759252Y1086417D03*
X766732D03*
X766731Y1082677D03*
X762992Y1097637D03*
X755512D03*
X757382Y1155610D03*
X755512Y1250984D03*
Y1254724D03*
X759252Y1247243D03*
Y1243503D03*
X762992Y1250984D03*
Y1254724D03*
X766732Y1247243D03*
Y1243503D03*
X759252Y1239763D03*
X751772Y1247243D03*
Y1243503D03*
X758688Y1348187D03*
Y1360099D03*
Y1372385D03*
Y1384297D03*
X774213Y1086417D03*
X774212Y1082677D03*
X781693Y1086417D03*
X777953D03*
X770472Y1097637D03*
X777953Y1093897D03*
Y1105117D03*
X781693Y1093897D03*
Y1097637D03*
X777953D03*
X781693Y1105117D03*
Y1112598D03*
X777953Y1120078D03*
X781693D03*
X774212Y1108858D03*
X777953Y1112598D03*
X783563Y1140649D03*
X779823D03*
X781693Y1127558D03*
X777953D03*
Y1135039D03*
X781693D03*
X783563Y1155610D03*
Y1148129D03*
X779823Y1155610D03*
Y1148129D03*
X783563Y1170570D03*
Y1185531D03*
Y1178051D03*
X770472Y1250984D03*
Y1254724D03*
X777953Y1250984D03*
X774212Y1247243D03*
Y1243503D03*
Y1239763D03*
X777953Y1254724D03*
X770928Y1348187D03*
Y1360099D03*
X907279Y1738990D03*
Y1728990D03*
X907073Y1776014D03*
Y1786014D03*
X1057381Y1092027D03*
Y1084547D03*
Y1095767D03*
Y1118208D03*
Y1110728D03*
X1068602Y1073326D03*
X1072342Y1088287D03*
Y1084547D03*
Y1080807D03*
X1061121Y1092027D03*
X1068602D03*
X1064862Y1088287D03*
X1068602D03*
X1061121Y1084547D03*
X1064862D03*
Y1080807D03*
X1061121Y1077066D03*
X1068602D03*
X1072342Y1099507D03*
Y1103247D03*
X1061121Y1095767D03*
X1068602D03*
X1064862Y1106988D03*
X1068602D03*
X1064862Y1103247D03*
Y1099507D03*
X1072342Y1114468D03*
Y1110728D03*
X1061121Y1118208D03*
X1064862Y1114468D03*
X1068602D03*
X1061121Y1110728D03*
X1072342Y1129429D03*
X1061122Y1166830D03*
X1074212Y1213582D03*
X1076082Y1073326D03*
X1083562Y1088287D03*
X1079822D03*
Y1084547D03*
Y1080807D03*
X1076082Y1092027D03*
Y1088287D03*
Y1077066D03*
X1079822Y1103247D03*
Y1099507D03*
X1076082Y1095767D03*
X1079822Y1170570D03*
Y1166830D03*
Y1174310D03*
Y1178050D03*
X1077952Y1213582D03*
X1128444Y1114468D03*
X1152755Y1078936D03*
X1156495Y1082677D03*
X1152755Y1097637D03*
Y1254724D03*
Y1250984D03*
X1149015Y1247243D03*
X1156495Y1243503D03*
Y1247243D03*
X1163976Y1082677D03*
X1171456D03*
X1163976Y1101377D03*
Y1239763D03*
Y1247243D03*
X1167716Y1239763D03*
Y1250984D03*
Y1254724D03*
X1171456Y1247243D03*
X1160235Y1250984D03*
Y1254724D03*
X1178936Y1082677D03*
X1188287Y1121948D03*
Y1204232D03*
X1175196Y1254724D03*
Y1239763D03*
Y1250984D03*
X1178936Y1247243D03*
X1182676Y1250984D03*
Y1254724D03*
X1186417Y1247243D03*
Y1239763D03*
X1178936Y1243503D03*
X1186417D03*
X1190157Y1078936D03*
X1201377Y1082677D03*
X1205117Y1078936D03*
X1193897Y1082677D03*
Y1086417D03*
X1190157Y1097637D03*
X1197637Y1093897D03*
X1205117Y1097637D03*
X1192027Y1133169D03*
Y1125688D03*
X1190157Y1254724D03*
Y1250984D03*
X1197637D03*
Y1254724D03*
X1201377Y1247243D03*
X1205117Y1250984D03*
Y1254724D03*
X1201377Y1239763D03*
Y1243503D03*
X1193897Y1247243D03*
Y1243503D03*
X1216337Y1082677D03*
X1216338Y1086417D03*
X1208857Y1082677D03*
X1208858Y1086417D03*
X1208857Y1090157D03*
X1212598Y1097637D03*
X1220078D03*
X1214468Y1155610D03*
X1212598Y1250984D03*
Y1254724D03*
X1216338Y1247243D03*
Y1243503D03*
X1220078Y1250984D03*
Y1254724D03*
X1216338Y1239763D03*
X1208858Y1247243D03*
Y1243503D03*
X1223817Y1082677D03*
X1223818Y1086417D03*
X1231298Y1082677D03*
X1235039Y1086417D03*
X1231299D03*
X1227558Y1097637D03*
X1235039Y1093897D03*
Y1097637D03*
Y1105117D03*
X1231298Y1108858D03*
X1235039Y1112598D03*
Y1120078D03*
X1236909Y1140649D03*
X1235039Y1127558D03*
Y1135039D03*
X1236909Y1148129D03*
Y1155610D03*
X1223818Y1247243D03*
Y1243503D03*
X1227558Y1250984D03*
Y1254724D03*
X1235039Y1250984D03*
X1231298Y1247243D03*
Y1243503D03*
Y1239763D03*
X1235039Y1254724D03*
X1238779Y1086417D03*
Y1093897D03*
Y1097637D03*
Y1105117D03*
Y1112598D03*
Y1120078D03*
X1240649Y1140649D03*
X1238779Y1127558D03*
Y1135039D03*
X1240649Y1148129D03*
Y1155610D03*
Y1170570D03*
Y1178051D03*
Y1185531D03*
X1514468Y1084547D03*
Y1092027D03*
Y1095767D03*
Y1110728D03*
Y1118208D03*
X1525689Y1073326D03*
Y1077066D03*
X1518208D03*
X1529429Y1080807D03*
X1521949D03*
X1529429Y1084547D03*
X1521949D03*
X1518208D03*
X1529429Y1088287D03*
X1525689D03*
X1521949D03*
X1525689Y1092027D03*
X1518208D03*
X1521949Y1103247D03*
X1525689Y1106988D03*
X1521949D03*
X1525689Y1095767D03*
X1518208D03*
X1529429Y1099507D03*
X1521949D03*
X1529429Y1103247D03*
Y1110728D03*
X1518208D03*
X1529429Y1114468D03*
X1525689D03*
X1521949D03*
X1518208Y1118208D03*
X1529429Y1129429D03*
X1518209Y1166830D03*
X1533169Y1073326D03*
X1540649Y1088287D03*
X1533169Y1077066D03*
X1536909Y1080807D03*
Y1084547D03*
Y1088287D03*
X1533169D03*
Y1092027D03*
Y1095767D03*
X1536909Y1099507D03*
Y1103247D03*
Y1166830D03*
Y1170570D03*
Y1174310D03*
X1535039Y1176180D03*
Y1213582D03*
X1531299D03*
X1585531Y1114468D03*
X1609842Y1078936D03*
Y1097637D03*
Y1254724D03*
Y1250984D03*
X1606102Y1247243D03*
X1613582Y1082677D03*
X1621063D03*
Y1101377D03*
X1613582Y1243503D03*
Y1247243D03*
X1621063Y1239763D03*
Y1247243D03*
X1624803Y1239763D03*
Y1250984D03*
Y1254724D03*
X1617322Y1250984D03*
Y1254724D03*
X1636023Y1082677D03*
X1628543D03*
X1632283Y1254724D03*
X1628543Y1247243D03*
X1632283Y1239763D03*
Y1250984D03*
X1636023Y1247243D03*
X1639763Y1250984D03*
Y1254724D03*
X1643504Y1247243D03*
Y1239763D03*
X1636023Y1243503D03*
X1643504D03*
X1658464Y1082677D03*
X1650984D03*
Y1086417D03*
X1647244Y1078936D03*
Y1097637D03*
X1654724Y1093897D03*
X1645374Y1121948D03*
X1649114Y1133169D03*
Y1125688D03*
X1645374Y1204232D03*
X1647244Y1254724D03*
Y1250984D03*
X1654724D03*
Y1254724D03*
X1658464Y1247243D03*
Y1239763D03*
Y1243503D03*
X1650984Y1247243D03*
Y1243503D03*
X1662204Y1078936D03*
X1673424Y1082677D03*
X1673425Y1086417D03*
X1665944Y1082677D03*
X1665945Y1086417D03*
X1665944Y1090157D03*
X1662204Y1097637D03*
X1669685D03*
X1671555Y1155610D03*
X1665945Y1247243D03*
Y1243503D03*
X1662204Y1250984D03*
Y1254724D03*
X1669685Y1250984D03*
Y1254724D03*
X1673425Y1247243D03*
Y1243503D03*
Y1239763D03*
X1680904Y1082677D03*
X1680905Y1086417D03*
X1688385Y1082677D03*
X1692126Y1086417D03*
X1688386D03*
X1677165Y1097637D03*
X1684645D03*
X1692126Y1093897D03*
Y1097637D03*
Y1105117D03*
X1688385Y1108858D03*
X1692126Y1112598D03*
Y1120078D03*
Y1127558D03*
Y1135039D03*
X1684645Y1250984D03*
Y1254724D03*
X1692126Y1250984D03*
X1688385Y1247243D03*
Y1243503D03*
Y1239763D03*
X1692126Y1254724D03*
X1677165Y1250984D03*
Y1254724D03*
X1680905Y1247243D03*
Y1243503D03*
X1695866Y1086417D03*
Y1093897D03*
Y1097637D03*
Y1105117D03*
Y1112598D03*
Y1120078D03*
X1697736Y1140649D03*
X1693996D03*
X1695866Y1127558D03*
Y1135039D03*
X1697736Y1148129D03*
X1693996D03*
X1697736Y1155610D03*
X1693996D03*
X1697736Y1170570D03*
Y1178051D03*
Y1185531D03*
G54D36*
X145078Y1250984D03*
X148818Y1243503D03*
Y1250984D03*
X145078Y1243503D03*
X161909Y1125688D03*
X158169Y1151869D03*
X154429D03*
Y1166830D03*
X160039Y1194881D03*
Y1202362D03*
Y1209842D03*
Y1217322D03*
X156299Y1250984D03*
X160039Y1247243D03*
X152559D03*
X156299Y1239763D03*
X163779Y1250984D03*
X156299Y1254724D03*
X163779D03*
X178740Y1075196D03*
X171259D03*
X178740Y1078936D03*
X174999Y1086417D03*
Y1082677D03*
X171259Y1078936D03*
X182480Y1086417D03*
Y1082677D03*
X171259Y1097637D03*
X173129Y1129428D03*
X169389D03*
X180610Y1170570D03*
X174999Y1209842D03*
X167519Y1221062D03*
X182480Y1239763D03*
Y1247243D03*
X178740Y1250984D03*
Y1239763D03*
X174999Y1243503D03*
X178740Y1254724D03*
X171259D03*
X167519Y1247243D03*
X186220Y1075196D03*
X193700D03*
X189960Y1086417D03*
Y1082677D03*
X193700Y1078936D03*
X186220D03*
X197440Y1086417D03*
Y1082677D03*
X188090Y1178051D03*
Y1193011D03*
X197440Y1247243D03*
X193700Y1254724D03*
X186220D03*
X189960Y1239763D03*
X186220Y1250984D03*
X189960Y1247243D03*
X193700Y1250984D03*
X201181Y1075196D03*
X208661D03*
Y1078936D03*
X212401Y1086417D03*
Y1082677D03*
X204921Y1086417D03*
Y1082677D03*
X201181Y1078936D03*
X208661Y1250984D03*
X201181Y1239763D03*
X212401D03*
Y1247243D03*
X201181Y1254724D03*
X204921Y1239763D03*
X201181Y1250984D03*
X204921Y1247243D03*
X208661Y1254724D03*
X213969Y1445013D03*
Y1456013D03*
X223622Y1075196D03*
X231102D03*
X216141D03*
X227362Y1086417D03*
Y1082677D03*
X219881Y1086417D03*
Y1082677D03*
X223622Y1078936D03*
X231102D03*
X216141D03*
X223622Y1254724D03*
X231102D03*
X227362Y1247243D03*
X219881Y1239763D03*
X223622Y1250984D03*
X219881Y1247243D03*
X231102Y1250984D03*
X227362Y1239763D03*
X216141Y1250984D03*
Y1254724D03*
X227249Y1445013D03*
Y1456013D03*
X246062Y1221062D03*
X234842Y1239763D03*
Y1243503D03*
X242322Y1239763D03*
X257283Y1101377D03*
X249803Y1221062D03*
X253543D03*
X261023D03*
X257283D03*
X249803Y1243503D03*
X257283D03*
X272244Y1101377D03*
X279724D03*
X264763D03*
X277854Y1121948D03*
Y1129429D03*
X264763Y1221062D03*
X279724Y1239763D03*
X275984D03*
X264763D03*
X287204Y1086417D03*
X283464Y1097637D03*
X294684Y1101377D03*
X289074Y1144389D03*
X294685Y1239763D03*
X302164Y1090157D03*
X305904D03*
X309644D03*
X302165Y1101377D03*
X309645D03*
Y1123818D03*
X309644Y1108858D03*
X309645Y1116338D03*
Y1131299D03*
X307775Y1140649D03*
X298425Y1135039D03*
Y1127558D03*
X300295Y1151869D03*
Y1144389D03*
X307775Y1148129D03*
Y1155610D03*
Y1159350D03*
X305905Y1239763D03*
X317125Y1090157D03*
X317126Y1105117D03*
X317125Y1101377D03*
X318996Y1136909D03*
X317125Y1131299D03*
X318996Y1144389D03*
Y1151869D03*
X322736Y1166830D03*
X318996Y1159350D03*
Y1166830D03*
X326476D03*
X318996Y1189271D03*
Y1181791D03*
Y1174310D03*
X317125Y1198621D03*
Y1206102D03*
Y1213582D03*
X320866Y1243503D03*
X313385Y1239763D03*
X602165Y1243503D03*
Y1250984D03*
X618996Y1125688D03*
Y1133169D03*
X615256Y1151869D03*
X611516D03*
Y1166830D03*
X617126Y1202362D03*
Y1194881D03*
Y1209842D03*
Y1217322D03*
X613386Y1239763D03*
X620866Y1254724D03*
Y1250984D03*
X617126Y1247243D03*
X609646D03*
X613386Y1254724D03*
Y1250984D03*
X605905Y1243503D03*
Y1254724D03*
Y1250984D03*
X626476Y1073326D03*
X635827Y1075196D03*
X628346D03*
X626476Y1077066D03*
X628346Y1078936D03*
X635827D03*
X632086Y1082677D03*
Y1086417D03*
X626476Y1099507D03*
X628346Y1097637D03*
X630216Y1129428D03*
X626476D03*
X630216Y1136909D03*
X626476D03*
X632086Y1209842D03*
X624606Y1221062D03*
X632086Y1243503D03*
X635827Y1239763D03*
Y1254724D03*
Y1250984D03*
X628346Y1254724D03*
X624606Y1247243D03*
X643307Y1075196D03*
X650787D03*
Y1078936D03*
X647047Y1082677D03*
Y1086417D03*
X643307Y1078936D03*
X639567Y1086417D03*
Y1082677D03*
X637697Y1170570D03*
X645177Y1178051D03*
Y1193011D03*
X639567Y1239763D03*
Y1247243D03*
X647047Y1239763D03*
X650787Y1254724D03*
Y1250984D03*
X647047Y1247243D03*
X643307Y1254724D03*
Y1250984D03*
X658268Y1075196D03*
X665748D03*
X669488Y1086417D03*
X665748Y1078936D03*
X669488Y1082677D03*
X654527D03*
Y1086417D03*
X662008Y1082677D03*
Y1086417D03*
X658268Y1078936D03*
X654527Y1247243D03*
X662008Y1239763D03*
X658268D03*
X669488D03*
X665748Y1250984D03*
Y1254724D03*
X669488Y1247243D03*
X662008D03*
X658268Y1254724D03*
Y1250984D03*
X680709Y1075196D03*
X673228D03*
X684449Y1082677D03*
Y1086417D03*
X673228Y1078936D03*
X680709D03*
X676968Y1082677D03*
Y1086417D03*
Y1239763D03*
X680709Y1254724D03*
Y1250984D03*
X676968Y1247243D03*
X673228Y1254724D03*
Y1250984D03*
X684449Y1247243D03*
Y1239763D03*
X688189Y1075196D03*
Y1078936D03*
Y1254724D03*
Y1250984D03*
X699409Y1239763D03*
X691929D03*
Y1243503D03*
X714370Y1101377D03*
Y1243503D03*
X706890D03*
X729331Y1101377D03*
X721850D03*
X734941Y1121948D03*
Y1129429D03*
X733071Y1239763D03*
X721850D03*
X744291Y1086417D03*
X740551Y1097637D03*
X736811Y1101377D03*
X746161Y1144389D03*
X736811Y1239763D03*
X766731Y1090157D03*
X759251D03*
X762991D03*
X751771Y1101377D03*
X759252D03*
X766732D03*
X766731Y1108858D03*
X766732Y1116338D03*
Y1123818D03*
X764862Y1140649D03*
X766732Y1131299D03*
X755512Y1127558D03*
Y1135039D03*
X764862Y1155610D03*
Y1148129D03*
X757382Y1144389D03*
Y1151869D03*
X764862Y1159350D03*
X762992Y1239763D03*
X751772D03*
X774212Y1090157D03*
Y1101377D03*
X774213Y1105117D03*
X774212Y1131299D03*
X776083Y1151869D03*
Y1144389D03*
X783563Y1166830D03*
X776083D03*
Y1159350D03*
X779823Y1166830D03*
X776083Y1174310D03*
Y1181791D03*
Y1196751D03*
X774212Y1198621D03*
Y1213582D03*
Y1206102D03*
X777953Y1243503D03*
X770472Y1239763D03*
X1059251Y1243503D03*
Y1250984D03*
X1072342Y1151869D03*
X1068602D03*
Y1166830D03*
X1074212Y1194881D03*
Y1202362D03*
Y1217322D03*
Y1209842D03*
X1070472Y1250984D03*
Y1254724D03*
X1066732Y1247243D03*
X1074212D03*
X1070472Y1239763D03*
X1062991Y1250984D03*
Y1254724D03*
Y1243503D03*
X1083562Y1073326D03*
Y1077066D03*
X1089172Y1082677D03*
Y1086417D03*
X1083562Y1099507D03*
Y1136909D03*
X1087302D03*
X1083562Y1129428D03*
X1087302D03*
X1076082Y1133169D03*
Y1125688D03*
X1089172Y1209842D03*
X1081692Y1221062D03*
X1077952Y1250984D03*
Y1254724D03*
X1081692Y1247243D03*
X1085432Y1254724D03*
X1089172Y1243503D03*
X1092913Y1075196D03*
X1107873D03*
X1100393D03*
X1092913Y1078936D03*
X1104133Y1086417D03*
Y1082677D03*
X1107873Y1078936D03*
X1100393D03*
X1096653Y1082677D03*
Y1086417D03*
X1094783Y1170570D03*
X1102263Y1178051D03*
Y1193011D03*
X1092913Y1250984D03*
Y1254724D03*
Y1239763D03*
X1100393Y1250984D03*
Y1254724D03*
X1104133Y1247243D03*
X1107873Y1250984D03*
Y1254724D03*
X1104133Y1239763D03*
X1096653Y1247243D03*
Y1239763D03*
X1115354Y1075196D03*
X1122834D03*
X1115354Y1078936D03*
X1119094Y1082677D03*
Y1086417D03*
X1122834Y1078936D03*
X1111613Y1082677D03*
Y1086417D03*
X1115354Y1250984D03*
Y1254724D03*
X1119094Y1247243D03*
X1122834Y1254724D03*
Y1250984D03*
X1115354Y1239763D03*
X1119094D03*
X1111613Y1247243D03*
X1130314Y1075196D03*
X1137795D03*
X1126574Y1086417D03*
Y1082677D03*
X1130314Y1078936D03*
X1134054Y1082677D03*
Y1086417D03*
X1137795Y1078936D03*
X1126574Y1247243D03*
Y1239763D03*
X1130314Y1250984D03*
Y1254724D03*
X1134054Y1247243D03*
X1137795Y1250984D03*
Y1254724D03*
X1134054Y1239763D03*
X1145275Y1075196D03*
X1141535Y1082677D03*
Y1086417D03*
X1145275Y1078936D03*
X1141535Y1239763D03*
Y1247243D03*
X1149015Y1243503D03*
Y1239763D03*
X1156495D03*
X1145275Y1250984D03*
Y1254724D03*
X1171456Y1101377D03*
X1163976Y1243503D03*
X1171456D03*
X1178936Y1101377D03*
X1186417D03*
X1178936Y1239763D03*
X1201377Y1086417D03*
X1197637Y1097637D03*
X1193897Y1101377D03*
X1192027Y1121948D03*
Y1129429D03*
X1203247Y1144389D03*
X1190157Y1239763D03*
X1193897D03*
X1216337Y1090157D03*
X1220077D03*
X1216338Y1101377D03*
X1208857D03*
X1221948Y1140649D03*
X1212598Y1127558D03*
Y1135039D03*
X1221948Y1155610D03*
X1214468Y1151869D03*
Y1144389D03*
X1221948Y1148129D03*
Y1159350D03*
X1220078Y1239763D03*
X1208858D03*
X1223817Y1090157D03*
X1231298D03*
X1223818Y1101377D03*
X1231298D03*
X1231299Y1105117D03*
X1223817Y1108858D03*
X1223818Y1116338D03*
Y1123818D03*
X1233169Y1136909D03*
X1223818Y1131299D03*
X1231298D03*
X1233169Y1144389D03*
Y1151869D03*
X1236909Y1166830D03*
X1233169Y1159350D03*
Y1166830D03*
Y1189271D03*
Y1181791D03*
Y1174310D03*
Y1196751D03*
X1231298Y1198621D03*
Y1206102D03*
Y1213582D03*
X1235039Y1243503D03*
X1227558Y1239763D03*
X1243149Y1136909D03*
X1240649Y1166830D03*
X1511968Y1170570D03*
Y1178050D03*
X1529429Y1151869D03*
X1525689D03*
Y1166830D03*
X1516338Y1243503D03*
Y1250984D03*
X1527559D03*
Y1254724D03*
X1523819Y1247243D03*
X1527559Y1239763D03*
X1520078Y1250984D03*
Y1254724D03*
Y1243503D03*
X1540649Y1073326D03*
Y1077066D03*
X1546259Y1082677D03*
Y1086417D03*
X1540649Y1099507D03*
X1533169Y1125688D03*
X1544389Y1129428D03*
X1540649D03*
X1544389Y1136909D03*
X1533169Y1133169D03*
X1540649Y1136909D03*
X1531299Y1194881D03*
Y1202362D03*
Y1217322D03*
Y1209842D03*
X1546259D03*
X1538779Y1221062D03*
X1531299Y1247243D03*
X1535039Y1250984D03*
Y1254724D03*
X1538779Y1247243D03*
X1542519Y1254724D03*
X1546259Y1243503D03*
X1557480Y1075196D03*
X1550000D03*
X1561220Y1086417D03*
Y1082677D03*
X1557480Y1078936D03*
X1553740Y1082677D03*
Y1086417D03*
X1550000Y1078936D03*
X1551870Y1170570D03*
X1559350Y1178051D03*
Y1193011D03*
X1550000Y1250984D03*
Y1254724D03*
Y1239763D03*
X1557480Y1250984D03*
Y1254724D03*
X1561220Y1247243D03*
Y1239763D03*
X1553740Y1247243D03*
Y1239763D03*
X1572441Y1075196D03*
X1564960D03*
Y1078936D03*
X1572441D03*
X1576181Y1082677D03*
Y1086417D03*
X1568700Y1082677D03*
Y1086417D03*
X1564960Y1250984D03*
Y1254724D03*
X1572441Y1250984D03*
Y1254724D03*
X1576181Y1247243D03*
X1572441Y1239763D03*
X1576181D03*
X1568700Y1247243D03*
X1579921Y1075196D03*
X1587401D03*
X1594882D03*
X1583661Y1086417D03*
Y1082677D03*
X1579921Y1078936D03*
X1587401D03*
X1591141Y1082677D03*
Y1086417D03*
X1594882Y1078936D03*
X1583661Y1247243D03*
X1579921Y1254724D03*
Y1250984D03*
X1583661Y1239763D03*
X1587401Y1250984D03*
Y1254724D03*
X1591141Y1247243D03*
X1594882Y1250984D03*
Y1254724D03*
X1591141Y1239763D03*
X1602362Y1075196D03*
X1598622Y1082677D03*
Y1086417D03*
X1602362Y1078936D03*
X1598622Y1239763D03*
Y1247243D03*
X1606102Y1243503D03*
Y1239763D03*
X1602362Y1250984D03*
Y1254724D03*
X1613582Y1239763D03*
X1621063Y1243503D03*
X1636023Y1101377D03*
X1643504D03*
X1628543D03*
Y1243503D03*
X1636023Y1239763D03*
X1658464Y1086417D03*
X1654724Y1097637D03*
X1650984Y1101377D03*
X1649114Y1121948D03*
Y1129429D03*
X1660334Y1144389D03*
X1647244Y1239763D03*
X1650984D03*
X1673424Y1090157D03*
X1673425Y1101377D03*
X1665944D03*
X1671555Y1136909D03*
X1669685Y1127558D03*
Y1135039D03*
X1671555Y1151869D03*
Y1144389D03*
X1665945Y1239763D03*
X1677164Y1090157D03*
X1680904D03*
X1688385D03*
X1680905Y1101377D03*
X1688385D03*
X1688386Y1105117D03*
X1680904Y1108858D03*
X1680905Y1116338D03*
Y1123818D03*
X1690256Y1136909D03*
X1679035Y1140649D03*
X1680905Y1131299D03*
X1688385D03*
X1690256Y1144389D03*
X1679035Y1148129D03*
Y1155610D03*
X1690256Y1151869D03*
Y1159350D03*
X1679035D03*
X1690256Y1166830D03*
Y1174310D03*
Y1189271D03*
Y1181791D03*
X1688385Y1198621D03*
Y1213582D03*
Y1206102D03*
X1692126Y1243503D03*
X1684645Y1239763D03*
X1677165D03*
X1700236Y1136909D03*
X1693996Y1166830D03*
X1697736D03*
G54D46*
X718503Y-38525D03*
X718500Y-33320D03*
Y-30420D03*
X718488Y-36010D03*
X721756Y-38539D03*
X724781Y-37219D03*
X721741Y-36024D03*
X838503Y-77705D03*
X841756Y-77719D03*
X838500Y-72500D03*
X838488Y-75190D03*
X841741Y-75204D03*
X844781Y-76399D03*
X838500Y-69600D03*
X1005256Y-48539D03*
X1002003D03*
X1005241Y-46024D03*
X1001988D03*
X1008281Y-47219D03*
X1002000Y-40834D03*
X1005256Y-38239D03*
X1002003Y-38225D03*
X1002000Y-43334D03*
X1005241Y-35724D03*
X1002000Y-32720D03*
X1001988Y-35710D03*
X1002000Y-30120D03*
X1008281Y-36919D03*
X1075256Y-77419D03*
X1072003Y-77405D03*
X1071988Y-85290D03*
X1075241D03*
X1072000Y-82600D03*
X1072003Y-87805D03*
X1075256D03*
X1072000Y-80100D03*
Y-72000D03*
Y-69400D03*
X1075241Y-74904D03*
X1071988Y-74890D03*
X1078281Y-86399D03*
Y-76099D03*
X1291756Y-48669D03*
X1288503D03*
X1291741Y-46154D03*
X1288488D03*
X1294781Y-47349D03*
X1288500Y-40964D03*
X1291756Y-38369D03*
X1288503Y-38355D03*
X1288500Y-43464D03*
X1291741Y-35854D03*
X1288500Y-32950D03*
X1288488Y-35840D03*
X1288500Y-30350D03*
X1294781Y-37049D03*
X1328500Y-80100D03*
X1331756Y-77419D03*
X1328503Y-77405D03*
X1331756Y-87805D03*
X1328503D03*
X1328500Y-82600D03*
X1331741Y-85290D03*
X1328488D03*
X1334781Y-86499D03*
X1331741Y-74904D03*
X1328500Y-72000D03*
X1328488Y-74890D03*
X1328500Y-69400D03*
X1334781Y-76099D03*
X1576256Y-48799D03*
X1573003D03*
X1576241Y-46284D03*
X1572988D03*
X1579281Y-47479D03*
X1573000Y-41094D03*
X1576256Y-38499D03*
X1573003Y-38485D03*
X1573000Y-43594D03*
X1576241Y-35984D03*
X1573000Y-33080D03*
X1572988Y-35970D03*
X1573000Y-30480D03*
X1579281Y-37179D03*
X1583000Y-80014D03*
X1586256Y-77419D03*
X1583003Y-77405D03*
X1586256Y-87719D03*
X1583003D03*
X1583000Y-82514D03*
X1586241Y-85204D03*
X1582988D03*
X1589281Y-86399D03*
X1586241Y-74904D03*
X1583000Y-72000D03*
X1582988Y-74890D03*
X1583000Y-69400D03*
X1589281Y-76099D03*
G54D26*
X56348Y1727941D03*
Y1737941D03*
X56248Y1750941D03*
X56348Y1773941D03*
X56248Y1760941D03*
X56348Y1783941D03*
X56248Y1806941D03*
Y1796941D03*
X308448Y1737941D03*
Y1727941D03*
Y1750941D03*
Y1760941D03*
Y1773941D03*
Y1783941D03*
X308348Y1796941D03*
Y1806941D03*
X343286Y1738583D03*
Y1728583D03*
X343112Y1751624D03*
X343212Y1774624D03*
X343112Y1761624D03*
X343212Y1784624D03*
Y1797624D03*
Y1807624D03*
X595386Y1728583D03*
Y1738583D03*
X595312Y1751624D03*
Y1774624D03*
Y1761624D03*
Y1784624D03*
Y1807624D03*
Y1797624D03*
X630083Y1738286D03*
Y1728286D03*
X629861Y1751765D03*
X629711Y1775438D03*
X629861Y1761765D03*
X629711Y1785438D03*
X629475Y1798845D03*
Y1808845D03*
X882183Y1728286D03*
Y1738286D03*
X881911Y1751765D03*
X881761Y1775438D03*
X881911Y1761765D03*
X881761Y1785438D03*
X881525Y1798845D03*
Y1808845D03*
X917279Y1738990D03*
Y1728990D03*
X917163Y1752566D03*
Y1762566D03*
X917073Y1786014D03*
Y1776014D03*
X917166Y1800435D03*
Y1810435D03*
X1169329Y1728990D03*
Y1738990D03*
X1169263Y1752566D03*
Y1762566D03*
X1169123Y1776014D03*
Y1786014D03*
X1169216Y1800435D03*
Y1810435D03*
G54D42*
X318448Y1727941D03*
Y1737941D03*
Y1773941D03*
Y1783941D03*
X605312Y1751624D03*
Y1761624D03*
Y1807624D03*
Y1797624D03*
X891911Y1751765D03*
Y1761765D03*
X891525Y1808845D03*
Y1798845D03*
X1179263Y1752566D03*
Y1762566D03*
X1179216Y1800435D03*
Y1810435D03*
G54D34*
X146948Y1136909D03*
X143208D03*
X145078Y1198621D03*
Y1191141D03*
X148818D03*
Y1198621D03*
X145078Y1221062D03*
X148818D03*
Y1213582D03*
X145078D03*
Y1206102D03*
X148818D03*
X145078Y1228543D03*
X148818D03*
Y1247243D03*
X145078D03*
X148818Y1239763D03*
X145078D03*
X150689Y1133169D03*
X165649D03*
X161909D03*
X154429D03*
X156299Y1187401D03*
X163779D03*
X152559D03*
X156299Y1202362D03*
Y1194881D03*
X152559Y1202362D03*
Y1194881D03*
X163779D03*
Y1202362D03*
X156299Y1217322D03*
Y1209842D03*
X152559D03*
X163779D03*
Y1217322D03*
X152559D03*
X160039Y1236023D03*
X163779Y1224803D03*
X156299D03*
Y1228543D03*
X163779D03*
X160039Y1232283D03*
X152559Y1236023D03*
Y1232283D03*
Y1250984D03*
Y1254724D03*
X160039D03*
X156299Y1243503D03*
Y1247243D03*
X163779Y1243503D03*
X160039Y1250984D03*
X163779Y1247243D03*
X174999Y1075196D03*
X182480D03*
X174999Y1078936D03*
X182480D03*
X178740Y1082677D03*
Y1086417D03*
X174999Y1093897D03*
X182480D03*
Y1097637D03*
X174999D03*
X178740Y1101376D03*
Y1105117D03*
X173129Y1136909D03*
X169389D03*
X167519Y1187401D03*
X174999Y1198621D03*
Y1191141D03*
X167519Y1194881D03*
X171259Y1198621D03*
Y1191141D03*
X167519Y1202362D03*
Y1209842D03*
X171259Y1213582D03*
Y1206102D03*
X174999D03*
X167519Y1217322D03*
X174999Y1213582D03*
X178740Y1228543D03*
X171259Y1224803D03*
X182480Y1236023D03*
Y1232283D03*
X174999D03*
X171259Y1228543D03*
X178740Y1224803D03*
X174999Y1236023D03*
X167519Y1232283D03*
Y1236023D03*
Y1254724D03*
Y1250984D03*
X178740Y1247243D03*
X182480Y1254724D03*
Y1250984D03*
X171259Y1247243D03*
X174999Y1250984D03*
X171259Y1243503D03*
X174999Y1254724D03*
X178740Y1243503D03*
X189960Y1075196D03*
X197440D03*
X186220Y1082677D03*
Y1086417D03*
X189960Y1078936D03*
X193700Y1086417D03*
Y1082677D03*
X197440Y1078936D03*
X193700Y1105117D03*
X197440Y1093897D03*
X189960Y1097637D03*
X186220Y1105117D03*
X197440Y1097637D03*
X193700Y1101376D03*
X186220D03*
X189960Y1093897D03*
X197440Y1236023D03*
X186220Y1224803D03*
X193700Y1228543D03*
X197440Y1232283D03*
X189960Y1236023D03*
X186220Y1228543D03*
X193700Y1224803D03*
X189960Y1232283D03*
X197440Y1254724D03*
Y1250984D03*
X193700Y1247243D03*
Y1243503D03*
X189960Y1254724D03*
Y1250984D03*
X186220Y1247243D03*
Y1243503D03*
X204921Y1075196D03*
X212401D03*
Y1078936D03*
X208661Y1082677D03*
X201181D03*
Y1086417D03*
X208661D03*
X204921Y1078936D03*
Y1097637D03*
X208661Y1101376D03*
X212401Y1097637D03*
X208661Y1105117D03*
X212401Y1093897D03*
X201181Y1101376D03*
X204921Y1093897D03*
X201181Y1105117D03*
X204921Y1232283D03*
X201181Y1224803D03*
X212401Y1232283D03*
X208661Y1228543D03*
X212401Y1236023D03*
X208661Y1224803D03*
X201181Y1228543D03*
X204921Y1236023D03*
X208661Y1243503D03*
X204921Y1250984D03*
X208661Y1247243D03*
X212401Y1254724D03*
X201181Y1243503D03*
X212401Y1250984D03*
X201181Y1247243D03*
X204921Y1254724D03*
X227362Y1075196D03*
X219881D03*
Y1078936D03*
X216141Y1086417D03*
X231102Y1082677D03*
Y1086417D03*
X223622Y1082677D03*
X227362Y1078936D03*
X216141Y1082677D03*
X223622Y1086417D03*
X216141Y1101376D03*
X231102D03*
X227362Y1093897D03*
X219881Y1097637D03*
X223621Y1101376D03*
Y1105117D03*
X216141D03*
X219881Y1093897D03*
X227362Y1097637D03*
X231102Y1105117D03*
Y1228543D03*
Y1224803D03*
X219881Y1232283D03*
Y1236023D03*
X216141Y1224803D03*
X223622D03*
X227362Y1232283D03*
X223622Y1228543D03*
X216141D03*
X227362Y1236023D03*
X231102Y1243503D03*
Y1247243D03*
X223622Y1243503D03*
X216141Y1247243D03*
X223622D03*
X216141Y1243503D03*
X219881Y1250984D03*
Y1254724D03*
X227362D03*
Y1250984D03*
X234841Y1075195D03*
X242321Y1075196D03*
Y1078936D03*
X246061Y1082677D03*
X238581Y1082676D03*
X234841Y1078935D03*
X246061Y1086417D03*
X238581Y1086416D03*
X234841Y1093897D03*
X246062Y1105117D03*
X242321Y1097637D03*
X234841D03*
X238582Y1101376D03*
X246062D03*
X238582Y1105117D03*
X242321Y1093897D03*
X238582Y1224803D03*
Y1228543D03*
X242322Y1236023D03*
Y1232283D03*
X246062Y1228543D03*
X234842Y1232283D03*
X246062Y1224803D03*
X234842Y1236023D03*
X238582Y1247243D03*
X246062Y1243503D03*
X242322Y1250984D03*
X234842D03*
X246062Y1247243D03*
X234842Y1254724D03*
X238582Y1243503D03*
X242322Y1254724D03*
X249802Y1075196D03*
X257282D03*
X249802Y1078936D03*
X261022Y1086417D03*
X253542Y1082676D03*
X257282Y1078936D03*
X253542Y1086416D03*
X261022Y1082677D03*
X249802Y1097637D03*
X257282D03*
X249802Y1093897D03*
X253543Y1105117D03*
Y1101376D03*
X257282Y1093897D03*
X261023Y1105117D03*
Y1101376D03*
Y1224803D03*
X253543Y1228543D03*
X249803Y1232283D03*
X257283D03*
Y1236023D03*
X261023Y1228543D03*
X253543Y1224803D03*
X249803Y1236023D03*
X261023Y1243503D03*
X249803Y1250984D03*
X261023Y1247243D03*
X257283Y1250984D03*
X253543Y1247243D03*
X257283Y1254724D03*
X249803D03*
X253543Y1243503D03*
X279723Y1075196D03*
X264762D03*
X272243D03*
X275982Y1082677D03*
Y1086417D03*
X268502Y1082676D03*
X272243Y1078936D03*
X268502Y1086416D03*
X279723Y1078936D03*
X264762D03*
Y1097637D03*
X268503Y1105117D03*
X272243Y1097637D03*
X275984Y1105117D03*
X279723Y1093897D03*
X272243D03*
X279723Y1097637D03*
X268503Y1101376D03*
X275984D03*
X264762Y1093897D03*
X264763Y1232283D03*
X268503Y1224803D03*
X275984D03*
X272244Y1236023D03*
X279724Y1232283D03*
Y1236023D03*
X275984Y1228543D03*
X272244Y1232283D03*
X268503Y1228543D03*
X264763Y1236023D03*
Y1254724D03*
Y1250984D03*
X268503Y1243503D03*
Y1247243D03*
X272244Y1254724D03*
Y1250984D03*
X275984Y1243503D03*
Y1247243D03*
X279724Y1250984D03*
Y1254724D03*
X287203Y1075196D03*
X294684D03*
X290943Y1086417D03*
X287203Y1078936D03*
X290943Y1082677D03*
X283463Y1082676D03*
Y1086416D03*
X294684Y1078936D03*
X283464Y1101376D03*
X294684Y1093897D03*
X287203D03*
X294684Y1097637D03*
X283464Y1105117D03*
X290944Y1101376D03*
Y1105117D03*
X287203Y1097637D03*
X294684Y1123818D03*
Y1116338D03*
Y1131299D03*
X294685Y1198621D03*
Y1213582D03*
Y1206102D03*
X287204Y1232283D03*
X283464Y1224803D03*
Y1228543D03*
X287204Y1236023D03*
X294685D03*
X290944Y1224803D03*
X294685Y1232283D03*
X290944Y1228543D03*
X287204Y1254724D03*
X283464Y1243503D03*
Y1247243D03*
X287204Y1250984D03*
X294685Y1254724D03*
Y1250984D03*
X290944Y1247243D03*
Y1243503D03*
X302164Y1075196D03*
X309644D03*
X305904Y1082677D03*
X302164Y1078936D03*
X305904Y1086417D03*
X309644Y1078936D03*
X298424Y1086416D03*
Y1082676D03*
X298425Y1105117D03*
Y1101376D03*
X309644Y1097637D03*
X302164D03*
X305905Y1105117D03*
X309644Y1093897D03*
X305905Y1101376D03*
X302164Y1093897D03*
X302165Y1120078D03*
X305905Y1112598D03*
X298425Y1116338D03*
X305905Y1120078D03*
X302165Y1112598D03*
X298425Y1123818D03*
X305905Y1127559D03*
Y1135039D03*
X302165D03*
Y1127559D03*
X298425Y1131299D03*
Y1198621D03*
X305905Y1202362D03*
X302165D03*
X298425Y1213582D03*
X305905Y1209842D03*
Y1217322D03*
X302165Y1209842D03*
X298425Y1206102D03*
X302165Y1217322D03*
Y1232283D03*
X309645D03*
X298425Y1224803D03*
Y1228543D03*
X309645Y1236023D03*
X305905Y1228543D03*
Y1224803D03*
X302165Y1236023D03*
X309645Y1254724D03*
X298425Y1247243D03*
X309645Y1250984D03*
X298425Y1243503D03*
X305905D03*
Y1247243D03*
X302165Y1254724D03*
Y1250984D03*
X317124Y1075196D03*
X320866Y1090157D03*
X324606D03*
Y1082676D03*
X317124Y1078936D03*
X313384Y1082677D03*
Y1086417D03*
X320866Y1082676D03*
X313385Y1101377D03*
X317125Y1093897D03*
X320866Y1101377D03*
X313385Y1105117D03*
X324606Y1101377D03*
X317125Y1097637D03*
X313385Y1120078D03*
X324606Y1123818D03*
Y1108858D03*
X320866D03*
X317125Y1112598D03*
X324606Y1116338D03*
X313385Y1112598D03*
X317125Y1120078D03*
X320866Y1116338D03*
Y1123818D03*
X313385Y1127558D03*
X317125Y1135039D03*
X313385D03*
X324606Y1131299D03*
X317125Y1127558D03*
X320866Y1131299D03*
Y1198621D03*
X313385Y1202362D03*
X324606Y1198621D03*
X317125Y1202362D03*
Y1217322D03*
Y1209842D03*
X324606Y1213582D03*
X320866Y1221062D03*
X313385Y1209842D03*
X320866Y1206102D03*
Y1213582D03*
X324606Y1221062D03*
Y1206102D03*
X313385Y1217322D03*
X317125Y1236023D03*
X313385Y1224803D03*
X324606Y1228543D03*
X317125Y1232283D03*
X313385Y1228543D03*
X320866D03*
X317125Y1254724D03*
X324606Y1239763D03*
X313385Y1247243D03*
X320866D03*
X317125Y1250984D03*
X320866Y1239763D03*
X313385Y1243503D03*
X324606Y1247243D03*
X602165Y1191141D03*
Y1198621D03*
Y1221062D03*
Y1206102D03*
Y1213582D03*
Y1228543D03*
Y1247243D03*
Y1239763D03*
X613386Y1187401D03*
X609646D03*
X620866D03*
X605905Y1191141D03*
X613386Y1194881D03*
X605905Y1198621D03*
X609646Y1194881D03*
Y1202362D03*
X613386D03*
X620866D03*
Y1194881D03*
X613386Y1217322D03*
X605905Y1221062D03*
X609646Y1217322D03*
Y1209842D03*
X605905Y1206102D03*
Y1213582D03*
X620866Y1209842D03*
X613386D03*
X620866Y1217322D03*
X605905Y1228543D03*
X620866D03*
Y1224803D03*
X609646Y1232283D03*
X617126Y1236023D03*
X613386Y1228543D03*
X617126Y1232283D03*
X609646Y1236023D03*
X613386Y1224803D03*
X605905Y1247243D03*
X617126Y1250984D03*
X620866Y1243503D03*
Y1247243D03*
X609646Y1254724D03*
X613386Y1247243D03*
X617126Y1254724D03*
X613386Y1243503D03*
X609646Y1250984D03*
X605905Y1239763D03*
X632086Y1075196D03*
Y1078936D03*
X635827Y1086417D03*
Y1082677D03*
X632086Y1097637D03*
X635827Y1105117D03*
X632086Y1093897D03*
X635827Y1101376D03*
X624606Y1187401D03*
X628346Y1191141D03*
X624606Y1194881D03*
X632086Y1191141D03*
X628346Y1198621D03*
X624606Y1202362D03*
X632086Y1198621D03*
X628346Y1206102D03*
X632086D03*
X624606Y1217322D03*
X628346Y1213582D03*
X632086D03*
X624606Y1209842D03*
X628346Y1224803D03*
Y1228543D03*
X635827D03*
X632086Y1232283D03*
Y1236023D03*
X624606Y1232283D03*
Y1236023D03*
X635827Y1224803D03*
X624606Y1254724D03*
Y1250984D03*
X632086Y1254724D03*
X635827Y1243503D03*
X632086Y1250984D03*
X635827Y1247243D03*
X628346Y1243503D03*
Y1247243D03*
X639567Y1075196D03*
X647047D03*
X643307Y1086417D03*
Y1082677D03*
X647047Y1078936D03*
X639567D03*
X650787Y1082677D03*
Y1086417D03*
Y1105117D03*
X647047Y1093897D03*
X639567Y1097637D03*
X643307Y1105117D03*
X647047Y1097637D03*
X639567Y1093897D03*
X643307Y1101376D03*
X650787D03*
X639567Y1236023D03*
X647047D03*
X639567Y1232283D03*
X643307Y1224803D03*
X647047Y1232283D03*
X643307Y1228543D03*
X650787D03*
Y1224803D03*
X639567Y1250984D03*
Y1254724D03*
X650787Y1247243D03*
Y1243503D03*
X647047Y1254724D03*
Y1250984D03*
X643307Y1247243D03*
Y1243503D03*
X662008Y1075196D03*
X654527D03*
X669488D03*
X662008Y1078936D03*
X665748Y1082677D03*
X658268D03*
X654527Y1078936D03*
X665748Y1086417D03*
X658268D03*
X669488Y1078936D03*
X662008Y1097637D03*
X654527Y1093897D03*
X669488D03*
X665748Y1105117D03*
X654527Y1097637D03*
X662008Y1093897D03*
X669488Y1097637D03*
X665748Y1101376D03*
X658268Y1105117D03*
Y1101376D03*
X669488Y1232283D03*
X654527Y1236023D03*
X662008Y1232283D03*
X665748Y1224803D03*
X662008Y1236023D03*
X658268Y1224803D03*
X665748Y1228543D03*
X658268D03*
X669488Y1236023D03*
X654527Y1232283D03*
X662008Y1254724D03*
X665748Y1247243D03*
X669488Y1250984D03*
X658268Y1247243D03*
X662008Y1250984D03*
X665748Y1243503D03*
X669488Y1254724D03*
X658268Y1243503D03*
X654527Y1254724D03*
Y1250984D03*
X676968Y1075196D03*
X684449D03*
X676968Y1078936D03*
X680709Y1086417D03*
X684449Y1078936D03*
X673228Y1086417D03*
Y1082677D03*
X680709D03*
X673228Y1105117D03*
X684449Y1093897D03*
X676968D03*
X684449Y1097637D03*
X676968D03*
X680708Y1105117D03*
X673228Y1101376D03*
X680708D03*
X676968Y1236023D03*
X684449Y1232283D03*
X673228Y1228543D03*
X680709Y1224803D03*
X684449Y1236023D03*
X676968Y1232283D03*
X673228Y1224803D03*
X680709Y1228543D03*
X673228Y1243503D03*
X680709Y1247243D03*
X673228D03*
X684449Y1254724D03*
Y1250984D03*
X676968Y1254724D03*
Y1250984D03*
X680709Y1243503D03*
X699408Y1075196D03*
X691928Y1075195D03*
X688189Y1086417D03*
Y1082677D03*
X691928Y1078935D03*
X699408Y1078936D03*
X695668Y1086416D03*
Y1082676D03*
X688189Y1105117D03*
X695669Y1101376D03*
X699408Y1097637D03*
X695669Y1105117D03*
X691928Y1093897D03*
Y1097637D03*
X699408Y1093897D03*
X688189Y1101376D03*
Y1228543D03*
X691929Y1236023D03*
X699409Y1232283D03*
X688189Y1224803D03*
X699409Y1236023D03*
X691929Y1232283D03*
X695669Y1228543D03*
Y1224803D03*
X699409Y1254724D03*
X691929Y1250984D03*
X688189Y1247243D03*
Y1243503D03*
X691929Y1254724D03*
X695669Y1247243D03*
X699409Y1250984D03*
X695669Y1243503D03*
X706889Y1075196D03*
X714369D03*
X706889Y1078936D03*
X718109Y1086417D03*
X714369Y1078936D03*
X703148Y1082677D03*
X710629Y1086416D03*
X703148Y1086417D03*
X718109Y1082677D03*
X710629Y1082676D03*
X714369Y1097637D03*
X706889Y1093897D03*
X703149Y1105117D03*
X718110D03*
Y1101376D03*
X710630Y1105117D03*
X714369Y1093897D03*
X706889Y1097637D03*
X703149Y1101376D03*
X710630D03*
X706890Y1236023D03*
X718110Y1228543D03*
X714370Y1236023D03*
X710630Y1228543D03*
X703149D03*
X714370Y1232283D03*
X703149Y1224803D03*
X718110D03*
X710630D03*
X706890Y1232283D03*
X718110Y1243503D03*
Y1247243D03*
X706890Y1250984D03*
X703149Y1243503D03*
X714370Y1254724D03*
Y1250984D03*
X710630Y1247243D03*
X706890Y1254724D03*
X710630Y1243503D03*
X703149Y1247243D03*
X721849Y1075196D03*
X729330D03*
X725589Y1086416D03*
X733069Y1086417D03*
X721849Y1078936D03*
X729330D03*
X733069Y1082677D03*
X725589Y1082676D03*
X725590Y1101376D03*
X733071Y1105117D03*
X725590D03*
X721849Y1097637D03*
Y1093897D03*
X729330Y1097637D03*
X733071Y1101376D03*
X729330Y1093897D03*
X725590Y1228543D03*
X733071D03*
X721850Y1236023D03*
X733071Y1224803D03*
X721850Y1232283D03*
X725590Y1224803D03*
X729331Y1236023D03*
Y1232283D03*
Y1250984D03*
X733071Y1247243D03*
X721850Y1250984D03*
Y1254724D03*
X725590Y1243503D03*
X729331Y1254724D03*
X733071Y1243503D03*
X725590Y1247243D03*
X736810Y1075196D03*
X744290D03*
Y1078936D03*
X748030Y1086417D03*
X740550Y1086416D03*
Y1082676D03*
X736810Y1078936D03*
X748030Y1082677D03*
X736810Y1097637D03*
X748031Y1105117D03*
X744290Y1093897D03*
X740551Y1105117D03*
X744290Y1097637D03*
X736810Y1093897D03*
X740551Y1101376D03*
X748031D03*
X744291Y1236023D03*
X736811Y1232283D03*
X744291D03*
X736811Y1236023D03*
X740551Y1224803D03*
Y1228543D03*
X748031Y1224803D03*
Y1228543D03*
X744291Y1254724D03*
X740551Y1243503D03*
Y1247243D03*
X744291Y1250984D03*
X736811Y1254724D03*
Y1250984D03*
X748031Y1247243D03*
Y1243503D03*
X751771Y1075196D03*
X766731D03*
X759251D03*
X762991Y1086417D03*
X766731Y1078936D03*
X755511Y1086416D03*
X759251Y1078936D03*
X755511Y1082676D03*
X762991Y1082677D03*
X751771Y1078936D03*
Y1097637D03*
X762992Y1101376D03*
Y1105117D03*
X755512D03*
X759251Y1097637D03*
Y1093897D03*
X766731Y1097637D03*
X755512Y1101376D03*
X766731Y1093897D03*
X751771D03*
X755512Y1123818D03*
X759252Y1112598D03*
X751771Y1123818D03*
X762992Y1112598D03*
X755512Y1116338D03*
X751771D03*
X759252Y1120078D03*
X762992D03*
X751771Y1131299D03*
X762992Y1135039D03*
X755512Y1131299D03*
X762992Y1127559D03*
X759252Y1135039D03*
Y1127559D03*
X762992Y1202362D03*
X755512Y1198621D03*
X759252Y1202362D03*
X751772Y1198621D03*
X762992Y1217322D03*
X751772Y1213582D03*
X762992Y1209842D03*
X755512Y1213582D03*
X751772Y1206102D03*
X759252Y1217322D03*
Y1209842D03*
X755512Y1206102D03*
Y1228543D03*
X751772Y1236023D03*
X762992Y1228543D03*
X751772Y1232283D03*
X766732D03*
Y1236023D03*
X759252Y1232283D03*
X762992Y1224803D03*
X759252Y1236023D03*
X755512Y1224803D03*
X766732Y1250984D03*
X755512Y1243503D03*
X762992D03*
Y1247243D03*
X751772Y1250984D03*
Y1254724D03*
X759252D03*
X766732D03*
X759252Y1250984D03*
X755512Y1247243D03*
X774211Y1075196D03*
X781693Y1090157D03*
X777953D03*
X781693Y1082676D03*
X774211Y1078936D03*
X770471Y1086417D03*
Y1082677D03*
X777953Y1082676D03*
X770472Y1101377D03*
X781693D03*
X777953D03*
X774212Y1097637D03*
X770472Y1105117D03*
X774212Y1093897D03*
Y1112598D03*
X770472D03*
X781693Y1123818D03*
X777953D03*
X781693Y1116338D03*
X777953Y1108858D03*
X770472Y1120078D03*
X781693Y1108858D03*
X777953Y1116338D03*
X774212Y1120078D03*
X770472Y1127558D03*
Y1135039D03*
X781693Y1131299D03*
X774212Y1127558D03*
Y1135039D03*
X777953Y1131299D03*
X781693Y1198621D03*
X774212Y1202362D03*
X770472D03*
X777953Y1198621D03*
Y1206102D03*
X770472Y1209842D03*
X781693Y1213582D03*
X774212Y1209842D03*
X777953Y1221062D03*
X781693D03*
Y1206102D03*
X770472Y1217322D03*
X774212D03*
X777953Y1213582D03*
X770472Y1228543D03*
X781693D03*
X770472Y1224803D03*
X777953Y1228543D03*
X774212Y1232283D03*
Y1236023D03*
X777953Y1239763D03*
X781693D03*
X777953Y1247243D03*
X770472Y1243503D03*
X781693Y1247243D03*
X770472D03*
X774212Y1250984D03*
Y1254724D03*
X1059251Y1198621D03*
Y1191141D03*
Y1221062D03*
Y1206102D03*
Y1213582D03*
Y1228543D03*
Y1247243D03*
Y1239763D03*
X1070472Y1187401D03*
X1066732D03*
X1062991Y1198621D03*
X1066732Y1194881D03*
X1062991Y1191141D03*
X1070472Y1194881D03*
Y1202362D03*
X1066732D03*
X1070472Y1217322D03*
X1066732D03*
X1062991Y1221062D03*
Y1206102D03*
X1070472Y1209842D03*
X1062991Y1213582D03*
X1066732Y1209842D03*
X1070472Y1228543D03*
X1066732Y1236023D03*
Y1232283D03*
X1074212Y1236023D03*
Y1232283D03*
X1070472Y1224803D03*
X1062991Y1228543D03*
X1074212Y1250984D03*
X1066732Y1254724D03*
X1070472Y1247243D03*
X1074212Y1254724D03*
X1062991Y1247243D03*
X1070472Y1243503D03*
X1062991Y1239763D03*
X1066732Y1250984D03*
X1089172Y1075196D03*
Y1078936D03*
Y1097637D03*
Y1093897D03*
X1077952Y1187401D03*
X1081692D03*
X1077952Y1194881D03*
Y1202362D03*
X1089172Y1191141D03*
Y1198621D03*
X1081692Y1202362D03*
X1085432Y1198621D03*
X1081692Y1194881D03*
X1085432Y1191141D03*
X1089172Y1206102D03*
X1077952Y1209842D03*
X1081692D03*
Y1217322D03*
X1089172Y1213582D03*
X1077952Y1217322D03*
X1085432Y1206102D03*
Y1213582D03*
X1089172Y1232283D03*
X1081692D03*
Y1236023D03*
X1089172D03*
X1077952Y1224803D03*
Y1228543D03*
X1085432Y1224803D03*
Y1228543D03*
X1077952Y1243503D03*
X1081692Y1250984D03*
X1077952Y1247243D03*
X1081692Y1254724D03*
X1085432Y1243503D03*
X1089172Y1254724D03*
Y1250984D03*
X1085432Y1247243D03*
X1096653Y1075196D03*
X1104133D03*
X1100393Y1082677D03*
X1104133Y1078936D03*
X1107873Y1082677D03*
Y1086417D03*
X1092913Y1082677D03*
X1100393Y1086417D03*
X1092913D03*
X1096653Y1078936D03*
X1092913Y1105117D03*
X1104133Y1097637D03*
X1096653D03*
X1100393Y1105117D03*
X1104133Y1093897D03*
X1100393Y1101376D03*
X1096653Y1093897D03*
X1092913Y1101376D03*
X1107873Y1105117D03*
Y1101376D03*
X1100393Y1228543D03*
X1104133Y1236023D03*
X1092913Y1224803D03*
X1104133Y1232283D03*
X1107873Y1224803D03*
X1096653Y1236023D03*
X1100393Y1224803D03*
X1107873Y1228543D03*
X1096653Y1232283D03*
X1092913Y1228543D03*
X1096653Y1254724D03*
X1104133D03*
X1092913Y1247243D03*
X1096653Y1250984D03*
X1092913Y1243503D03*
X1107873D03*
X1100393D03*
X1107873Y1247243D03*
X1100393D03*
X1104133Y1250984D03*
X1111613Y1075196D03*
X1119094D03*
X1122834Y1086417D03*
X1119094Y1078936D03*
X1115354Y1082677D03*
X1111613Y1078936D03*
X1115354Y1086417D03*
X1122834Y1082677D03*
X1119094Y1097637D03*
X1115354Y1101376D03*
X1111613Y1093897D03*
Y1097637D03*
X1122834Y1105117D03*
X1119094Y1093897D03*
X1122834Y1101376D03*
X1115354Y1105117D03*
X1122834Y1224803D03*
X1119094Y1232283D03*
X1115354Y1228543D03*
X1111613Y1232283D03*
X1119094Y1236023D03*
X1115354Y1224803D03*
X1111613Y1236023D03*
X1122834Y1228543D03*
Y1243503D03*
X1119094Y1250984D03*
X1111613Y1254724D03*
X1119094D03*
X1122834Y1247243D03*
X1115354Y1243503D03*
Y1247243D03*
X1111613Y1250984D03*
X1126574Y1075196D03*
X1134054D03*
Y1078936D03*
X1126574D03*
X1130314Y1086417D03*
Y1082677D03*
X1137795Y1086417D03*
Y1082677D03*
X1126574Y1093897D03*
X1130314Y1105117D03*
X1134054Y1093897D03*
X1130314Y1101376D03*
X1134054Y1097637D03*
X1137794Y1105117D03*
X1126574Y1097637D03*
X1137794Y1101376D03*
X1134054Y1236023D03*
X1137795Y1228543D03*
X1134054Y1232283D03*
X1126574D03*
Y1236023D03*
X1137795Y1224803D03*
X1130314Y1228543D03*
Y1224803D03*
X1126574Y1254724D03*
X1137795Y1243503D03*
X1130314Y1247243D03*
X1126574Y1250984D03*
X1137795Y1247243D03*
X1130314Y1243503D03*
X1134054Y1250984D03*
Y1254724D03*
X1141535Y1075196D03*
X1156494D03*
X1149014Y1075195D03*
X1145275Y1086417D03*
Y1082677D03*
X1141535Y1078936D03*
X1149014Y1078935D03*
X1156494Y1078936D03*
X1152754Y1086416D03*
Y1082676D03*
X1145275Y1105117D03*
X1141535Y1093897D03*
X1145275Y1101376D03*
X1141535Y1097637D03*
X1149014D03*
X1156494Y1093897D03*
X1152755Y1101376D03*
X1156494Y1097637D03*
X1149014Y1093897D03*
X1152755Y1105117D03*
X1149015Y1236023D03*
Y1232283D03*
X1152755Y1228543D03*
X1145275Y1224803D03*
X1156495Y1232283D03*
Y1236023D03*
X1141535D03*
X1145275Y1228543D03*
X1152755Y1224803D03*
X1141535Y1232283D03*
Y1254724D03*
Y1250984D03*
X1149015Y1254724D03*
X1145275Y1247243D03*
X1152755Y1243503D03*
X1156495Y1254724D03*
X1145275Y1243503D03*
X1152755Y1247243D03*
X1149015Y1250984D03*
X1156495D03*
X1163975Y1075196D03*
X1171455D03*
X1160234Y1086417D03*
X1167715Y1086416D03*
X1163975Y1078936D03*
X1160234Y1082677D03*
X1171455Y1078936D03*
X1167715Y1082676D03*
X1160235Y1105117D03*
Y1101376D03*
X1171455Y1093897D03*
X1167716Y1105117D03*
X1171455Y1097637D03*
X1163975Y1093897D03*
Y1097637D03*
X1167716Y1101376D03*
X1160235Y1224803D03*
X1163976Y1232283D03*
X1167716Y1224803D03*
X1160235Y1228543D03*
X1171456Y1232283D03*
X1163976Y1236023D03*
X1171456D03*
X1167716Y1228543D03*
X1171456Y1250984D03*
X1167716Y1247243D03*
X1163976Y1250984D03*
X1160235Y1247243D03*
Y1243503D03*
X1167716D03*
X1171456Y1254724D03*
X1163976D03*
X1178935Y1075196D03*
X1186416D03*
X1175195Y1086417D03*
X1182675Y1086416D03*
X1175195Y1082677D03*
X1178935Y1078936D03*
X1182675Y1082676D03*
X1186416Y1078936D03*
X1178935Y1097637D03*
X1186416Y1093897D03*
X1182676Y1105117D03*
X1175196D03*
X1178935Y1093897D03*
X1182676Y1101376D03*
X1175196D03*
X1186416Y1097637D03*
X1182676Y1228543D03*
X1186417Y1236023D03*
X1178936D03*
X1186417Y1232283D03*
X1175196Y1228543D03*
X1178936Y1232283D03*
X1182676Y1224803D03*
X1175196D03*
X1178936Y1254724D03*
X1175196Y1243503D03*
X1182676Y1247243D03*
X1178936Y1250984D03*
X1186417D03*
X1182676Y1243503D03*
X1186417Y1254724D03*
X1175196Y1247243D03*
X1193896Y1075196D03*
X1201376D03*
X1190155Y1086417D03*
X1205116Y1082677D03*
X1190155D03*
X1197636Y1082676D03*
X1193896Y1078936D03*
X1205116Y1086417D03*
X1201376Y1078936D03*
X1197636Y1086416D03*
X1201376Y1093897D03*
X1193896Y1097637D03*
X1197637Y1105117D03*
X1205117D03*
X1197637Y1101376D03*
X1205117D03*
X1190157D03*
X1193896Y1093897D03*
X1201376Y1097637D03*
X1190157Y1105117D03*
X1197637Y1224803D03*
X1193897Y1236023D03*
X1190157Y1228543D03*
X1201377Y1236023D03*
X1190157Y1224803D03*
X1193897Y1232283D03*
X1197637Y1228543D03*
X1201377Y1232283D03*
X1205117Y1228543D03*
Y1224803D03*
X1190157Y1243503D03*
X1201377Y1250984D03*
X1197637Y1247243D03*
X1193897Y1250984D03*
X1201377Y1254724D03*
X1197637Y1243503D03*
X1193897Y1254724D03*
X1190157Y1247243D03*
X1205117Y1243503D03*
Y1247243D03*
X1216337Y1075196D03*
X1208857D03*
X1212597Y1082676D03*
Y1086416D03*
X1220077Y1086417D03*
X1208857Y1078936D03*
X1216337D03*
X1220077Y1082677D03*
X1220078Y1105117D03*
X1216337Y1093897D03*
X1212598Y1101376D03*
Y1105117D03*
X1208857Y1093897D03*
X1216337Y1097637D03*
X1220078Y1101376D03*
X1208857Y1097637D03*
X1212598Y1123818D03*
X1208857Y1116338D03*
X1212598D03*
X1216338Y1120078D03*
Y1112598D03*
X1208857Y1123818D03*
X1220078Y1112598D03*
Y1120078D03*
X1216338Y1127559D03*
Y1135039D03*
X1212598Y1131299D03*
X1208857D03*
X1220078Y1135039D03*
Y1127559D03*
X1212598Y1198621D03*
X1208858D03*
X1216338Y1202362D03*
X1220078D03*
Y1217322D03*
Y1209842D03*
X1212598Y1206102D03*
X1216338Y1217322D03*
X1212598Y1213582D03*
X1208858Y1206102D03*
Y1213582D03*
X1216338Y1209842D03*
X1220078Y1224803D03*
X1212598Y1228543D03*
X1208858Y1232283D03*
X1216338Y1236023D03*
Y1232283D03*
X1212598Y1224803D03*
X1220078Y1228543D03*
X1208858Y1236023D03*
X1212598Y1243503D03*
X1220078Y1247243D03*
Y1243503D03*
X1212598Y1247243D03*
X1208858Y1254724D03*
Y1250984D03*
X1216338Y1254724D03*
Y1250984D03*
X1231297Y1075196D03*
X1223817D03*
X1235039Y1090157D03*
X1231297Y1078936D03*
X1235039Y1082676D03*
X1227557Y1086417D03*
X1223817Y1078936D03*
X1227557Y1082677D03*
X1227558Y1101377D03*
X1231298Y1093897D03*
X1235039Y1101377D03*
X1227558Y1105117D03*
X1223817Y1093897D03*
Y1097637D03*
X1231298D03*
X1227558Y1112598D03*
X1235039Y1123818D03*
X1231298Y1120078D03*
Y1112598D03*
X1235039Y1108858D03*
Y1116338D03*
X1227558Y1120078D03*
X1231298Y1135039D03*
X1227558Y1127558D03*
X1235039Y1131299D03*
X1231298Y1127558D03*
X1227558Y1135039D03*
X1231298Y1202362D03*
X1235039Y1198621D03*
X1227558Y1202362D03*
X1235039Y1213582D03*
X1231298Y1209842D03*
X1227558D03*
X1235039Y1221062D03*
X1231298Y1217322D03*
X1235039Y1206102D03*
X1227558Y1217322D03*
X1231298Y1232283D03*
X1227558Y1228543D03*
Y1224803D03*
X1223818Y1236023D03*
X1231298D03*
X1235039Y1228543D03*
X1223818Y1232283D03*
X1227558Y1247243D03*
X1231298Y1254724D03*
X1223818D03*
Y1250984D03*
X1235039Y1239763D03*
X1227558Y1243503D03*
X1231298Y1250984D03*
X1235039Y1247243D03*
X1238779Y1090157D03*
Y1082676D03*
Y1101377D03*
Y1108858D03*
Y1116338D03*
Y1123818D03*
Y1131299D03*
Y1198621D03*
Y1221062D03*
Y1206102D03*
Y1213582D03*
Y1228543D03*
Y1247243D03*
Y1239763D03*
X1523819Y1187401D03*
X1527559D03*
X1516338Y1198621D03*
X1523819Y1194881D03*
X1520078Y1198621D03*
X1523819Y1202362D03*
X1516338Y1191141D03*
X1527559Y1202362D03*
Y1194881D03*
X1520078Y1191141D03*
Y1221062D03*
X1516338Y1213582D03*
Y1206102D03*
X1520078D03*
X1527559Y1217322D03*
X1523819Y1209842D03*
X1516338Y1221062D03*
X1527559Y1209842D03*
X1523819Y1217322D03*
X1520078Y1213582D03*
X1527559Y1228543D03*
X1516338D03*
X1523819Y1232283D03*
X1520078Y1228543D03*
X1523819Y1236023D03*
X1527559Y1224803D03*
X1516338Y1239763D03*
X1520078D03*
Y1247243D03*
X1516338D03*
X1527559Y1243503D03*
Y1247243D03*
X1523819Y1250984D03*
Y1254724D03*
X1546259Y1075196D03*
Y1078936D03*
Y1097637D03*
Y1093897D03*
X1535039Y1187401D03*
X1538779D03*
X1542519Y1191141D03*
X1538779Y1202362D03*
X1535039Y1194881D03*
X1542519Y1198621D03*
X1546259D03*
Y1191141D03*
X1535039Y1202362D03*
X1538779Y1194881D03*
X1542519Y1213582D03*
Y1206102D03*
X1546259Y1213582D03*
X1535039Y1209842D03*
Y1217322D03*
X1546259Y1206102D03*
X1538779Y1209842D03*
Y1217322D03*
X1546259Y1232283D03*
X1535039Y1224803D03*
X1538779Y1236023D03*
X1531299Y1232283D03*
X1542519Y1228543D03*
X1535039D03*
X1546259Y1236023D03*
X1542519Y1224803D03*
X1531299Y1236023D03*
X1538779Y1232283D03*
X1546259Y1250984D03*
X1542519Y1243503D03*
X1546259Y1254724D03*
X1542519Y1247243D03*
X1538779Y1250984D03*
Y1254724D03*
X1535039Y1243503D03*
X1531299Y1250984D03*
X1535039Y1247243D03*
X1531299Y1254724D03*
X1553740Y1075196D03*
X1561220D03*
X1557480Y1082677D03*
X1553740Y1078936D03*
X1561220D03*
X1550000Y1086417D03*
Y1082677D03*
X1557480Y1086417D03*
Y1101376D03*
X1561220Y1093897D03*
X1557480Y1105117D03*
X1561220Y1097637D03*
X1550000Y1101376D03*
Y1105117D03*
X1553740Y1093897D03*
Y1097637D03*
Y1232283D03*
X1550000Y1228543D03*
X1553740Y1236023D03*
X1550000Y1224803D03*
X1557480Y1228543D03*
X1561220Y1236023D03*
Y1232283D03*
X1557480Y1224803D03*
X1561220Y1250984D03*
Y1254724D03*
X1550000Y1243503D03*
X1557480Y1247243D03*
X1550000D03*
X1557480Y1243503D03*
X1553740Y1250984D03*
Y1254724D03*
X1576181Y1075196D03*
X1568700D03*
Y1078936D03*
X1572441Y1086417D03*
X1564960Y1082677D03*
Y1086417D03*
X1572441Y1082677D03*
X1576181Y1078936D03*
X1564960Y1105117D03*
X1576181Y1097637D03*
X1568700D03*
X1576181Y1093897D03*
X1568700D03*
X1572441Y1101376D03*
Y1105117D03*
X1564960Y1101376D03*
X1572441Y1228543D03*
X1568700Y1236023D03*
X1564960Y1224803D03*
X1576181Y1236023D03*
X1572441Y1224803D03*
X1564960Y1228543D03*
X1576181Y1232283D03*
X1568700D03*
Y1254724D03*
X1572441Y1247243D03*
X1576181Y1254724D03*
X1564960Y1243503D03*
Y1247243D03*
X1576181Y1250984D03*
X1572441Y1243503D03*
X1568700Y1250984D03*
X1583661Y1075196D03*
X1591141D03*
X1594882Y1082677D03*
X1579921D03*
X1583661Y1078936D03*
X1594882Y1086417D03*
X1587401Y1082677D03*
X1579921Y1086417D03*
X1587401D03*
X1591141Y1078936D03*
X1594881Y1105117D03*
X1591141Y1097637D03*
X1583661Y1093897D03*
X1594881Y1101376D03*
X1583661Y1097637D03*
X1587401Y1105117D03*
X1579921Y1101376D03*
X1591141Y1093897D03*
X1587401Y1101376D03*
X1579921Y1105117D03*
X1594882Y1224803D03*
X1591141Y1232283D03*
X1583661Y1236023D03*
X1579921Y1228543D03*
X1583661Y1232283D03*
X1594882Y1228543D03*
X1579921Y1224803D03*
X1587401Y1228543D03*
Y1224803D03*
X1591141Y1236023D03*
X1583661Y1254724D03*
X1579921Y1247243D03*
X1591141Y1254724D03*
X1587401Y1247243D03*
Y1243503D03*
X1594882D03*
X1579921D03*
X1594882Y1247243D03*
X1583661Y1250984D03*
X1591141D03*
X1606101Y1075195D03*
X1598622Y1075196D03*
X1609841Y1086416D03*
X1606101Y1078935D03*
X1609841Y1082676D03*
X1602362Y1082677D03*
Y1086417D03*
X1598622Y1078936D03*
X1606101Y1093897D03*
X1602362Y1101376D03*
X1598622Y1097637D03*
Y1093897D03*
X1602362Y1105117D03*
X1609842Y1101376D03*
Y1105117D03*
X1606101Y1097637D03*
X1598622Y1236023D03*
X1606102D03*
X1609842Y1228543D03*
X1606102Y1232283D03*
X1602362Y1224803D03*
X1609842D03*
X1602362Y1228543D03*
X1598622Y1232283D03*
Y1254724D03*
Y1250984D03*
X1609842Y1247243D03*
X1606102Y1250984D03*
Y1254724D03*
X1609842Y1243503D03*
X1602362Y1247243D03*
Y1243503D03*
X1613581Y1075196D03*
X1621062D03*
X1613581Y1078936D03*
X1624802Y1082676D03*
X1617321Y1082677D03*
X1621062Y1078936D03*
X1617321Y1086417D03*
X1624802Y1086416D03*
X1621062Y1093897D03*
X1617322Y1105117D03*
Y1101376D03*
X1613581Y1093897D03*
Y1097637D03*
X1624803Y1101376D03*
Y1105117D03*
X1621062Y1097637D03*
X1617322Y1228543D03*
X1624803Y1224803D03*
X1617322D03*
X1621063Y1236023D03*
X1613582D03*
X1621063Y1232283D03*
X1624803Y1228543D03*
X1613582Y1232283D03*
X1624803Y1247243D03*
Y1243503D03*
X1621063Y1254724D03*
X1613582Y1250984D03*
X1617322Y1243503D03*
Y1247243D03*
X1613582Y1254724D03*
X1621063Y1250984D03*
X1636022Y1075196D03*
X1643503D03*
X1628542D03*
X1632282Y1082677D03*
X1643503Y1078936D03*
X1628542D03*
X1639762Y1086416D03*
X1632282Y1086417D03*
X1636022Y1078936D03*
X1639762Y1082676D03*
X1639763Y1101376D03*
X1628542Y1093897D03*
X1636022D03*
X1639763Y1105117D03*
X1632283D03*
Y1101376D03*
X1636022Y1097637D03*
X1643503D03*
Y1093897D03*
X1628542Y1097637D03*
X1632283Y1228543D03*
X1628543Y1236023D03*
Y1232283D03*
X1639763Y1224803D03*
X1636023Y1236023D03*
X1643504Y1232283D03*
X1632283Y1224803D03*
X1643504Y1236023D03*
X1636023Y1232283D03*
X1639763Y1228543D03*
X1632283Y1243503D03*
X1636023Y1254724D03*
X1639763Y1243503D03*
X1636023Y1250984D03*
X1632283Y1247243D03*
X1643504Y1250984D03*
X1628543D03*
X1639763Y1247243D03*
X1628543Y1254724D03*
X1643504D03*
X1650983Y1075196D03*
X1658463D03*
X1654723Y1086416D03*
Y1082676D03*
X1650983Y1078936D03*
X1647242Y1082677D03*
Y1086417D03*
X1658463Y1078936D03*
Y1097637D03*
X1647244Y1101376D03*
X1658463Y1093897D03*
X1654724Y1105117D03*
X1650983Y1093897D03*
X1647244Y1105117D03*
X1654724Y1101376D03*
X1650983Y1097637D03*
X1654724Y1228543D03*
X1647244D03*
X1658464Y1232283D03*
X1654724Y1224803D03*
X1658464Y1236023D03*
X1650984D03*
X1647244Y1224803D03*
X1650984Y1232283D03*
X1654724Y1243503D03*
X1650984Y1250984D03*
X1647244Y1247243D03*
X1654724D03*
X1647244Y1243503D03*
X1650984Y1254724D03*
X1658464D03*
Y1250984D03*
X1673424Y1075196D03*
X1665944D03*
X1662203Y1086417D03*
Y1082677D03*
X1669684Y1086416D03*
X1665944Y1078936D03*
X1673424D03*
X1669684Y1082676D03*
X1665944Y1093897D03*
X1662204Y1105117D03*
X1669685D03*
X1673424Y1097637D03*
X1669685Y1101376D03*
X1673424Y1093897D03*
X1665944Y1097637D03*
X1662204Y1101376D03*
X1673425Y1112598D03*
X1665944Y1123818D03*
X1673425Y1120078D03*
X1669685Y1123818D03*
X1665944Y1116338D03*
X1669685D03*
X1665944Y1131299D03*
X1669685D03*
X1673425Y1127559D03*
Y1135039D03*
Y1202362D03*
X1665945Y1198621D03*
X1669685D03*
X1665945Y1206102D03*
X1669685Y1213582D03*
X1673425Y1209842D03*
X1669685Y1206102D03*
X1665945Y1213582D03*
X1673425Y1217322D03*
Y1236023D03*
X1662204Y1228543D03*
X1669685D03*
X1673425Y1232283D03*
X1665945D03*
Y1236023D03*
X1662204Y1224803D03*
X1669685D03*
X1673425Y1250984D03*
X1662204Y1247243D03*
X1665945Y1254724D03*
X1673425D03*
X1662204Y1243503D03*
X1665945Y1250984D03*
X1669685Y1247243D03*
Y1243503D03*
X1680904Y1075196D03*
X1688384D03*
X1692126Y1090157D03*
Y1082676D03*
X1684644Y1082677D03*
Y1086417D03*
X1680904Y1078936D03*
X1688384D03*
X1677164Y1086417D03*
Y1082677D03*
X1692126Y1101377D03*
X1684645D03*
X1677165Y1105117D03*
X1680904Y1097637D03*
X1677165Y1101376D03*
X1688385Y1097637D03*
X1684645Y1105117D03*
X1680904Y1093897D03*
X1688385D03*
X1677165Y1120078D03*
Y1112598D03*
X1692126Y1116338D03*
Y1108858D03*
X1684645Y1120078D03*
X1688385D03*
X1684645Y1112598D03*
X1692126Y1123818D03*
X1688385Y1112598D03*
X1677165Y1135039D03*
Y1127559D03*
X1684645Y1135039D03*
Y1127558D03*
X1692126Y1131299D03*
X1688385Y1127558D03*
Y1135039D03*
X1684645Y1202362D03*
X1692126Y1198621D03*
X1688385Y1202362D03*
X1677165D03*
X1692126Y1213582D03*
X1684645Y1217322D03*
Y1209842D03*
X1692126Y1206102D03*
X1677165Y1209842D03*
X1692126Y1221062D03*
X1688385Y1209842D03*
X1677165Y1217322D03*
X1688385D03*
X1677165Y1228543D03*
X1680905Y1236023D03*
Y1232283D03*
X1692126Y1228543D03*
X1684645Y1224803D03*
Y1228543D03*
X1677165Y1224803D03*
X1688385Y1232283D03*
Y1236023D03*
X1684645Y1243503D03*
X1677165D03*
X1692126Y1247243D03*
X1684645D03*
X1677165D03*
X1688385Y1254724D03*
Y1250984D03*
X1692126Y1239763D03*
X1680905Y1254724D03*
Y1250984D03*
X1695866Y1090157D03*
Y1082676D03*
Y1101377D03*
Y1123818D03*
Y1116338D03*
Y1108858D03*
Y1131299D03*
Y1198621D03*
Y1221062D03*
Y1213582D03*
Y1206102D03*
Y1228543D03*
Y1239763D03*
Y1247243D03*
G54D58*
X1250055Y1710189D03*
Y1720189D03*
Y1739208D03*
Y1749208D03*
X1250048Y1768377D03*
Y1778377D03*
X1248555Y1797909D03*
Y1807909D03*
X1734069Y1710189D03*
Y1720189D03*
Y1739208D03*
Y1749208D03*
X1734062Y1768377D03*
Y1778377D03*
X1734069Y1797909D03*
Y1807909D03*
G54D18*
X7983Y1529035D03*
Y1525635D03*
X35688Y111255D03*
Y114655D03*
X28388Y121742D03*
X35688Y125428D03*
X28388Y132515D03*
Y118342D03*
X35688Y128828D03*
X28388Y135915D03*
X35825Y1464845D03*
X39225D03*
X76005Y114623D03*
Y111223D03*
Y125396D03*
Y128796D03*
X76112Y1348187D03*
X79512D03*
X76112Y1360099D03*
X79512D03*
Y1372385D03*
X76112D03*
Y1384297D03*
X79512D03*
X86407Y132509D03*
Y118335D03*
Y121735D03*
Y135909D03*
X88352Y1348187D03*
X91752D03*
X100592D03*
X91752Y1360099D03*
X88352D03*
X100592D03*
Y1384297D03*
Y1372385D03*
X91752D03*
X88352D03*
Y1384297D03*
X91752D03*
Y1396583D03*
X88352D03*
X100592D03*
X91752Y1408495D03*
X88352D03*
X100592D03*
X116232Y1348187D03*
X112832D03*
X103992D03*
X112832Y1360099D03*
X116232D03*
X103992D03*
Y1372385D03*
Y1384297D03*
X112832D03*
X116232Y1372385D03*
Y1384297D03*
X112832Y1372385D03*
X116232Y1396583D03*
X112832D03*
X103992D03*
X112832Y1408495D03*
X116232D03*
X103992D03*
X130750Y132515D03*
Y121742D03*
Y118342D03*
Y135915D03*
X125072Y1348187D03*
X128472D03*
Y1360099D03*
X125072D03*
Y1384297D03*
X128472D03*
X125072Y1372385D03*
X128472D03*
X125072Y1396583D03*
X128472D03*
X125072Y1408495D03*
X128472D03*
X138050Y111255D03*
Y114655D03*
Y128828D03*
Y125428D03*
X148692Y391001D03*
Y394401D03*
Y405174D03*
X140690Y401513D03*
Y398113D03*
X148692Y408574D03*
X138290Y412287D03*
X148692Y419347D03*
Y422747D03*
X138290Y415687D03*
Y426460D03*
X148692Y433521D03*
X138290Y429860D03*
X148692Y436921D03*
X138290Y440633D03*
Y444033D03*
Y469387D03*
Y472787D03*
X148692Y476499D03*
X138290Y483560D03*
X148692Y490673D03*
X138290Y486960D03*
X148692Y479899D03*
Y494073D03*
Y524033D03*
Y520633D03*
X138290Y516921D03*
Y513521D03*
Y531094D03*
X148692Y538206D03*
Y534806D03*
X138290Y527694D03*
X140712Y1348187D03*
X137312D03*
X149552D03*
X137312Y1360099D03*
X140712D03*
X149552D03*
Y1384297D03*
Y1372385D03*
X140712D03*
Y1384297D03*
X137312D03*
Y1372385D03*
X140712Y1396583D03*
X137312D03*
X149552D03*
X140712Y1408495D03*
X137312D03*
X149552D03*
X165192Y1348187D03*
X161792D03*
X152952D03*
X165192Y1360099D03*
X161792D03*
X152952D03*
Y1384297D03*
Y1372385D03*
X161792Y1384297D03*
X165192Y1372385D03*
Y1384297D03*
X161792Y1372385D03*
X165192Y1396583D03*
X161792D03*
X152952D03*
X165192Y1408495D03*
X161792D03*
X152952D03*
X178367Y111223D03*
Y114623D03*
Y128796D03*
Y125396D03*
X177432Y1348187D03*
X174032D03*
Y1360099D03*
X177432D03*
Y1384297D03*
X174032D03*
Y1372385D03*
X177432D03*
Y1396583D03*
X174032D03*
X177432Y1408495D03*
X174032D03*
X188769Y118335D03*
Y121735D03*
Y132509D03*
Y135909D03*
X189672Y1348187D03*
X186272D03*
X198512D03*
X189672Y1360099D03*
X186272D03*
X198512D03*
Y1384297D03*
Y1372385D03*
X186272Y1384297D03*
X189672D03*
Y1372385D03*
X186272D03*
Y1396583D03*
X189672D03*
X198512D03*
X189672Y1408495D03*
X186272D03*
X198512D03*
X212980Y390995D03*
Y405168D03*
Y394395D03*
X205680Y401482D03*
Y398082D03*
X212980Y408568D03*
Y419341D03*
Y422741D03*
X205680Y415655D03*
Y412255D03*
Y426428D03*
Y440602D03*
Y429828D03*
X212980Y433515D03*
Y436915D03*
X205680Y444002D03*
X212980Y469381D03*
Y472781D03*
X205680Y490641D03*
Y479868D03*
X212980Y483554D03*
X205680Y476468D03*
X212980Y486954D03*
X205680Y494041D03*
Y524002D03*
X212980Y516915D03*
Y513515D03*
X205680Y520602D03*
Y534775D03*
X212980Y527688D03*
X205680Y538175D03*
X212980Y531088D03*
X201912Y1348187D03*
Y1360099D03*
Y1384297D03*
Y1372385D03*
Y1396583D03*
Y1408495D03*
X213969Y1447453D03*
Y1461853D03*
Y1458453D03*
Y1450853D03*
X227249Y1447453D03*
Y1450853D03*
Y1458453D03*
Y1461853D03*
X240412Y114655D03*
Y111255D03*
X233112Y132515D03*
Y121742D03*
X240412Y125428D03*
X233112Y118342D03*
X240412Y128828D03*
X233112Y135915D03*
X241623Y1348187D03*
X245023D03*
Y1360099D03*
X241623D03*
X245023Y1372385D03*
X241623D03*
Y1384297D03*
X245023D03*
X264005Y467337D03*
Y470737D03*
X256705Y474424D03*
X264005Y484910D03*
X256705Y488597D03*
X264005Y481510D03*
X256705Y477824D03*
Y491997D03*
X264005Y514871D03*
X256705Y518558D03*
X264005Y511471D03*
X256705Y521958D03*
Y532731D03*
Y536131D03*
X264005Y525644D03*
Y529044D03*
Y561510D03*
X256705Y571997D03*
Y568597D03*
X264005Y564910D03*
X256705Y586171D03*
X264005Y575684D03*
Y579084D03*
X256705Y582771D03*
X264005Y589857D03*
X256705Y600344D03*
X264005Y593257D03*
Y604030D03*
X256705Y596944D03*
Y611117D03*
Y614517D03*
X264005Y607430D03*
X253863Y1348187D03*
X257263D03*
X253863Y1360099D03*
X257263D03*
X253863Y1372385D03*
X257263D03*
X253863Y1384297D03*
X257263D03*
X253863Y1396583D03*
X257263D03*
Y1408495D03*
X253863D03*
X269503Y1348187D03*
X278343D03*
X266103D03*
X278343Y1360099D03*
X266103D03*
X269503D03*
Y1372385D03*
X266103D03*
X278343D03*
X266103Y1384297D03*
X269503D03*
X278343D03*
Y1396583D03*
X269503D03*
X266103D03*
X278343Y1408495D03*
X269503D03*
X266103D03*
X280729Y111223D03*
Y114623D03*
Y125396D03*
X291131Y121735D03*
X280729Y128796D03*
X291131Y118335D03*
Y132509D03*
Y135909D03*
X281743Y1348187D03*
X293983D03*
X290583D03*
X281743Y1360099D03*
X293983D03*
X290583D03*
X293983Y1372385D03*
X281743D03*
X290583Y1384297D03*
X293983D03*
X290583Y1372385D03*
X281743Y1384297D03*
X293983Y1396583D03*
X290583D03*
X281743D03*
Y1408495D03*
X293983D03*
X290583D03*
X302823Y1348187D03*
X306223D03*
Y1360099D03*
X302823D03*
X306223Y1372385D03*
X302823D03*
X306223Y1384297D03*
X302823D03*
Y1396583D03*
X306223D03*
X302823Y1408495D03*
X306223D03*
X320993Y467306D03*
Y470706D03*
Y481479D03*
Y484879D03*
Y514839D03*
Y511439D03*
Y525613D03*
Y529013D03*
Y564879D03*
Y561479D03*
Y575652D03*
Y579052D03*
Y603999D03*
Y593225D03*
Y589825D03*
Y607399D03*
X327303Y1348187D03*
X315063D03*
X318463D03*
X327303Y1360099D03*
X315063D03*
X318463D03*
X315063Y1372385D03*
X318463Y1384297D03*
X315063D03*
X327303Y1372385D03*
X318463D03*
X327303Y1384297D03*
Y1396583D03*
X315063D03*
X318463D03*
X327303Y1408495D03*
X318463D03*
X315063D03*
X342774Y111255D03*
Y114655D03*
X335474Y118342D03*
Y132515D03*
X342774Y125428D03*
X335474Y121742D03*
X342774Y128828D03*
X335474Y135915D03*
X331395Y474418D03*
Y488591D03*
Y477818D03*
Y491991D03*
Y518552D03*
Y521952D03*
Y536125D03*
Y532725D03*
Y568591D03*
Y571991D03*
Y586165D03*
Y582765D03*
Y600338D03*
Y596938D03*
Y611111D03*
Y614511D03*
X339543Y1348187D03*
X342943D03*
X330703D03*
Y1360099D03*
X342943D03*
X339543D03*
Y1372385D03*
X342943D03*
X330703D03*
X342943Y1384297D03*
X339543D03*
X330703D03*
Y1396583D03*
X339543D03*
X342943D03*
X330703Y1408495D03*
X342943D03*
X339543D03*
X351783Y1348187D03*
X355183D03*
Y1360099D03*
X351783D03*
Y1372385D03*
X355183D03*
Y1384297D03*
X351783D03*
Y1396583D03*
X355183D03*
X351783Y1408495D03*
X355183D03*
X364023Y1348187D03*
X367423D03*
Y1360099D03*
X364023D03*
Y1372385D03*
X367423Y1384297D03*
X364023D03*
X367423Y1372385D03*
X364023Y1396583D03*
X367423D03*
X364023Y1408495D03*
X367423D03*
X383091Y111223D03*
Y114623D03*
X393493Y118335D03*
X383091Y125396D03*
Y128796D03*
X393493Y132509D03*
Y121735D03*
Y135909D03*
X392415Y792725D03*
X389015D03*
X440402Y1348187D03*
Y1360099D03*
Y1372385D03*
Y1384297D03*
X452642Y1348187D03*
X456042D03*
X443802D03*
X456042Y1360099D03*
X452642D03*
X443802D03*
Y1372385D03*
X452642D03*
X456042D03*
X452642Y1384297D03*
X456042D03*
X443802D03*
X452642Y1396583D03*
X456042D03*
X452642Y1408495D03*
X456042D03*
X468282Y1348187D03*
X464882D03*
X468282Y1360099D03*
X464882D03*
Y1372385D03*
X468282D03*
X464882Y1384297D03*
X468282D03*
Y1396583D03*
X464882D03*
Y1408495D03*
X468282D03*
X485475Y118342D03*
Y121742D03*
Y132515D03*
Y135915D03*
X489362Y1348187D03*
X480522D03*
X477122D03*
X480522Y1360099D03*
X477122D03*
X489362D03*
X477122Y1372385D03*
X480522D03*
X489362D03*
Y1384297D03*
X480522D03*
X477122D03*
X480522Y1396583D03*
X477122D03*
X489362D03*
X477122Y1408495D03*
X480522D03*
X489362D03*
X492775Y114655D03*
Y111255D03*
Y128828D03*
Y125428D03*
X492762Y1348187D03*
X501602D03*
X505002D03*
X501602Y1360099D03*
X505002D03*
X492762D03*
X505002Y1372385D03*
X492762D03*
X501602D03*
X492762Y1384297D03*
X505002D03*
X501602D03*
X505002Y1396583D03*
X492762D03*
X501602D03*
X505002Y1408495D03*
X501602D03*
X492762D03*
X517242Y1348187D03*
X513842D03*
Y1360099D03*
X517242D03*
Y1372385D03*
X513842D03*
X517242Y1384297D03*
X513842D03*
X517242Y1396583D03*
X513842D03*
X517242Y1408495D03*
X513842D03*
X533092Y114623D03*
Y111223D03*
Y128796D03*
Y125396D03*
X529482Y1348187D03*
X526082D03*
X538322D03*
Y1360099D03*
X529482D03*
X526082D03*
X529482Y1372385D03*
X538322Y1384297D03*
X529482D03*
X538322Y1372385D03*
X526082D03*
Y1384297D03*
Y1396583D03*
X538322D03*
X529482D03*
Y1408495D03*
X526082D03*
X538322D03*
X543494Y121735D03*
Y132509D03*
Y118335D03*
Y135909D03*
X549168Y781600D03*
X545768D03*
X553962Y1348187D03*
X541722D03*
X550562D03*
X553962Y1360099D03*
X550562D03*
X541722D03*
Y1372385D03*
X550562D03*
X541722Y1384297D03*
X553962D03*
X550562D03*
X553962Y1372385D03*
Y1396583D03*
X541722D03*
X550562D03*
X553962Y1408495D03*
X550562D03*
X541722D03*
X562802Y1348187D03*
X566202D03*
Y1360099D03*
X562802D03*
X566202Y1372385D03*
Y1384297D03*
X562802D03*
Y1372385D03*
X566202Y1396583D03*
X562802D03*
X566202Y1408495D03*
X562802D03*
X587837Y118342D03*
Y121742D03*
Y132515D03*
Y135915D03*
X595137Y111255D03*
Y114655D03*
Y125428D03*
Y128828D03*
X597776Y401513D03*
Y398113D03*
X595376Y412287D03*
Y426460D03*
Y415687D03*
Y440633D03*
Y429860D03*
Y444033D03*
Y469387D03*
Y472787D03*
Y483560D03*
Y486960D03*
Y513521D03*
Y516921D03*
Y531094D03*
Y527694D03*
X605778Y391001D03*
Y405174D03*
Y394401D03*
Y408574D03*
Y422747D03*
Y419347D03*
Y433521D03*
Y436921D03*
Y479899D03*
Y490673D03*
Y476499D03*
Y494073D03*
Y520633D03*
Y524033D03*
Y534806D03*
Y538206D03*
X635454Y114623D03*
Y111223D03*
Y128796D03*
Y125396D03*
X629688Y1396583D03*
X626288D03*
Y1408495D03*
X629688D03*
X645856Y118335D03*
Y132509D03*
Y121735D03*
Y135909D03*
X650768Y1348187D03*
Y1360099D03*
Y1384297D03*
Y1372385D03*
X638528D03*
X641928D03*
X638528Y1384297D03*
X641928D03*
Y1396583D03*
X638528D03*
X650768D03*
X638528Y1408495D03*
X641928D03*
X650768D03*
X670066Y390995D03*
Y405168D03*
X662766Y398082D03*
X670066Y408568D03*
Y394395D03*
X662766Y401482D03*
X670066Y422741D03*
Y419341D03*
X662766Y415655D03*
Y426428D03*
Y412255D03*
Y440602D03*
X670066Y433515D03*
X662766Y429828D03*
X670066Y436915D03*
X662766Y444002D03*
X670066Y469381D03*
Y472781D03*
X662766Y476468D03*
Y490641D03*
X670066Y483554D03*
Y486954D03*
X662766Y479868D03*
Y494041D03*
X670066Y516915D03*
X662766Y520602D03*
Y524002D03*
X670066Y513515D03*
Y527688D03*
X662766Y534775D03*
X670066Y531088D03*
X662766Y538175D03*
X666408Y1348187D03*
X663008D03*
X654168D03*
X666408Y1360099D03*
X663008D03*
X654168D03*
Y1384297D03*
Y1372385D03*
X663008D03*
X666408D03*
X663008Y1384297D03*
X666408D03*
Y1396583D03*
X663008D03*
X654168D03*
X666408Y1408495D03*
X663008D03*
X654168D03*
X678648Y1348187D03*
X675248D03*
X678648Y1360099D03*
X675248D03*
Y1384297D03*
X678648D03*
Y1372385D03*
X675248D03*
Y1396583D03*
X678648D03*
Y1408495D03*
X675248D03*
X697499Y114655D03*
Y111255D03*
X690199Y132515D03*
X697499Y125428D03*
Y128828D03*
X690199Y121742D03*
Y118342D03*
Y135915D03*
X690888Y1348187D03*
X687488D03*
X699728D03*
X687488Y1360099D03*
X690888D03*
X699728D03*
Y1372385D03*
Y1384297D03*
X690888Y1372385D03*
X687488D03*
Y1384297D03*
X690888D03*
Y1396583D03*
X687488D03*
X699728D03*
X687488Y1408495D03*
X690888D03*
X699728D03*
X713791Y474424D03*
Y488597D03*
Y477824D03*
Y491997D03*
Y518558D03*
Y521958D03*
Y536131D03*
Y532731D03*
Y571997D03*
Y568597D03*
Y582771D03*
Y586171D03*
Y596944D03*
Y600344D03*
Y611117D03*
Y614517D03*
X715368Y1348187D03*
X711968D03*
X703128D03*
X715368Y1360099D03*
X711968D03*
X703128D03*
Y1372385D03*
Y1384297D03*
X715368Y1372385D03*
X711968D03*
X715368Y1384297D03*
X711968D03*
X715368Y1396583D03*
X711968D03*
X703128D03*
X715368Y1408495D03*
X711968D03*
X703128D03*
X721091Y470737D03*
Y467337D03*
Y484910D03*
Y481510D03*
Y514871D03*
Y511471D03*
Y525644D03*
Y529044D03*
Y561510D03*
Y564910D03*
Y579084D03*
Y575684D03*
Y593257D03*
Y604030D03*
Y589857D03*
Y607430D03*
X727608Y1348187D03*
X724208D03*
Y1360099D03*
X727608D03*
X724208Y1372385D03*
Y1384297D03*
X727608D03*
Y1372385D03*
X724208Y1396489D03*
X727608D03*
X724208Y1408401D03*
X727608D03*
X737816Y114623D03*
Y111223D03*
X748218Y118335D03*
X737816Y128796D03*
X748218Y132509D03*
Y121735D03*
X737816Y125396D03*
X748218Y135909D03*
X739848Y1348187D03*
X736448D03*
X748688D03*
X736448Y1360099D03*
X739848D03*
X748688D03*
Y1372385D03*
Y1384297D03*
X739848Y1372385D03*
X736448D03*
X739848Y1384297D03*
X736448D03*
X739848Y1396489D03*
X736448D03*
X739848Y1408401D03*
X736448D03*
X760928Y1348187D03*
X764328D03*
X752088D03*
X764328Y1360099D03*
X760928D03*
X752088D03*
Y1372385D03*
Y1384297D03*
X764328Y1372385D03*
X760928D03*
X764328Y1384297D03*
X760928D03*
X778079Y467306D03*
Y470706D03*
Y481479D03*
Y484879D03*
Y514839D03*
Y511439D03*
Y529013D03*
Y525613D03*
Y561479D03*
Y564879D03*
Y575652D03*
Y579052D03*
Y589825D03*
Y593225D03*
Y603999D03*
Y607399D03*
X776568Y1348187D03*
X773168D03*
Y1360099D03*
X776568D03*
X799861Y114655D03*
Y111255D03*
X792561Y132515D03*
Y118342D03*
X799861Y128828D03*
X792561Y121742D03*
X799861Y125428D03*
X792561Y135915D03*
X788481Y474418D03*
Y477818D03*
Y488591D03*
Y491991D03*
Y518552D03*
Y521952D03*
Y532725D03*
Y536125D03*
Y571991D03*
Y568591D03*
Y586165D03*
Y582765D03*
Y600338D03*
Y596938D03*
Y614511D03*
Y611111D03*
X840178Y114623D03*
Y111223D03*
Y128796D03*
Y125396D03*
X850580Y118335D03*
Y132509D03*
Y121735D03*
Y135909D03*
X917882Y328216D03*
Y324816D03*
X915954Y344150D03*
X919354D03*
X927964Y344041D03*
X924564D03*
X919163Y848442D03*
Y851592D03*
X942561Y118342D03*
Y132515D03*
Y121742D03*
Y135915D03*
X942731Y324044D03*
X939331D03*
X940997Y331912D03*
Y335312D03*
X942700Y346363D03*
X939300D03*
X945982Y886737D03*
X949861Y111255D03*
Y114655D03*
Y125428D03*
Y128828D03*
X949382Y886737D03*
X990178Y114623D03*
Y111223D03*
Y128796D03*
Y125396D03*
X1011187Y-33526D03*
Y-30126D03*
X1000580Y121735D03*
Y118335D03*
Y132509D03*
Y135909D03*
X1052223Y111255D03*
Y114655D03*
X1044923Y118342D03*
X1052223Y125428D03*
Y128828D03*
X1044923Y132515D03*
Y121742D03*
Y135915D03*
X1054863Y401513D03*
Y398113D03*
X1052463Y412287D03*
Y415687D03*
Y426460D03*
Y440633D03*
Y429860D03*
Y444033D03*
Y469387D03*
Y472787D03*
Y486960D03*
Y483560D03*
Y513521D03*
Y516921D03*
Y531094D03*
Y527694D03*
X1058113Y1348187D03*
X1054713D03*
X1058113Y1360099D03*
X1054713D03*
X1058113Y1372385D03*
X1054713D03*
Y1384297D03*
X1058113D03*
X1062865Y391001D03*
Y408574D03*
Y405174D03*
Y394401D03*
Y422747D03*
Y419347D03*
Y436921D03*
Y433521D03*
Y476499D03*
Y479899D03*
Y490673D03*
Y494073D03*
Y520633D03*
Y524033D03*
Y534806D03*
Y538206D03*
X1066953Y1348187D03*
X1070353D03*
X1066953Y1360099D03*
X1070353D03*
X1066953Y1384297D03*
Y1372385D03*
X1070353D03*
Y1384297D03*
Y1396583D03*
X1066953D03*
Y1408495D03*
X1070353D03*
X1081187Y-72706D03*
Y-69306D03*
X1092540Y111223D03*
Y114623D03*
Y128796D03*
Y125396D03*
X1091433Y1348187D03*
X1082593D03*
X1079193D03*
X1091433Y1360099D03*
X1082593D03*
X1079193D03*
Y1372385D03*
X1082593D03*
Y1384297D03*
X1079193D03*
X1091433D03*
Y1372385D03*
Y1396583D03*
X1082593D03*
X1079193D03*
X1091433Y1408495D03*
X1082593D03*
X1079193D03*
X1102942Y118335D03*
Y132509D03*
Y121735D03*
Y135909D03*
X1094833Y1348187D03*
X1107073D03*
X1103673D03*
X1094833Y1360099D03*
X1103673D03*
X1107073D03*
Y1372385D03*
X1103673D03*
X1107073Y1384297D03*
X1103673D03*
X1094833D03*
Y1372385D03*
Y1396583D03*
X1107073D03*
X1103673D03*
X1094833Y1408495D03*
X1107073D03*
X1103673D03*
X1119853Y398082D03*
Y401482D03*
Y412255D03*
Y426428D03*
Y415655D03*
Y440602D03*
Y429828D03*
Y444002D03*
Y490641D03*
Y476468D03*
Y479868D03*
Y494041D03*
Y524002D03*
Y520602D03*
Y538175D03*
Y534775D03*
X1115913Y1348187D03*
X1119313D03*
X1115913Y1360099D03*
X1119313D03*
Y1384297D03*
X1115913Y1372385D03*
X1119313D03*
X1115913Y1384297D03*
Y1396583D03*
X1119313D03*
X1115913Y1408495D03*
X1119313D03*
X1127153Y390995D03*
Y408568D03*
Y405168D03*
Y394395D03*
Y422741D03*
Y419341D03*
Y436915D03*
Y433515D03*
Y472781D03*
Y469381D03*
Y486954D03*
Y483554D03*
Y516915D03*
Y513515D03*
Y527688D03*
Y531088D03*
X1140393Y1348187D03*
X1131553D03*
X1128153D03*
X1140393Y1360099D03*
X1131553D03*
X1128153D03*
Y1384297D03*
X1131553D03*
X1128153Y1372385D03*
X1131553D03*
X1140393Y1384297D03*
Y1372385D03*
Y1396583D03*
X1131553D03*
X1128153D03*
X1140393Y1408495D03*
X1128153D03*
X1131553D03*
X1154585Y114655D03*
Y111255D03*
Y128828D03*
X1147285Y118342D03*
Y121742D03*
Y132515D03*
X1154585Y125428D03*
X1147285Y135915D03*
X1143793Y1348187D03*
X1156033D03*
X1152633D03*
X1143793Y1360099D03*
X1152633D03*
X1156033D03*
Y1384297D03*
X1152633D03*
X1156033Y1372385D03*
X1152633D03*
X1143793D03*
Y1384297D03*
Y1396583D03*
X1156033D03*
X1152633D03*
X1143793Y1408495D03*
X1152633D03*
X1156033D03*
X1170878Y474424D03*
Y477824D03*
Y488597D03*
Y491997D03*
Y518558D03*
Y521958D03*
Y532731D03*
Y536131D03*
Y571997D03*
Y568597D03*
Y586171D03*
Y582771D03*
Y596944D03*
Y600344D03*
Y614517D03*
Y611117D03*
X1168273Y1348187D03*
X1164873D03*
Y1360099D03*
X1168273D03*
Y1384297D03*
X1164873D03*
X1168273Y1372385D03*
X1164873D03*
Y1396583D03*
X1168273D03*
Y1408495D03*
X1164873D03*
X1178178Y467337D03*
Y470737D03*
Y484910D03*
Y481510D03*
Y511471D03*
Y514871D03*
Y529044D03*
Y525644D03*
Y564910D03*
Y561510D03*
Y579084D03*
Y575684D03*
Y604030D03*
Y593257D03*
Y589857D03*
Y607430D03*
X1177113Y1348187D03*
X1180513D03*
X1177113Y1360099D03*
X1180513D03*
X1177113Y1384297D03*
X1180513D03*
X1177113Y1372385D03*
X1180513D03*
Y1396583D03*
X1177113D03*
Y1408495D03*
X1180513D03*
X1194902Y114623D03*
Y111223D03*
X1205304Y118335D03*
Y121735D03*
X1194902Y128796D03*
X1205304Y132509D03*
X1194902Y125396D03*
X1205304Y135909D03*
X1225405Y-72678D03*
Y-69278D03*
X1230761Y-33628D03*
Y-30228D03*
X1235166Y470706D03*
Y467306D03*
Y484879D03*
Y481479D03*
Y514839D03*
Y511439D03*
Y529013D03*
Y525613D03*
Y564879D03*
Y561479D03*
Y575652D03*
Y579052D03*
Y593225D03*
Y603999D03*
Y589825D03*
Y607399D03*
X1230326Y1348187D03*
X1233726D03*
X1230326Y1360099D03*
X1233726D03*
X1230326Y1372385D03*
X1233726D03*
X1230326Y1384297D03*
X1233726D03*
X1249647Y118342D03*
Y132515D03*
Y121742D03*
Y135915D03*
X1245568Y474418D03*
Y488591D03*
Y477818D03*
Y491991D03*
Y521952D03*
Y518552D03*
Y536125D03*
Y532725D03*
Y568591D03*
Y571991D03*
Y582765D03*
Y586165D03*
Y596938D03*
Y600338D03*
Y611111D03*
Y614511D03*
X1245966Y1348187D03*
X1242566D03*
X1254806D03*
Y1360099D03*
X1242566D03*
X1245966D03*
X1254806Y1372385D03*
X1242566D03*
X1245966D03*
X1242566Y1384297D03*
X1245966D03*
X1254806D03*
X1245966Y1396583D03*
X1254806D03*
X1242566D03*
X1254806Y1408495D03*
X1242566D03*
X1245966D03*
X1256947Y114655D03*
Y111255D03*
Y128828D03*
Y125428D03*
X1267046Y1348187D03*
X1270446D03*
X1258206D03*
Y1360099D03*
X1270446D03*
X1267046D03*
X1258206Y1372385D03*
X1270446D03*
X1267046D03*
X1270446Y1384297D03*
X1267046D03*
X1258206D03*
X1267046Y1396583D03*
X1270446D03*
X1258206D03*
Y1408495D03*
X1270446D03*
X1267046D03*
X1282686Y1348187D03*
X1279286D03*
Y1360099D03*
X1282686D03*
X1279286Y1372385D03*
X1282686D03*
Y1384297D03*
X1279286D03*
Y1396583D03*
X1282686D03*
X1279286Y1408495D03*
X1282686D03*
X1297687Y-33656D03*
Y-30256D03*
X1297264Y114623D03*
Y111223D03*
Y128796D03*
Y125396D03*
X1291526Y1348187D03*
X1294926D03*
X1291526Y1360099D03*
X1294926D03*
X1291526Y1372385D03*
X1294926D03*
X1291526Y1384297D03*
X1294926D03*
Y1396583D03*
X1291526D03*
Y1408495D03*
X1294926D03*
X1307666Y118335D03*
Y132509D03*
Y121735D03*
Y135909D03*
X1319406Y1348187D03*
X1316006D03*
X1307166D03*
X1303766D03*
X1319406Y1360099D03*
X1316006D03*
X1307166D03*
X1303766D03*
X1316006Y1372385D03*
X1307166D03*
X1303766D03*
Y1384297D03*
X1307166D03*
X1319406Y1372385D03*
X1316006Y1384297D03*
X1319406D03*
Y1396583D03*
X1316006D03*
X1303766D03*
X1307166D03*
X1316006Y1408495D03*
X1319406D03*
X1307166D03*
X1303766D03*
X1328246Y1348187D03*
X1331646D03*
X1328246Y1360099D03*
X1331646D03*
Y1384297D03*
Y1372385D03*
X1328246D03*
Y1384297D03*
X1331646Y1396583D03*
X1328246D03*
X1331646Y1408495D03*
X1328246D03*
X1337687Y-69306D03*
Y-72706D03*
X1343886Y1348187D03*
X1340486D03*
X1343886Y1360099D03*
X1340486D03*
X1343886Y1372385D03*
X1340486D03*
Y1384297D03*
X1343886D03*
X1340486Y1396583D03*
X1343886D03*
Y1408495D03*
X1340486D03*
X1356126Y1348187D03*
X1352726D03*
X1356126Y1360099D03*
X1352726D03*
Y1384297D03*
X1356126Y1372385D03*
Y1384297D03*
X1352726Y1372385D03*
X1356126Y1396583D03*
X1352726D03*
Y1408495D03*
X1356126D03*
X1399648Y132515D03*
Y121742D03*
Y118342D03*
Y135915D03*
X1406948Y111255D03*
Y114655D03*
Y128828D03*
Y125428D03*
X1447265Y111223D03*
Y114623D03*
Y125396D03*
Y128796D03*
X1457667Y118335D03*
Y121735D03*
Y132509D03*
Y135909D03*
X1464770Y1348187D03*
X1461370D03*
X1464770Y1360099D03*
X1461370D03*
X1464770Y1372385D03*
X1461370D03*
X1464770Y1384297D03*
X1461370D03*
X1481905Y-69278D03*
Y-72678D03*
X1477010Y1348187D03*
X1473610D03*
Y1360099D03*
X1477010D03*
X1473610Y1372385D03*
X1477010D03*
X1473610Y1384297D03*
X1477010D03*
Y1396583D03*
X1473610D03*
Y1408495D03*
X1477010D03*
X1489250Y1348187D03*
X1485850D03*
X1498090D03*
Y1360099D03*
X1485850D03*
X1489250D03*
Y1372385D03*
X1485850D03*
X1498090D03*
X1485850Y1384297D03*
X1498090D03*
X1489250D03*
X1498090Y1396583D03*
X1485850D03*
X1489250D03*
X1498090Y1408495D03*
X1489250D03*
X1485850D03*
X1509310Y114655D03*
Y111255D03*
X1502010Y121742D03*
X1509310Y125428D03*
Y128828D03*
X1502010Y118342D03*
Y132515D03*
Y135915D03*
X1511950Y401513D03*
Y398113D03*
X1509550Y412287D03*
Y415687D03*
Y426460D03*
Y440633D03*
Y429860D03*
Y444033D03*
Y472787D03*
Y469387D03*
Y483560D03*
Y486960D03*
Y516921D03*
Y513521D03*
Y527694D03*
Y531094D03*
X1513730Y1348187D03*
X1510330D03*
X1501490D03*
X1510330Y1360099D03*
X1501490D03*
X1513730D03*
X1510330Y1372385D03*
X1513730D03*
X1501490D03*
Y1384297D03*
X1513730D03*
X1510330D03*
Y1396583D03*
X1513730D03*
X1501490D03*
X1510330Y1408495D03*
X1513730D03*
X1501490D03*
X1517261Y-33758D03*
Y-30358D03*
X1519952Y391001D03*
Y394401D03*
Y408574D03*
Y405174D03*
Y422747D03*
Y419347D03*
Y436921D03*
Y433521D03*
Y479899D03*
Y476499D03*
Y490673D03*
Y494073D03*
Y520633D03*
Y524033D03*
Y534806D03*
Y538206D03*
X1525970Y1348187D03*
X1522570D03*
Y1360099D03*
X1525970D03*
Y1372385D03*
X1522570D03*
X1525970Y1384297D03*
X1522570D03*
Y1396583D03*
X1525970D03*
Y1408495D03*
X1522570D03*
X1538210Y1348187D03*
X1547050D03*
X1534810D03*
X1538210Y1360099D03*
X1534810D03*
X1547050D03*
X1538210Y1372385D03*
X1534810D03*
X1547050D03*
Y1384297D03*
X1534810D03*
X1538210D03*
Y1396583D03*
X1534810D03*
X1547050D03*
X1538210Y1408495D03*
X1534810D03*
X1547050D03*
X1549627Y111223D03*
Y114623D03*
Y128796D03*
X1560029Y132509D03*
Y121735D03*
Y118335D03*
X1549627Y125396D03*
X1560029Y135909D03*
X1550450Y1348187D03*
X1559290D03*
X1562690D03*
X1559290Y1360099D03*
X1562690D03*
X1550450D03*
X1562690Y1372385D03*
X1559290D03*
X1550450D03*
X1562690Y1384297D03*
X1559290D03*
X1550450D03*
Y1396583D03*
X1562690D03*
X1559290D03*
Y1408495D03*
X1562690D03*
X1550450D03*
X1576940Y398082D03*
Y401482D03*
Y415655D03*
Y412255D03*
Y426428D03*
Y440602D03*
Y429828D03*
Y444002D03*
Y476468D03*
Y490641D03*
Y479868D03*
Y494041D03*
Y520602D03*
Y524002D03*
Y534775D03*
Y538175D03*
X1574930Y1348187D03*
X1571530D03*
X1574930Y1360099D03*
X1571530D03*
X1574930Y1372385D03*
X1571530D03*
Y1384297D03*
X1574930D03*
X1571530Y1396583D03*
X1574930D03*
X1571530Y1408495D03*
X1574930D03*
X1592187Y-69306D03*
Y-72706D03*
X1582187Y-33786D03*
Y-30386D03*
X1584240Y390995D03*
Y408568D03*
Y405168D03*
Y394395D03*
Y419341D03*
Y422741D03*
Y433515D03*
Y436915D03*
Y472781D03*
Y469381D03*
Y483554D03*
Y486954D03*
Y516915D03*
Y513515D03*
Y531088D03*
Y527688D03*
X1587170Y1348187D03*
X1583770D03*
X1587170Y1360099D03*
X1583770D03*
X1587170Y1372385D03*
X1583770D03*
Y1384297D03*
X1587170D03*
X1583770Y1396583D03*
X1587170D03*
X1583770Y1408495D03*
X1587170D03*
X1611672Y111255D03*
Y114655D03*
X1604372Y118342D03*
X1611672Y125428D03*
X1604372Y121742D03*
X1611672Y128828D03*
X1604372Y132515D03*
Y135915D03*
X1611398Y1348187D03*
Y1360099D03*
Y1384297D03*
Y1372385D03*
X1627965Y474424D03*
Y488597D03*
Y477824D03*
Y491997D03*
Y521958D03*
Y518558D03*
Y536131D03*
Y532731D03*
Y571997D03*
Y568597D03*
Y582771D03*
Y586171D03*
Y596944D03*
Y600344D03*
Y614517D03*
Y611117D03*
X1614798Y1348187D03*
X1623638D03*
X1627038D03*
X1614798Y1360099D03*
X1623638D03*
X1627038D03*
Y1372385D03*
X1623638D03*
X1627038Y1384297D03*
X1623638D03*
X1614798Y1372385D03*
Y1384297D03*
X1627038Y1396583D03*
X1623638D03*
X1627038Y1408495D03*
X1623638D03*
X1635265Y470737D03*
Y467337D03*
Y484910D03*
Y481510D03*
Y514871D03*
Y511471D03*
Y529044D03*
Y525644D03*
Y564910D03*
Y561510D03*
Y575684D03*
Y579084D03*
Y593257D03*
Y604030D03*
Y589857D03*
Y607430D03*
X1639278Y1348187D03*
X1635878D03*
X1639278Y1360099D03*
X1635878D03*
Y1384297D03*
X1639278D03*
Y1372385D03*
X1635878D03*
X1639278Y1396583D03*
X1635878D03*
Y1408495D03*
X1639278D03*
X1651989Y114623D03*
Y111223D03*
Y125396D03*
Y128796D03*
X1660358Y1348187D03*
X1651518D03*
X1648118D03*
X1660358Y1360099D03*
X1651518D03*
X1648118D03*
Y1372385D03*
X1651518D03*
X1648118Y1384297D03*
X1651518D03*
X1660358D03*
Y1372385D03*
Y1396583D03*
X1651518D03*
X1648118D03*
X1660358Y1408495D03*
X1648118D03*
X1651518D03*
X1662391Y118335D03*
Y121735D03*
Y132509D03*
Y135909D03*
X1663758Y1348187D03*
X1672598D03*
X1675998D03*
X1663758Y1360099D03*
X1675998D03*
X1672598D03*
X1675998Y1372385D03*
X1672598D03*
Y1384297D03*
X1675998D03*
X1663758D03*
Y1372385D03*
Y1396583D03*
X1675998D03*
X1672598D03*
X1663758Y1408495D03*
X1675998D03*
X1672598D03*
X1692253Y467306D03*
Y470706D03*
Y484879D03*
Y481479D03*
Y511439D03*
Y514839D03*
Y529013D03*
Y525613D03*
Y561479D03*
Y564879D03*
Y575652D03*
Y579052D03*
Y593225D03*
Y603999D03*
Y589825D03*
Y607399D03*
X1688238Y1348187D03*
X1684838D03*
X1688238Y1360099D03*
X1684838D03*
Y1384297D03*
X1688238D03*
X1684838Y1372385D03*
X1688238D03*
X1684838Y1396583D03*
X1688238D03*
Y1408495D03*
X1684838D03*
X1706734Y118342D03*
Y132515D03*
Y121742D03*
Y135915D03*
X1702655Y474418D03*
Y477818D03*
Y488591D03*
Y491991D03*
Y521952D03*
Y518552D03*
Y536125D03*
Y532725D03*
Y571991D03*
Y568591D03*
Y586165D03*
Y582765D03*
Y600338D03*
Y596938D03*
Y611111D03*
Y614511D03*
X1709318Y1348187D03*
X1700478D03*
X1697078D03*
X1709318Y1360099D03*
X1697078D03*
X1700478D03*
X1697078Y1372385D03*
X1700478D03*
X1697078Y1384297D03*
X1700478D03*
X1709318D03*
Y1372385D03*
Y1396583D03*
X1700478D03*
X1697078D03*
X1709318Y1408495D03*
X1697078D03*
X1700478D03*
X1714034Y111255D03*
Y114655D03*
Y125428D03*
Y128828D03*
X1712718Y1348187D03*
X1721558D03*
X1724958D03*
X1712718Y1360099D03*
X1724958D03*
X1721558D03*
Y1372385D03*
X1724958D03*
Y1384297D03*
X1721558D03*
X1712718Y1372385D03*
Y1384297D03*
Y1396583D03*
X1721558D03*
X1724958D03*
X1712718Y1408495D03*
X1721558D03*
X1724958D03*
X1736405Y-69278D03*
Y-72678D03*
X1733798Y1348187D03*
X1737198D03*
X1733798Y1360099D03*
X1737198D03*
Y1384297D03*
X1733798D03*
Y1372385D03*
X1737198D03*
Y1396583D03*
X1733798D03*
X1737198Y1408495D03*
X1733798D03*
X1754351Y111223D03*
Y114623D03*
Y128796D03*
Y125396D03*
X1764753Y121735D03*
Y118335D03*
Y132509D03*
Y135909D03*
X1801761Y-33888D03*
Y-30488D03*
G54D11*
X13780Y1226024D03*
X79331Y1186654D03*
X390354Y1141024D03*
X536418Y1086654D03*
X854291Y1225118D03*
X993504Y1170748D03*
X1304528Y1141024D03*
X1450591Y1086654D03*
X1761614Y1215000D03*
X1827165Y1235630D03*
G54D44*
X661674Y23622D03*
G54D19*
X23622Y1604724D03*
X62205Y765197D03*
X74016Y333464D03*
X102224Y70866D03*
X409488Y1604724D03*
X433130Y70866D03*
X463387Y286221D03*
X463386Y765197D03*
X785039Y1547638D03*
X890217Y23622D03*
X920473Y765196D03*
X1055905Y1547637D03*
X1118760Y23622D03*
X1347303Y70866D03*
X1377559Y286220D03*
Y765197D03*
X1431457Y1604724D03*
X1575846Y23622D03*
X1766929Y333464D03*
X1778740Y765197D03*
X1795010Y23622D03*
X1817323Y1604724D03*
G54D20*
X28819Y81575D03*
X73307Y61614D03*
X131181Y81575D03*
X175669Y61614D03*
X233543Y81575D03*
X278032Y61614D03*
X335906Y81575D03*
X380394Y61614D03*
X485886Y81595D03*
X530394Y61614D03*
X588248Y81594D03*
X632756Y61614D03*
X690611Y81595D03*
X735118Y61614D03*
X792973Y81595D03*
X837480Y61614D03*
X942973Y81595D03*
X987480Y61614D03*
X1045335Y81595D03*
X1089843Y61614D03*
X1147697Y81595D03*
X1192205Y61614D03*
X1250060Y81595D03*
X1294567Y61614D03*
X1400060Y81595D03*
X1444567Y61614D03*
X1502441Y81575D03*
X1546929Y61614D03*
X1604784Y81595D03*
X1649291Y61614D03*
X1707146Y81595D03*
X1751654Y61614D03*
G54D32*
X109882Y1458622D03*
Y1463741D03*
Y1473977D03*
Y1479095D03*
Y1489331D03*
Y1494449D03*
Y1504685D03*
Y1509804D03*
Y1560985D03*
Y1566103D03*
Y1576339D03*
Y1581457D03*
Y1591693D03*
Y1596811D03*
Y1607048D03*
Y1612166D03*
X127205Y1458622D03*
Y1463741D03*
X118543Y1462953D03*
X127205Y1473977D03*
Y1479095D03*
X118543Y1468071D03*
Y1478308D03*
X127205Y1489331D03*
Y1494449D03*
X118543Y1483426D03*
Y1493662D03*
Y1498780D03*
X127205Y1504685D03*
Y1509804D03*
X118543Y1509016D03*
Y1514134D03*
X127205Y1560985D03*
Y1566103D03*
Y1576339D03*
X118543Y1565315D03*
Y1570434D03*
X127205Y1581457D03*
Y1591693D03*
X118543Y1580670D03*
Y1585788D03*
Y1596024D03*
X127205Y1596811D03*
Y1607048D03*
Y1612166D03*
X118543Y1601142D03*
Y1611378D03*
Y1616496D03*
X144528Y1458622D03*
Y1463741D03*
X135866Y1462953D03*
X144528Y1473977D03*
Y1479095D03*
X135866Y1468071D03*
Y1478308D03*
X144528Y1489331D03*
Y1494449D03*
X135866Y1483426D03*
Y1493662D03*
Y1498780D03*
X144528Y1504685D03*
Y1509804D03*
X135866Y1509016D03*
Y1514134D03*
X144528Y1560985D03*
Y1566103D03*
Y1576339D03*
X135866Y1565315D03*
Y1570434D03*
X144528Y1581457D03*
Y1591693D03*
X135866Y1580670D03*
Y1585788D03*
Y1596024D03*
X144528Y1596811D03*
Y1607048D03*
Y1612166D03*
X135866Y1601142D03*
Y1611378D03*
Y1616496D03*
X161850Y1458622D03*
Y1463741D03*
X153189Y1462953D03*
X161850Y1473977D03*
Y1479095D03*
X153189Y1468071D03*
Y1478308D03*
X161850Y1489331D03*
Y1494449D03*
X153189Y1483426D03*
Y1493662D03*
Y1498780D03*
X161850Y1504685D03*
Y1509804D03*
X153189Y1509016D03*
Y1514134D03*
X161850Y1560985D03*
Y1566103D03*
Y1576339D03*
X153189Y1565315D03*
Y1570434D03*
X161850Y1581457D03*
Y1591693D03*
X153189Y1580670D03*
Y1585788D03*
Y1596024D03*
X161850Y1596811D03*
Y1607048D03*
Y1612166D03*
X153189Y1601142D03*
Y1611378D03*
Y1616496D03*
X179173Y1458622D03*
Y1463741D03*
X170512Y1462953D03*
X179173Y1473977D03*
Y1479095D03*
X170512Y1468071D03*
Y1478308D03*
Y1483426D03*
Y1493662D03*
Y1498780D03*
Y1509016D03*
Y1514134D03*
Y1565315D03*
Y1570434D03*
Y1580670D03*
Y1585788D03*
Y1596024D03*
Y1601142D03*
Y1611378D03*
Y1616496D03*
X187835Y1462953D03*
Y1468071D03*
Y1478308D03*
Y1483426D03*
Y1596024D03*
Y1601142D03*
Y1611378D03*
Y1616496D03*
X283110Y1458622D03*
X291771Y1462953D03*
X283110Y1463741D03*
X291771Y1468071D03*
X283110Y1473977D03*
X291771Y1478308D03*
X283110Y1479095D03*
X291771Y1483426D03*
X283110Y1489331D03*
X291771Y1493662D03*
X283110Y1494449D03*
X291771Y1498780D03*
X283110Y1504685D03*
X291771Y1509016D03*
X283110Y1509804D03*
X291771Y1514134D03*
X283110Y1560985D03*
X291771Y1565315D03*
X283110Y1566103D03*
X291771Y1570434D03*
X283110Y1576339D03*
X291771Y1580670D03*
X283110Y1581457D03*
X291771Y1585788D03*
X283110Y1591693D03*
X291771Y1596024D03*
X283110Y1596811D03*
X291771Y1601142D03*
X283110Y1607048D03*
X291771Y1611378D03*
X283110Y1612166D03*
X291771Y1616496D03*
X300433Y1458622D03*
X309094Y1462953D03*
X300433Y1463741D03*
X309094Y1468071D03*
X300433Y1473977D03*
X309094Y1478308D03*
X300433Y1479095D03*
X309094Y1483426D03*
X300433Y1489331D03*
X309094Y1493662D03*
X300433Y1494449D03*
X309094Y1498780D03*
X300433Y1504685D03*
X309094Y1509016D03*
X300433Y1509804D03*
X309094Y1514134D03*
X300433Y1560985D03*
X309094Y1565315D03*
X300433Y1566103D03*
X309094Y1570434D03*
X300433Y1576339D03*
X309094Y1580670D03*
X300433Y1581457D03*
X309094Y1585788D03*
X300433Y1591693D03*
X309094Y1596024D03*
X300433Y1596811D03*
X309094Y1601142D03*
X300433Y1607048D03*
X309094Y1611378D03*
X300433Y1612166D03*
X309094Y1616496D03*
X317756Y1458622D03*
X326417Y1462953D03*
X317756Y1463741D03*
X326417Y1468071D03*
X317756Y1473977D03*
X326417Y1478308D03*
X317756Y1479095D03*
X326417Y1483426D03*
X317756Y1489331D03*
X326417Y1493662D03*
X317756Y1494449D03*
X326417Y1498780D03*
X317756Y1504685D03*
X326417Y1509016D03*
X317756Y1509804D03*
X326417Y1514134D03*
X317756Y1560985D03*
X326417Y1565315D03*
X317756Y1566103D03*
X326417Y1570434D03*
X317756Y1576339D03*
X326417Y1580670D03*
X317756Y1581457D03*
X326417Y1585788D03*
X317756Y1591693D03*
X326417Y1596024D03*
X317756Y1596811D03*
X326417Y1601142D03*
X317756Y1607048D03*
X326417Y1611378D03*
X317756Y1612166D03*
X326417Y1616496D03*
X335078Y1458622D03*
X343740Y1462953D03*
X335078Y1463741D03*
X343740Y1468071D03*
X335078Y1473977D03*
X343740Y1478308D03*
X335078Y1479095D03*
X343740Y1483426D03*
X335078Y1489331D03*
X343740Y1493662D03*
X335078Y1494449D03*
X343740Y1498780D03*
X335078Y1504685D03*
X343740Y1509016D03*
X335078Y1509804D03*
X343740Y1514134D03*
X335078Y1560985D03*
X343740Y1565315D03*
X335078Y1566103D03*
X343740Y1570434D03*
X335078Y1576339D03*
X343740Y1580670D03*
X335078Y1581457D03*
X343740Y1585788D03*
X335078Y1591693D03*
X343740Y1596024D03*
X335078Y1596811D03*
X343740Y1601142D03*
X335078Y1607048D03*
X343740Y1611378D03*
X335078Y1612166D03*
X343740Y1616496D03*
X361063Y1596024D03*
Y1601142D03*
Y1611378D03*
Y1616496D03*
X456339Y1458622D03*
Y1463741D03*
Y1473977D03*
Y1479095D03*
Y1489331D03*
Y1494449D03*
Y1504685D03*
Y1509804D03*
Y1560985D03*
Y1566103D03*
Y1576339D03*
Y1581457D03*
Y1591693D03*
Y1596811D03*
Y1607048D03*
Y1612166D03*
X473662Y1458622D03*
Y1463741D03*
X465000Y1462953D03*
X473662Y1473977D03*
Y1479095D03*
X465000Y1468071D03*
Y1478308D03*
X473662Y1489331D03*
Y1494449D03*
X465000Y1483426D03*
Y1493662D03*
Y1498780D03*
X473662Y1504685D03*
Y1509804D03*
X465000Y1509016D03*
Y1514134D03*
X473662Y1560985D03*
Y1566103D03*
Y1576339D03*
X465000Y1565315D03*
Y1570434D03*
X473662Y1581457D03*
Y1591693D03*
X465000Y1580670D03*
Y1585788D03*
Y1596024D03*
X473662Y1596811D03*
Y1607048D03*
Y1612166D03*
X465000Y1601142D03*
Y1611378D03*
Y1616496D03*
X490985Y1458622D03*
Y1463741D03*
X482323Y1462953D03*
X490985Y1473977D03*
Y1479095D03*
X482323Y1468071D03*
Y1478308D03*
X490985Y1489331D03*
Y1494449D03*
X482323Y1483426D03*
Y1493662D03*
Y1498780D03*
X490985Y1504685D03*
Y1509804D03*
X482323Y1509016D03*
Y1514134D03*
X490985Y1560985D03*
Y1566103D03*
Y1576339D03*
X482323Y1565315D03*
Y1570434D03*
X490985Y1581457D03*
Y1591693D03*
X482323Y1580670D03*
Y1585788D03*
Y1596024D03*
X490985Y1596811D03*
Y1607048D03*
Y1612166D03*
X482323Y1601142D03*
Y1611378D03*
Y1616496D03*
X499646Y1462953D03*
Y1468071D03*
Y1478308D03*
Y1483426D03*
Y1493662D03*
Y1498780D03*
Y1509016D03*
Y1514134D03*
Y1565315D03*
Y1570434D03*
Y1580670D03*
Y1585788D03*
Y1596024D03*
Y1601142D03*
Y1611378D03*
Y1616496D03*
X508307Y1458622D03*
X516969Y1462953D03*
X508307Y1463741D03*
X516969Y1468071D03*
X508307Y1473977D03*
X516969Y1478308D03*
X508307Y1479095D03*
X516969Y1483426D03*
X508307Y1489331D03*
X516969Y1493662D03*
X508307Y1494449D03*
X516969Y1498780D03*
X508307Y1504685D03*
X516969Y1509016D03*
X508307Y1509804D03*
X516969Y1514134D03*
X508307Y1560985D03*
X516969Y1565315D03*
X508307Y1566103D03*
X516969Y1570434D03*
X508307Y1576339D03*
X516969Y1580670D03*
X508307Y1581457D03*
X516969Y1585788D03*
X508307Y1591693D03*
X516969Y1596024D03*
X508307Y1596811D03*
X516969Y1601142D03*
X508307Y1607048D03*
X516969Y1611378D03*
X508307Y1612166D03*
X516969Y1616496D03*
X629567Y1458622D03*
Y1463741D03*
Y1473977D03*
Y1479095D03*
Y1489331D03*
Y1494449D03*
Y1504685D03*
Y1509804D03*
Y1560985D03*
Y1566103D03*
Y1576339D03*
Y1581457D03*
Y1591693D03*
Y1596811D03*
Y1607048D03*
Y1612166D03*
X646890Y1458622D03*
Y1463741D03*
X638228Y1462953D03*
X646890Y1473977D03*
Y1479095D03*
X638228Y1468071D03*
Y1478308D03*
X646890Y1489331D03*
Y1494449D03*
X638228Y1483426D03*
Y1493662D03*
Y1498780D03*
X646890Y1504685D03*
Y1509804D03*
X638228Y1509016D03*
Y1514134D03*
X646890Y1560985D03*
Y1566103D03*
Y1576339D03*
X638228Y1565315D03*
Y1570434D03*
X646890Y1581457D03*
Y1591693D03*
X638228Y1580670D03*
Y1585788D03*
Y1596024D03*
X646890Y1596811D03*
Y1607048D03*
Y1612166D03*
X638228Y1601142D03*
Y1611378D03*
Y1616496D03*
X664213Y1458622D03*
Y1463741D03*
X655551Y1462953D03*
X664213Y1473977D03*
Y1479095D03*
X655551Y1468071D03*
Y1478308D03*
X664213Y1489331D03*
Y1494449D03*
X655551Y1483426D03*
Y1493662D03*
Y1498780D03*
X664213Y1504685D03*
Y1509804D03*
X655551Y1509016D03*
Y1514134D03*
X664213Y1560985D03*
Y1566103D03*
Y1576339D03*
X655551Y1565315D03*
Y1570434D03*
X664213Y1581457D03*
Y1591693D03*
X655551Y1580670D03*
Y1585788D03*
Y1596024D03*
X664213Y1596811D03*
Y1607048D03*
Y1612166D03*
X655551Y1601142D03*
Y1611378D03*
Y1616496D03*
X681535Y1458622D03*
Y1463741D03*
X672874Y1462953D03*
X681535Y1473977D03*
Y1479095D03*
X672874Y1468071D03*
Y1478308D03*
X681535Y1489331D03*
Y1494449D03*
X672874Y1483426D03*
Y1493662D03*
Y1498780D03*
X681535Y1504685D03*
Y1509804D03*
X672874Y1509016D03*
Y1514134D03*
X681535Y1560985D03*
Y1566103D03*
Y1576339D03*
X672874Y1565315D03*
Y1570434D03*
X681535Y1581457D03*
Y1591693D03*
X672874Y1580670D03*
Y1585788D03*
Y1596024D03*
X681535Y1596811D03*
Y1607048D03*
Y1612166D03*
X672874Y1601142D03*
Y1611378D03*
Y1616496D03*
X690197Y1462953D03*
Y1468071D03*
Y1478308D03*
Y1483426D03*
Y1493662D03*
Y1498780D03*
Y1509016D03*
Y1514134D03*
Y1565315D03*
Y1570434D03*
Y1580670D03*
Y1585788D03*
Y1596024D03*
Y1601142D03*
Y1611378D03*
Y1616496D03*
X1131850Y1458622D03*
X1140511Y1462953D03*
X1131850Y1463741D03*
X1140511Y1468071D03*
X1131850Y1473977D03*
X1140511Y1478308D03*
X1131850Y1479095D03*
X1140511Y1483426D03*
X1131850Y1489331D03*
X1140511Y1493662D03*
X1131850Y1494449D03*
X1140511Y1498780D03*
X1131850Y1504685D03*
X1140511Y1509016D03*
X1131850Y1509804D03*
X1140511Y1514134D03*
X1131850Y1560985D03*
X1140511Y1565315D03*
X1131850Y1566103D03*
X1140511Y1570434D03*
X1131850Y1576339D03*
X1140511Y1580670D03*
X1131850Y1581457D03*
X1140511Y1585788D03*
X1131850Y1591693D03*
X1140511Y1596024D03*
X1131850Y1596811D03*
X1140511Y1601142D03*
X1131850Y1607048D03*
X1140511Y1611378D03*
X1131850Y1612166D03*
X1140511Y1616496D03*
X1149173Y1458622D03*
Y1463741D03*
Y1473977D03*
Y1479095D03*
Y1489331D03*
Y1494449D03*
Y1504685D03*
Y1509804D03*
Y1560985D03*
Y1566103D03*
Y1576339D03*
Y1581457D03*
Y1591693D03*
Y1596811D03*
Y1607048D03*
Y1612166D03*
X1166496Y1458622D03*
Y1463741D03*
X1157834Y1462953D03*
X1166496Y1473977D03*
Y1479095D03*
X1157834Y1468071D03*
Y1478308D03*
X1166496Y1489331D03*
Y1494449D03*
X1157834Y1483426D03*
Y1493662D03*
Y1498780D03*
X1166496Y1504685D03*
Y1509804D03*
X1157834Y1509016D03*
Y1514134D03*
X1166496Y1560985D03*
Y1566103D03*
Y1576339D03*
X1157834Y1565315D03*
Y1570434D03*
X1166496Y1581457D03*
Y1591693D03*
X1157834Y1580670D03*
Y1585788D03*
Y1596024D03*
X1166496Y1596811D03*
Y1607048D03*
Y1612166D03*
X1157834Y1601142D03*
Y1611378D03*
Y1616496D03*
X1183818Y1458622D03*
Y1463741D03*
X1175157Y1462953D03*
X1183818Y1473977D03*
Y1479095D03*
X1175157Y1468071D03*
Y1478308D03*
X1183818Y1489331D03*
Y1494449D03*
X1175157Y1483426D03*
Y1493662D03*
Y1498780D03*
X1183818Y1504685D03*
Y1509804D03*
X1175157Y1509016D03*
Y1514134D03*
X1183818Y1560985D03*
Y1566103D03*
Y1576339D03*
X1175157Y1565315D03*
Y1570434D03*
X1183818Y1581457D03*
Y1591693D03*
X1175157Y1580670D03*
Y1585788D03*
Y1596024D03*
X1183818Y1596811D03*
Y1607048D03*
Y1612166D03*
X1175157Y1601142D03*
Y1611378D03*
Y1616496D03*
X1192480Y1462953D03*
Y1468071D03*
Y1478308D03*
Y1483426D03*
Y1493662D03*
Y1498780D03*
Y1509016D03*
Y1514134D03*
Y1565315D03*
Y1570434D03*
Y1580670D03*
Y1585788D03*
Y1596024D03*
Y1601142D03*
Y1611378D03*
Y1616496D03*
X1305079Y1458622D03*
X1313740Y1462953D03*
X1305079Y1463741D03*
X1313740Y1468071D03*
X1305079Y1473977D03*
X1313740Y1478308D03*
X1305079Y1479095D03*
X1313740Y1483426D03*
X1305079Y1489331D03*
X1313740Y1493662D03*
X1305079Y1494449D03*
X1313740Y1498780D03*
X1305079Y1504685D03*
X1313740Y1509016D03*
X1305079Y1509804D03*
X1313740Y1514134D03*
X1305079Y1560985D03*
X1313740Y1565315D03*
X1305079Y1566103D03*
X1313740Y1570434D03*
X1305079Y1576339D03*
X1313740Y1580670D03*
X1305079Y1581457D03*
X1313740Y1585788D03*
X1305079Y1591693D03*
X1313740Y1596024D03*
X1305079Y1596811D03*
X1313740Y1601142D03*
X1305079Y1607048D03*
X1313740Y1611378D03*
X1305079Y1612166D03*
X1313740Y1616496D03*
X1322402Y1458622D03*
X1331063Y1462953D03*
X1322402Y1463741D03*
X1331063Y1468071D03*
X1322402Y1473977D03*
X1331063Y1478308D03*
X1322402Y1479095D03*
X1331063Y1483426D03*
X1322402Y1489331D03*
X1331063Y1493662D03*
X1322402Y1494449D03*
X1331063Y1498780D03*
X1322402Y1504685D03*
X1331063Y1509016D03*
X1322402Y1509804D03*
X1331063Y1514134D03*
X1322402Y1560985D03*
X1331063Y1565315D03*
X1322402Y1566103D03*
X1331063Y1570434D03*
X1322402Y1576339D03*
X1331063Y1580670D03*
X1322402Y1581457D03*
X1331063Y1585788D03*
X1322402Y1591693D03*
X1331063Y1596024D03*
X1322402Y1596811D03*
X1331063Y1601142D03*
X1322402Y1607048D03*
X1331063Y1611378D03*
X1322402Y1612166D03*
X1331063Y1616496D03*
X1339725Y1458622D03*
X1348386Y1462953D03*
X1339725Y1463741D03*
X1348386Y1468071D03*
X1339725Y1473977D03*
X1348386Y1478308D03*
X1339725Y1479095D03*
X1348386Y1483426D03*
X1339725Y1489331D03*
X1348386Y1493662D03*
X1339725Y1494449D03*
X1348386Y1498780D03*
X1339725Y1504685D03*
X1348386Y1509016D03*
X1339725Y1509804D03*
X1348386Y1514134D03*
X1339725Y1560985D03*
X1348386Y1565315D03*
X1339725Y1566103D03*
X1348386Y1570434D03*
X1339725Y1576339D03*
X1348386Y1580670D03*
X1339725Y1581457D03*
X1348386Y1585788D03*
X1339725Y1591693D03*
X1348386Y1596024D03*
X1339725Y1596811D03*
X1348386Y1601142D03*
X1339725Y1607048D03*
X1348386Y1611378D03*
X1339725Y1612166D03*
X1348386Y1616496D03*
X1357047Y1458622D03*
X1365709Y1462953D03*
X1357047Y1463741D03*
X1365709Y1468071D03*
X1357047Y1473977D03*
X1365709Y1478308D03*
X1357047Y1479095D03*
X1365709Y1483426D03*
X1357047Y1489331D03*
X1365709Y1493662D03*
X1357047Y1494449D03*
X1365709Y1498780D03*
X1357047Y1504685D03*
X1365709Y1509016D03*
X1357047Y1509804D03*
X1365709Y1514134D03*
X1357047Y1560985D03*
X1365709Y1565315D03*
X1357047Y1566103D03*
X1365709Y1570434D03*
X1357047Y1576339D03*
X1365709Y1580670D03*
X1357047Y1581457D03*
X1365709Y1585788D03*
X1357047Y1591693D03*
X1365709Y1596024D03*
X1357047Y1596811D03*
X1365709Y1601142D03*
X1357047Y1607048D03*
X1365709Y1611378D03*
X1357047Y1612166D03*
X1365709Y1616496D03*
X1478307Y1458622D03*
Y1463741D03*
Y1473977D03*
Y1479095D03*
Y1489331D03*
Y1494449D03*
Y1504685D03*
Y1509804D03*
Y1560985D03*
Y1566103D03*
Y1576339D03*
Y1581457D03*
Y1591693D03*
Y1596811D03*
Y1607048D03*
Y1612166D03*
X1495630Y1458622D03*
Y1463741D03*
X1486968Y1462953D03*
X1495630Y1473977D03*
Y1479095D03*
X1486968Y1468071D03*
Y1478308D03*
X1495630Y1489331D03*
Y1494449D03*
X1486968Y1483426D03*
Y1493662D03*
Y1498780D03*
X1495630Y1504685D03*
Y1509804D03*
X1486968Y1509016D03*
Y1514134D03*
X1495630Y1560985D03*
Y1566103D03*
Y1576339D03*
X1486968Y1565315D03*
Y1570434D03*
X1495630Y1581457D03*
Y1591693D03*
X1486968Y1580670D03*
Y1585788D03*
Y1596024D03*
X1495630Y1596811D03*
Y1607048D03*
Y1612166D03*
X1486968Y1601142D03*
Y1611378D03*
Y1616496D03*
X1512953Y1458622D03*
Y1463741D03*
X1504291Y1462953D03*
X1512953Y1473977D03*
Y1479095D03*
X1504291Y1468071D03*
Y1478308D03*
X1512953Y1489331D03*
Y1494449D03*
X1504291Y1483426D03*
Y1493662D03*
Y1498780D03*
X1512953Y1504685D03*
Y1509804D03*
X1504291Y1509016D03*
Y1514134D03*
X1512953Y1560985D03*
Y1566103D03*
Y1576339D03*
X1504291Y1565315D03*
Y1570434D03*
X1512953Y1581457D03*
Y1591693D03*
X1504291Y1580670D03*
Y1585788D03*
Y1596024D03*
X1512953Y1596811D03*
Y1607048D03*
Y1612166D03*
X1504291Y1601142D03*
Y1611378D03*
Y1616496D03*
X1530275Y1458622D03*
Y1463741D03*
X1521614Y1462953D03*
X1530275Y1473977D03*
Y1479095D03*
X1521614Y1468071D03*
Y1478308D03*
X1530275Y1489331D03*
Y1494449D03*
X1521614Y1483426D03*
Y1493662D03*
Y1498780D03*
X1530275Y1504685D03*
Y1509804D03*
X1521614Y1509016D03*
Y1514134D03*
X1530275Y1560985D03*
Y1566103D03*
Y1576339D03*
X1521614Y1565315D03*
Y1570434D03*
X1530275Y1581457D03*
Y1591693D03*
X1521614Y1580670D03*
Y1585788D03*
Y1596024D03*
X1530275Y1596811D03*
Y1607048D03*
Y1612166D03*
X1521614Y1601142D03*
Y1611378D03*
Y1616496D03*
X1538937Y1462953D03*
Y1468071D03*
Y1478308D03*
Y1483426D03*
Y1493662D03*
Y1498780D03*
Y1509016D03*
Y1514134D03*
Y1565315D03*
Y1570434D03*
Y1580670D03*
Y1585788D03*
Y1596024D03*
Y1601142D03*
Y1611378D03*
Y1616496D03*
X1651535Y1458622D03*
X1660196Y1462953D03*
X1651535Y1463741D03*
X1660196Y1468071D03*
X1651535Y1473977D03*
X1660196Y1478308D03*
X1651535Y1479095D03*
X1660196Y1483426D03*
X1651535Y1489331D03*
X1660196Y1493662D03*
X1651535Y1494449D03*
X1660196Y1498780D03*
X1651535Y1504685D03*
X1660196Y1509016D03*
X1651535Y1509804D03*
X1660196Y1514134D03*
X1651535Y1560985D03*
X1660196Y1565315D03*
X1651535Y1566103D03*
X1660196Y1570434D03*
X1651535Y1576339D03*
X1660196Y1580670D03*
X1651535Y1581457D03*
X1660196Y1585788D03*
X1651535Y1591693D03*
X1660196Y1596024D03*
X1651535Y1596811D03*
X1660196Y1601142D03*
X1651535Y1607048D03*
X1660196Y1611378D03*
X1651535Y1612166D03*
X1660196Y1616496D03*
X1668858Y1458622D03*
Y1463741D03*
Y1473977D03*
Y1479095D03*
Y1489331D03*
Y1494449D03*
Y1504685D03*
Y1509804D03*
Y1560985D03*
Y1566103D03*
Y1576339D03*
Y1581457D03*
Y1591693D03*
Y1596811D03*
Y1607048D03*
Y1612166D03*
X1686181Y1458622D03*
Y1463741D03*
X1677519Y1462953D03*
X1686181Y1473977D03*
Y1479095D03*
X1677519Y1468071D03*
Y1478308D03*
X1686181Y1489331D03*
Y1494449D03*
X1677519Y1483426D03*
Y1493662D03*
Y1498780D03*
X1686181Y1504685D03*
Y1509804D03*
X1677519Y1509016D03*
Y1514134D03*
X1686181Y1560985D03*
Y1566103D03*
Y1576339D03*
X1677519Y1565315D03*
Y1570434D03*
X1686181Y1581457D03*
Y1591693D03*
X1677519Y1580670D03*
Y1585788D03*
Y1596024D03*
X1686181Y1596811D03*
Y1607048D03*
Y1612166D03*
X1677519Y1601142D03*
Y1611378D03*
Y1616496D03*
X1703503Y1458622D03*
Y1463741D03*
X1694842Y1462953D03*
X1703503Y1473977D03*
Y1479095D03*
X1694842Y1468071D03*
Y1478308D03*
X1703503Y1489331D03*
Y1494449D03*
X1694842Y1483426D03*
Y1493662D03*
Y1498780D03*
X1703503Y1504685D03*
Y1509804D03*
X1694842Y1509016D03*
Y1514134D03*
X1703503Y1560985D03*
Y1566103D03*
Y1576339D03*
X1694842Y1565315D03*
Y1570434D03*
X1703503Y1581457D03*
Y1591693D03*
X1694842Y1580670D03*
Y1585788D03*
Y1596024D03*
X1703503Y1596811D03*
Y1607048D03*
Y1612166D03*
X1694842Y1601142D03*
Y1611378D03*
Y1616496D03*
X1712165Y1462953D03*
Y1468071D03*
Y1478308D03*
Y1483426D03*
Y1493662D03*
Y1498780D03*
Y1509016D03*
Y1514134D03*
Y1565315D03*
Y1570434D03*
Y1580670D03*
Y1585788D03*
Y1596024D03*
Y1601142D03*
Y1611378D03*
Y1616496D03*
G54D37*
X173829Y455492D03*
Y583957D03*
X202844Y455492D03*
Y583957D03*
X630915Y455492D03*
Y583957D03*
X659930Y455492D03*
Y583957D03*
X1088002Y455492D03*
Y583957D03*
X1117017Y455492D03*
Y583957D03*
X1545089Y455492D03*
Y583957D03*
X1574104Y455492D03*
Y583957D03*
G54D61*
X1795453Y812874D03*
Y834922D03*
G54D48*
X849441Y1367717D03*
G54D50*
X895384Y228740D03*
Y276772D03*
X923336Y226772D03*
Y278740D03*
G54D55*
X1030635Y764546D03*
G54D62*
X1803917Y823898D03*
G54D59*
X1747253Y1715189D03*
Y1744208D03*
X1747246Y1773377D03*
G54D60*
X1747253Y1802909D03*
G54D63*
X1817323Y1567323D03*
G54D13*
X19685Y-83298D03*
Y1801195D03*
X1821260Y-83298D03*
Y1801195D03*
G54D29*
X116731Y1066535D03*
Y1263386D03*
X352952Y1066535D03*
Y1263386D03*
X573818Y1066535D03*
Y1263386D03*
X810038Y1066535D03*
Y1263386D03*
X1030905Y1066535D03*
Y1263386D03*
X1267125Y1066535D03*
Y1263386D03*
X1487991Y1066535D03*
Y1263386D03*
X1724212Y1066535D03*
Y1263386D03*
G54D17*
X26789Y1373669D03*
X184851Y334492D03*
X235433Y1580079D03*
Y1626339D03*
X581890Y1580079D03*
Y1626339D03*
X1259055Y1580079D03*
Y1626339D03*
X1605512Y1580079D03*
Y1626339D03*
X1796847Y1517889D03*
X1809883Y120792D03*
G54D47*
X770472Y1490945D03*
X820079Y388583D03*
X1020866D03*
X1070472Y1490945D03*
G54D31*
X109882Y1453504D03*
Y1468859D03*
Y1484213D03*
Y1499567D03*
Y1514922D03*
Y1555867D03*
Y1571221D03*
Y1586575D03*
Y1601930D03*
Y1617284D03*
X127205Y1453504D03*
X118543Y1457835D03*
X127205Y1468859D03*
X118543Y1473189D03*
X127205Y1484213D03*
X118543Y1488544D03*
X127205Y1499567D03*
Y1514922D03*
X118543Y1503898D03*
Y1519252D03*
X127205Y1555867D03*
X118543Y1560197D03*
X127205Y1571221D03*
X118543Y1575552D03*
X127205Y1586575D03*
X118543Y1590906D03*
X127205Y1601930D03*
X118543Y1606260D03*
X127205Y1617284D03*
X118543Y1621615D03*
X144528Y1453504D03*
X135866Y1457835D03*
X144528Y1468859D03*
X135866Y1473189D03*
X144528Y1484213D03*
X135866Y1488544D03*
X144528Y1499567D03*
Y1514922D03*
X135866Y1503898D03*
Y1519252D03*
X144528Y1555867D03*
X135866Y1560197D03*
X144528Y1571221D03*
X135866Y1575552D03*
X144528Y1586575D03*
X135866Y1590906D03*
X144528Y1601930D03*
X135866Y1606260D03*
X144528Y1617284D03*
X135866Y1621615D03*
X161850Y1453504D03*
X153189Y1457835D03*
X161850Y1468859D03*
X153189Y1473189D03*
X161850Y1484213D03*
X153189Y1488544D03*
X161850Y1499567D03*
Y1514922D03*
X153189Y1503898D03*
Y1519252D03*
X161850Y1555867D03*
X153189Y1560197D03*
X161850Y1571221D03*
X153189Y1575552D03*
X161850Y1586575D03*
X153189Y1590906D03*
X161850Y1601930D03*
X153189Y1606260D03*
X161850Y1617284D03*
X153189Y1621615D03*
X179173Y1453504D03*
X170512Y1457835D03*
X179173Y1468859D03*
X170512Y1473189D03*
X179173Y1484213D03*
X170512Y1488544D03*
X179173Y1499567D03*
Y1514922D03*
X170512Y1503898D03*
Y1519252D03*
X179173Y1555867D03*
X170512Y1560197D03*
X179173Y1571221D03*
X170512Y1575552D03*
X179173Y1586575D03*
X170512Y1590906D03*
X179173Y1601930D03*
X170512Y1606260D03*
X179173Y1617284D03*
X170512Y1621615D03*
X187835Y1457835D03*
Y1473189D03*
Y1488544D03*
Y1503898D03*
Y1519252D03*
Y1560197D03*
Y1575552D03*
Y1590906D03*
Y1606260D03*
Y1621615D03*
X283110Y1453504D03*
X291771Y1457835D03*
X283110Y1468859D03*
X291771Y1473189D03*
X283110Y1484213D03*
X291771Y1488544D03*
X283110Y1499567D03*
X291771Y1503898D03*
X283110Y1514922D03*
X291771Y1519252D03*
X283110Y1555867D03*
X291771Y1560197D03*
X283110Y1571221D03*
X291771Y1575552D03*
X283110Y1586575D03*
X291771Y1590906D03*
X283110Y1601930D03*
X291771Y1606260D03*
X283110Y1617284D03*
X291771Y1621615D03*
X300433Y1453504D03*
X309094Y1457835D03*
X300433Y1468859D03*
X309094Y1473189D03*
X300433Y1484213D03*
X309094Y1488544D03*
X300433Y1499567D03*
X309094Y1503898D03*
X300433Y1514922D03*
X309094Y1519252D03*
X300433Y1555867D03*
X309094Y1560197D03*
X300433Y1571221D03*
X309094Y1575552D03*
X300433Y1586575D03*
X309094Y1590906D03*
X300433Y1601930D03*
X309094Y1606260D03*
X300433Y1617284D03*
X309094Y1621615D03*
X317756Y1453504D03*
X326417Y1457835D03*
X317756Y1468859D03*
X326417Y1473189D03*
X317756Y1484213D03*
X326417Y1488544D03*
X317756Y1499567D03*
X326417Y1503898D03*
X317756Y1514922D03*
X326417Y1519252D03*
X317756Y1555867D03*
X326417Y1560197D03*
X317756Y1571221D03*
X326417Y1575552D03*
X317756Y1586575D03*
X326417Y1590906D03*
X317756Y1601930D03*
X326417Y1606260D03*
X317756Y1617284D03*
X326417Y1621615D03*
X335078Y1453504D03*
X343740Y1457835D03*
X335078Y1468859D03*
X343740Y1473189D03*
X335078Y1484213D03*
X343740Y1488544D03*
X335078Y1499567D03*
X343740Y1503898D03*
X335078Y1514922D03*
X343740Y1519252D03*
X335078Y1555867D03*
X343740Y1560197D03*
X335078Y1571221D03*
X343740Y1575552D03*
X335078Y1586575D03*
X343740Y1590906D03*
X335078Y1601930D03*
X343740Y1606260D03*
X335078Y1617284D03*
X343740Y1621615D03*
X352401Y1453504D03*
X361063Y1457835D03*
X352401Y1468859D03*
X361063Y1473189D03*
X352401Y1484213D03*
X361063Y1488544D03*
X352401Y1499567D03*
X361063Y1503898D03*
X352401Y1514922D03*
X361063Y1519252D03*
X352401Y1555867D03*
X361063Y1560197D03*
X352401Y1571221D03*
X361063Y1575552D03*
X352401Y1586575D03*
X361063Y1590906D03*
X352401Y1601930D03*
X361063Y1606260D03*
X352401Y1617284D03*
X361063Y1621615D03*
X456339Y1453504D03*
Y1468859D03*
Y1484213D03*
Y1499567D03*
Y1514922D03*
Y1555867D03*
Y1571221D03*
Y1586575D03*
Y1601930D03*
Y1617284D03*
X473662Y1453504D03*
X465000Y1457835D03*
X473662Y1468859D03*
X465000Y1473189D03*
X473662Y1484213D03*
X465000Y1488544D03*
X473662Y1499567D03*
Y1514922D03*
X465000Y1503898D03*
Y1519252D03*
X473662Y1555867D03*
X465000Y1560197D03*
X473662Y1571221D03*
X465000Y1575552D03*
X473662Y1586575D03*
X465000Y1590906D03*
X473662Y1601930D03*
X465000Y1606260D03*
X473662Y1617284D03*
X465000Y1621615D03*
X490985Y1453504D03*
X482323Y1457835D03*
X490985Y1468859D03*
X482323Y1473189D03*
X490985Y1484213D03*
X482323Y1488544D03*
X490985Y1499567D03*
Y1514922D03*
X482323Y1503898D03*
Y1519252D03*
X490985Y1555867D03*
X482323Y1560197D03*
X490985Y1571221D03*
X482323Y1575552D03*
X490985Y1586575D03*
X482323Y1590906D03*
X490985Y1601930D03*
X482323Y1606260D03*
X490985Y1617284D03*
X482323Y1621615D03*
X508307Y1453504D03*
X499646Y1457835D03*
X508307Y1468859D03*
X499646Y1473189D03*
X508307Y1484213D03*
X499646Y1488544D03*
X508307Y1499567D03*
Y1514922D03*
X499646Y1503898D03*
Y1519252D03*
X508307Y1555867D03*
X499646Y1560197D03*
X508307Y1571221D03*
X499646Y1575552D03*
X508307Y1586575D03*
X499646Y1590906D03*
X508307Y1601930D03*
X499646Y1606260D03*
X508307Y1617284D03*
X499646Y1621615D03*
X516969Y1457835D03*
Y1473189D03*
Y1488544D03*
Y1503898D03*
Y1519252D03*
Y1560197D03*
Y1575552D03*
Y1590906D03*
Y1606260D03*
Y1621615D03*
X525630Y1453504D03*
X534292Y1457835D03*
X525630Y1468859D03*
X534292Y1473189D03*
X525630Y1484213D03*
X534292Y1488544D03*
X525630Y1499567D03*
X534292Y1503898D03*
X525630Y1514922D03*
X534292Y1519252D03*
X525630Y1555867D03*
X534292Y1560197D03*
X525630Y1571221D03*
X534292Y1575552D03*
X525630Y1586575D03*
X534292Y1590906D03*
X525630Y1601930D03*
X534292Y1606260D03*
X525630Y1617284D03*
X534292Y1621615D03*
X629567Y1453504D03*
X638228Y1457835D03*
X629567Y1468859D03*
X638228Y1473189D03*
X629567Y1484213D03*
X638228Y1488544D03*
X629567Y1499567D03*
X638228Y1503898D03*
X629567Y1514922D03*
X638228Y1519252D03*
X629567Y1555867D03*
X638228Y1560197D03*
X629567Y1571221D03*
X638228Y1575552D03*
X629567Y1586575D03*
X638228Y1590906D03*
X629567Y1601930D03*
X638228Y1606260D03*
X629567Y1617284D03*
X638228Y1621615D03*
X646890Y1453504D03*
Y1468859D03*
Y1484213D03*
Y1499567D03*
Y1514922D03*
Y1555867D03*
Y1571221D03*
Y1586575D03*
Y1601930D03*
Y1617284D03*
X664213Y1453504D03*
X655551Y1457835D03*
X664213Y1468859D03*
X655551Y1473189D03*
X664213Y1484213D03*
X655551Y1488544D03*
X664213Y1499567D03*
Y1514922D03*
X655551Y1503898D03*
Y1519252D03*
X664213Y1555867D03*
X655551Y1560197D03*
X664213Y1571221D03*
X655551Y1575552D03*
X664213Y1586575D03*
X655551Y1590906D03*
X664213Y1601930D03*
X655551Y1606260D03*
X664213Y1617284D03*
X655551Y1621615D03*
X681535Y1453504D03*
X672874Y1457835D03*
X681535Y1468859D03*
X672874Y1473189D03*
X681535Y1484213D03*
X672874Y1488544D03*
X681535Y1499567D03*
Y1514922D03*
X672874Y1503898D03*
Y1519252D03*
X681535Y1555867D03*
X672874Y1560197D03*
X681535Y1571221D03*
X672874Y1575552D03*
X681535Y1586575D03*
X672874Y1590906D03*
X681535Y1601930D03*
X672874Y1606260D03*
X681535Y1617284D03*
X672874Y1621615D03*
X698858Y1453504D03*
X690197Y1457835D03*
X698858Y1468859D03*
X690197Y1473189D03*
X698858Y1484213D03*
X690197Y1488544D03*
X698858Y1499567D03*
Y1514922D03*
X690197Y1503898D03*
Y1519252D03*
X698858Y1555867D03*
X690197Y1560197D03*
X698858Y1571221D03*
X690197Y1575552D03*
X698858Y1586575D03*
X690197Y1590906D03*
X698858Y1601930D03*
X690197Y1606260D03*
X698858Y1617284D03*
X690197Y1621615D03*
X707520Y1457835D03*
Y1473189D03*
Y1488544D03*
Y1503898D03*
Y1519252D03*
Y1560197D03*
Y1575552D03*
Y1590906D03*
Y1606260D03*
Y1621615D03*
X1131850Y1453504D03*
X1140511Y1457835D03*
X1131850Y1468859D03*
X1140511Y1473189D03*
X1131850Y1484213D03*
X1140511Y1488544D03*
X1131850Y1499567D03*
X1140511Y1503898D03*
X1131850Y1514922D03*
X1140511Y1519252D03*
X1131850Y1555867D03*
X1140511Y1560197D03*
X1131850Y1571221D03*
X1140511Y1575552D03*
X1131850Y1586575D03*
X1140511Y1590906D03*
X1131850Y1601930D03*
X1140511Y1606260D03*
X1131850Y1617284D03*
X1140511Y1621615D03*
X1149173Y1453504D03*
X1157834Y1457835D03*
X1149173Y1468859D03*
X1157834Y1473189D03*
X1149173Y1484213D03*
X1157834Y1488544D03*
X1149173Y1499567D03*
X1157834Y1503898D03*
X1149173Y1514922D03*
X1157834Y1519252D03*
X1149173Y1555867D03*
X1157834Y1560197D03*
X1149173Y1571221D03*
X1157834Y1575552D03*
X1149173Y1586575D03*
X1157834Y1590906D03*
X1149173Y1601930D03*
X1157834Y1606260D03*
X1149173Y1617284D03*
X1157834Y1621615D03*
X1166496Y1453504D03*
Y1468859D03*
Y1484213D03*
Y1499567D03*
Y1514922D03*
Y1555867D03*
Y1571221D03*
Y1586575D03*
Y1601930D03*
Y1617284D03*
X1183818Y1453504D03*
X1175157Y1457835D03*
X1183818Y1468859D03*
X1175157Y1473189D03*
X1183818Y1484213D03*
X1175157Y1488544D03*
X1183818Y1499567D03*
Y1514922D03*
X1175157Y1503898D03*
Y1519252D03*
X1183818Y1555867D03*
X1175157Y1560197D03*
X1183818Y1571221D03*
X1175157Y1575552D03*
X1183818Y1586575D03*
X1175157Y1590906D03*
X1183818Y1601930D03*
X1175157Y1606260D03*
X1183818Y1617284D03*
X1175157Y1621615D03*
X1201141Y1453504D03*
X1192480Y1457835D03*
X1201141Y1468859D03*
X1192480Y1473189D03*
X1201141Y1484213D03*
X1192480Y1488544D03*
X1201141Y1499567D03*
Y1514922D03*
X1192480Y1503898D03*
Y1519252D03*
X1201141Y1555867D03*
X1192480Y1560197D03*
X1201141Y1571221D03*
X1192480Y1575552D03*
X1201141Y1586575D03*
X1192480Y1590906D03*
X1201141Y1601930D03*
X1192480Y1606260D03*
X1201141Y1617284D03*
X1192480Y1621615D03*
X1209803Y1457835D03*
Y1473189D03*
Y1488544D03*
Y1503898D03*
Y1519252D03*
Y1560197D03*
Y1575552D03*
Y1590906D03*
Y1606260D03*
Y1621615D03*
X1305079Y1453504D03*
X1313740Y1457835D03*
X1305079Y1468859D03*
X1313740Y1473189D03*
X1305079Y1484213D03*
X1313740Y1488544D03*
X1305079Y1499567D03*
X1313740Y1503898D03*
X1305079Y1514922D03*
X1313740Y1519252D03*
X1305079Y1555867D03*
X1313740Y1560197D03*
X1305079Y1571221D03*
X1313740Y1575552D03*
X1305079Y1586575D03*
X1313740Y1590906D03*
X1305079Y1601930D03*
X1313740Y1606260D03*
X1305079Y1617284D03*
X1313740Y1621615D03*
X1322402Y1453504D03*
X1331063Y1457835D03*
X1322402Y1468859D03*
X1331063Y1473189D03*
X1322402Y1484213D03*
X1331063Y1488544D03*
X1322402Y1499567D03*
X1331063Y1503898D03*
X1322402Y1514922D03*
X1331063Y1519252D03*
X1322402Y1555867D03*
X1331063Y1560197D03*
X1322402Y1571221D03*
X1331063Y1575552D03*
X1322402Y1586575D03*
X1331063Y1590906D03*
X1322402Y1601930D03*
X1331063Y1606260D03*
X1322402Y1617284D03*
X1331063Y1621615D03*
X1339725Y1453504D03*
X1348386Y1457835D03*
X1339725Y1468859D03*
X1348386Y1473189D03*
X1339725Y1484213D03*
X1348386Y1488544D03*
X1339725Y1499567D03*
X1348386Y1503898D03*
X1339725Y1514922D03*
X1348386Y1519252D03*
X1339725Y1555867D03*
X1348386Y1560197D03*
X1339725Y1571221D03*
X1348386Y1575552D03*
X1339725Y1586575D03*
X1348386Y1590906D03*
X1339725Y1601930D03*
X1348386Y1606260D03*
X1339725Y1617284D03*
X1348386Y1621615D03*
X1357047Y1453504D03*
X1365709Y1457835D03*
X1357047Y1468859D03*
X1365709Y1473189D03*
X1357047Y1484213D03*
X1365709Y1488544D03*
X1357047Y1499567D03*
X1365709Y1503898D03*
X1357047Y1514922D03*
X1365709Y1519252D03*
X1357047Y1555867D03*
X1365709Y1560197D03*
X1357047Y1571221D03*
X1365709Y1575552D03*
X1357047Y1586575D03*
X1365709Y1590906D03*
X1357047Y1601930D03*
X1365709Y1606260D03*
X1357047Y1617284D03*
X1365709Y1621615D03*
X1374370Y1453504D03*
X1383032Y1457835D03*
X1374370Y1468859D03*
X1383032Y1473189D03*
X1374370Y1484213D03*
X1383032Y1488544D03*
X1374370Y1499567D03*
X1383032Y1503898D03*
X1374370Y1514922D03*
X1383032Y1519252D03*
X1374370Y1555867D03*
X1383032Y1560197D03*
X1374370Y1571221D03*
X1383032Y1575552D03*
X1374370Y1586575D03*
X1383032Y1590906D03*
X1374370Y1601930D03*
X1383032Y1606260D03*
X1374370Y1617284D03*
X1383032Y1621615D03*
X1478307Y1453504D03*
Y1468859D03*
Y1484213D03*
Y1499567D03*
Y1514922D03*
Y1555867D03*
Y1571221D03*
Y1586575D03*
Y1601930D03*
Y1617284D03*
X1495630Y1453504D03*
X1486968Y1457835D03*
X1495630Y1468859D03*
X1486968Y1473189D03*
X1495630Y1484213D03*
X1486968Y1488544D03*
X1495630Y1499567D03*
Y1514922D03*
X1486968Y1503898D03*
Y1519252D03*
X1495630Y1555867D03*
X1486968Y1560197D03*
X1495630Y1571221D03*
X1486968Y1575552D03*
X1495630Y1586575D03*
X1486968Y1590906D03*
X1495630Y1601930D03*
X1486968Y1606260D03*
X1495630Y1617284D03*
X1486968Y1621615D03*
X1512953Y1453504D03*
X1504291Y1457835D03*
X1512953Y1468859D03*
X1504291Y1473189D03*
X1512953Y1484213D03*
X1504291Y1488544D03*
X1512953Y1499567D03*
Y1514922D03*
X1504291Y1503898D03*
Y1519252D03*
X1512953Y1555867D03*
X1504291Y1560197D03*
X1512953Y1571221D03*
X1504291Y1575552D03*
X1512953Y1586575D03*
X1504291Y1590906D03*
X1512953Y1601930D03*
X1504291Y1606260D03*
X1512953Y1617284D03*
X1504291Y1621615D03*
X1530275Y1453504D03*
X1521614Y1457835D03*
X1530275Y1468859D03*
X1521614Y1473189D03*
X1530275Y1484213D03*
X1521614Y1488544D03*
X1530275Y1499567D03*
Y1514922D03*
X1521614Y1503898D03*
Y1519252D03*
X1530275Y1555867D03*
X1521614Y1560197D03*
X1530275Y1571221D03*
X1521614Y1575552D03*
X1530275Y1586575D03*
X1521614Y1590906D03*
X1530275Y1601930D03*
X1521614Y1606260D03*
X1530275Y1617284D03*
X1521614Y1621615D03*
X1547598Y1453504D03*
X1538937Y1457835D03*
X1547598Y1468859D03*
X1538937Y1473189D03*
X1547598Y1484213D03*
X1538937Y1488544D03*
X1547598Y1499567D03*
Y1514922D03*
X1538937Y1503898D03*
Y1519252D03*
X1547598Y1555867D03*
X1538937Y1560197D03*
X1547598Y1571221D03*
X1538937Y1575552D03*
X1547598Y1586575D03*
X1538937Y1590906D03*
X1547598Y1601930D03*
X1538937Y1606260D03*
X1547598Y1617284D03*
X1538937Y1621615D03*
X1556260Y1457835D03*
Y1473189D03*
Y1488544D03*
Y1503898D03*
Y1519252D03*
Y1560197D03*
Y1575552D03*
Y1590906D03*
Y1606260D03*
Y1621615D03*
X1651535Y1453504D03*
X1660196Y1457835D03*
X1651535Y1468859D03*
X1660196Y1473189D03*
X1651535Y1484213D03*
X1660196Y1488544D03*
X1651535Y1499567D03*
X1660196Y1503898D03*
X1651535Y1514922D03*
X1660196Y1519252D03*
X1651535Y1555867D03*
X1660196Y1560197D03*
X1651535Y1571221D03*
X1660196Y1575552D03*
X1651535Y1586575D03*
X1660196Y1590906D03*
X1651535Y1601930D03*
X1660196Y1606260D03*
X1651535Y1617284D03*
X1660196Y1621615D03*
X1668858Y1453504D03*
X1677519Y1457835D03*
X1668858Y1468859D03*
X1677519Y1473189D03*
X1668858Y1484213D03*
X1677519Y1488544D03*
X1668858Y1499567D03*
X1677519Y1503898D03*
X1668858Y1514922D03*
X1677519Y1519252D03*
X1668858Y1555867D03*
X1677519Y1560197D03*
X1668858Y1571221D03*
X1677519Y1575552D03*
X1668858Y1586575D03*
X1677519Y1590906D03*
X1668858Y1601930D03*
X1677519Y1606260D03*
X1668858Y1617284D03*
X1677519Y1621615D03*
X1686181Y1453504D03*
Y1468859D03*
Y1484213D03*
Y1499567D03*
Y1514922D03*
Y1555867D03*
Y1571221D03*
Y1586575D03*
Y1601930D03*
Y1617284D03*
X1703503Y1453504D03*
X1694842Y1457835D03*
X1703503Y1468859D03*
X1694842Y1473189D03*
X1703503Y1484213D03*
X1694842Y1488544D03*
X1703503Y1499567D03*
Y1514922D03*
X1694842Y1503898D03*
Y1519252D03*
X1703503Y1555867D03*
X1694842Y1560197D03*
X1703503Y1571221D03*
X1694842Y1575552D03*
X1703503Y1586575D03*
X1694842Y1590906D03*
X1703503Y1601930D03*
X1694842Y1606260D03*
X1703503Y1617284D03*
X1694842Y1621615D03*
X1720826Y1453504D03*
X1712165Y1457835D03*
X1720826Y1468859D03*
X1712165Y1473189D03*
X1720826Y1484213D03*
X1712165Y1488544D03*
X1720826Y1499567D03*
Y1514922D03*
X1712165Y1503898D03*
Y1519252D03*
X1720826Y1555867D03*
X1712165Y1560197D03*
X1720826Y1571221D03*
X1712165Y1575552D03*
X1720826Y1586575D03*
X1712165Y1590906D03*
X1720826Y1601930D03*
X1712165Y1606260D03*
X1720826Y1617284D03*
X1712165Y1621615D03*
X1729488Y1457835D03*
Y1473189D03*
Y1488544D03*
Y1503898D03*
Y1519252D03*
Y1560197D03*
Y1575552D03*
Y1590906D03*
Y1606260D03*
Y1621615D03*
G54D39*
X235433Y1606142D03*
X581890D03*
X1259055D03*
X1605512D03*
G54D16*
X15139Y198883D03*
Y201683D03*
X18564Y238589D03*
X6690Y1496782D03*
X34520Y213539D03*
X36201Y238714D03*
X21530Y236121D03*
X27966Y238689D03*
X27625Y663094D03*
X25818Y682139D03*
X28818D03*
X32079Y1517641D03*
X65189Y228961D03*
Y231461D03*
Y223661D03*
Y226461D03*
X54733Y231226D03*
Y228726D03*
Y223726D03*
Y226226D03*
X67622Y572842D03*
X64408Y572975D03*
X73110Y101701D03*
X78501Y110445D03*
Y115401D03*
Y129574D03*
Y124618D03*
X73158Y229286D03*
X76851Y222212D03*
Y224712D03*
X73158Y231786D03*
X75777Y585507D03*
X71184D03*
X71730Y579475D03*
X71228Y590145D03*
X75822Y590190D03*
X75684Y605443D03*
X83684D03*
X78129Y656900D03*
X72314Y680207D03*
Y683407D03*
X82714Y674707D03*
X71928Y873683D03*
X88903Y117557D03*
Y122513D03*
Y131731D03*
Y136687D03*
X94390Y293645D03*
Y290845D03*
Y288345D03*
X91890Y293645D03*
Y290845D03*
Y288345D03*
X93456Y649838D03*
X89432Y668293D03*
X92134D03*
X85614Y674707D03*
X87714Y684607D03*
X117501Y198883D03*
Y201683D03*
X111275Y1008262D03*
Y1011762D03*
X130328Y238689D03*
X123892Y236121D03*
X120926Y238589D03*
X136882Y213539D03*
X138563Y238714D03*
X143186Y402291D03*
Y397335D03*
X140786Y416465D03*
Y411509D03*
Y425682D03*
Y430638D03*
Y439855D03*
Y444811D03*
Y468609D03*
Y473565D03*
Y487738D03*
Y482782D03*
Y512743D03*
Y517699D03*
Y531872D03*
Y526916D03*
X157095Y228726D03*
Y231226D03*
X167551Y223661D03*
X157095Y226226D03*
Y223726D03*
X151188Y390223D03*
Y395179D03*
Y404396D03*
Y409352D03*
Y423525D03*
Y418569D03*
Y432743D03*
Y437699D03*
Y489895D03*
Y480677D03*
Y475721D03*
Y494851D03*
Y519855D03*
Y538984D03*
Y534028D03*
Y524811D03*
X175472Y101701D03*
X175520Y229286D03*
X179213Y224712D03*
Y222212D03*
X167551Y231461D03*
Y228961D03*
Y226461D03*
X175520Y231786D03*
X194189Y103621D03*
X196752Y293645D03*
Y290845D03*
Y288345D03*
X194252Y293645D03*
Y290845D03*
Y288345D03*
X203740Y567914D03*
Y565414D03*
Y570414D03*
Y575414D03*
Y572914D03*
X219863Y198883D03*
Y201683D03*
X226254Y236121D03*
X223288Y238589D03*
X239244Y213539D03*
X232690Y238689D03*
X240925Y238714D03*
X259457Y228726D03*
Y231226D03*
Y226226D03*
Y223726D03*
X251802Y824128D03*
X277834Y101701D03*
X269913Y228961D03*
Y226461D03*
Y223661D03*
X277882Y229286D03*
X269913Y231461D03*
X277882Y231786D03*
X286129Y36971D03*
X296551Y103621D03*
X281575Y224712D03*
Y222212D03*
X296614Y293645D03*
Y290845D03*
Y288345D03*
X309106Y37543D03*
X299114Y290845D03*
Y288345D03*
Y293645D03*
X302966Y324139D03*
X310013Y316731D03*
X301158Y380307D03*
X301308Y395346D03*
X301393Y400039D03*
X322225Y198883D03*
Y201683D03*
X325650Y238589D03*
X328616Y236121D03*
X321549Y445315D03*
Y448115D03*
X323489Y471484D03*
Y466528D03*
Y480701D03*
Y485657D03*
Y515617D03*
Y510661D03*
Y529791D03*
Y524835D03*
Y565657D03*
Y560701D03*
Y574874D03*
Y579830D03*
Y589047D03*
Y594003D03*
Y603221D03*
Y608177D03*
X330905Y11806D03*
Y23806D03*
Y31806D03*
X341606Y213539D03*
X335052Y238689D03*
X343287Y238714D03*
X345050Y458334D03*
X333891Y473640D03*
Y487813D03*
Y478596D03*
Y492769D03*
Y522730D03*
Y517774D03*
Y531947D03*
Y536903D03*
Y572769D03*
Y567813D03*
Y586943D03*
Y581987D03*
Y596160D03*
Y601116D03*
Y610333D03*
Y615289D03*
X347450Y447486D03*
X353670Y488618D03*
Y491118D03*
Y493618D03*
Y496118D03*
X372275Y226461D03*
X361819Y231226D03*
Y228726D03*
Y223726D03*
Y226226D03*
X372275Y228961D03*
Y231461D03*
Y223661D03*
X364954Y450091D03*
X367564Y452740D03*
X365332Y490070D03*
Y487570D03*
X361887Y493758D03*
Y496258D03*
X377020Y782535D03*
X368491Y815092D03*
X368273Y928100D03*
X380196Y101701D03*
X380244Y229286D03*
X383937Y222212D03*
Y224712D03*
X380244Y231786D03*
X393837Y466409D03*
X393823Y487382D03*
X398913Y103621D03*
X398976Y293645D03*
X401476D03*
Y288345D03*
Y290845D03*
X398976Y288345D03*
Y290845D03*
X406843Y399161D03*
Y401661D03*
Y396661D03*
X405603Y668060D03*
X408103D03*
X403103D03*
X400603D03*
Y678060D03*
X405603D03*
X408103D03*
X403103D03*
X406967Y878764D03*
X406415Y874840D03*
X399285Y1081599D03*
X398915Y1097278D03*
X396415D03*
X401711Y1419771D03*
X406667D03*
X400911Y1537902D03*
X407048D03*
X400911Y1544424D03*
X407048Y1549936D03*
X400911D03*
X420050Y33425D03*
X418876Y401661D03*
Y396661D03*
Y399161D03*
X411754Y474513D03*
X424731Y508152D03*
Y513452D03*
Y515952D03*
X414275Y508217D03*
Y510717D03*
Y515717D03*
Y513217D03*
X424731Y510952D03*
X410603Y668060D03*
Y678060D03*
X425759Y869921D03*
Y872721D03*
Y875521D03*
Y867121D03*
Y878321D03*
X411214Y892109D03*
X413012Y1537902D03*
Y1544098D03*
X426196Y1534087D03*
X413012Y1549936D03*
X421616Y1549885D03*
X442704Y506427D03*
X427693Y506520D03*
X438353Y508685D03*
X427693Y509020D03*
X432700Y516277D03*
X429210Y784833D03*
X428759Y869921D03*
Y867121D03*
Y872721D03*
Y875521D03*
Y878321D03*
X432332Y892049D03*
Y897649D03*
Y894849D03*
Y900449D03*
X453544Y461961D03*
X451144Y472809D03*
X447836Y711199D03*
X451889Y1301067D03*
X456832Y1299121D03*
X451889Y1306023D03*
X472226Y198883D03*
Y201683D03*
X473658Y467215D03*
X471048Y464566D03*
X469495Y1011303D03*
Y1023303D03*
Y1017303D03*
X491607Y213539D03*
X478617Y236121D03*
X475651Y238589D03*
X485053Y238689D03*
X481495Y1011303D03*
X475495D03*
X481495Y1023303D03*
Y1017303D03*
X475495Y1023303D03*
X484800Y1302000D03*
X493288Y238714D03*
X522276Y223661D03*
Y226461D03*
Y228961D03*
Y231461D03*
X511820Y231226D03*
Y228726D03*
Y223726D03*
Y226226D03*
X521494Y572975D03*
X524475Y952290D03*
X509471Y981608D03*
X517374Y1287222D03*
X514363Y1287370D03*
X520548Y1287181D03*
X530197Y101701D03*
X530245Y229286D03*
X533938Y222212D03*
Y224712D03*
X530245Y231786D03*
X524708Y572842D03*
X532863Y585507D03*
X528270D03*
X528816Y579475D03*
X532908Y590190D03*
X528314Y590145D03*
X532770Y605443D03*
X528868Y873683D03*
X548914Y103621D03*
X551477Y288345D03*
Y290845D03*
X548977Y288345D03*
Y290845D03*
Y293645D03*
X551477D03*
X540770Y605443D03*
X574588Y201683D03*
X568362Y1008262D03*
Y1011762D03*
X574588Y198883D03*
X587415Y238689D03*
X580979Y236121D03*
X578013Y238589D03*
X577249Y965445D03*
X593969Y213539D03*
X595650Y238714D03*
X600272Y397335D03*
Y402291D03*
X597872Y425682D03*
Y416465D03*
Y411509D03*
Y439855D03*
Y430638D03*
Y444811D03*
Y468609D03*
Y473565D03*
Y487738D03*
Y482782D03*
Y517699D03*
Y531872D03*
Y526916D03*
X606142Y965665D03*
X614182Y223726D03*
Y226226D03*
Y231226D03*
Y228726D03*
X608274Y390223D03*
Y395179D03*
Y404396D03*
Y409352D03*
Y418569D03*
Y423525D03*
Y432743D03*
Y437699D03*
Y489895D03*
Y480677D03*
Y475721D03*
Y494851D03*
Y519855D03*
Y538984D03*
Y534028D03*
Y524811D03*
X632559Y101701D03*
X624638Y231461D03*
X636300Y222212D03*
Y224712D03*
X632607Y229286D03*
X624638Y223661D03*
Y226461D03*
Y228961D03*
X632607Y231786D03*
X651276Y103621D03*
X651339Y290845D03*
Y293645D03*
X653839D03*
Y288345D03*
Y290845D03*
X651339Y288345D03*
X660826Y570414D03*
Y567914D03*
Y565414D03*
Y575414D03*
Y572914D03*
X676950Y201683D03*
X680375Y238589D03*
X683341Y236121D03*
X696331Y213539D03*
X698012Y238714D03*
X689777Y238689D03*
X716544Y228726D03*
Y231226D03*
Y226226D03*
Y223726D03*
X704446Y760611D03*
X713425Y786029D03*
X734921Y101701D03*
X727000Y228961D03*
Y226461D03*
Y223661D03*
X734969Y229286D03*
X727000Y231461D03*
X734969Y231786D03*
X721218Y742131D03*
X720271Y782481D03*
X738662Y224712D03*
Y222212D03*
X744069Y746617D03*
X735576Y861780D03*
X753638Y103621D03*
X760407Y324494D03*
X767099Y316731D03*
X767310Y1599164D03*
X756358Y1616917D03*
X779312Y198883D03*
Y201683D03*
X782737Y238589D03*
X780575Y471484D03*
Y466528D03*
Y480701D03*
Y485657D03*
Y510661D03*
Y515617D03*
Y524835D03*
Y529791D03*
Y560701D03*
Y565657D03*
Y579830D03*
Y574874D03*
Y589047D03*
Y594003D03*
Y603221D03*
Y608177D03*
X798693Y213539D03*
X792139Y238689D03*
X785703Y236121D03*
X790977Y473640D03*
Y487813D03*
Y478596D03*
Y492769D03*
Y517774D03*
Y522730D03*
Y531947D03*
Y536903D03*
Y567813D03*
Y572769D03*
Y581987D03*
Y586943D03*
Y601116D03*
Y596160D03*
Y615289D03*
Y610333D03*
X800374Y238714D03*
X804536Y441486D03*
X802136Y452334D03*
X810756Y491118D03*
Y488618D03*
Y483618D03*
Y486118D03*
X815492Y732917D03*
X829362Y231461D03*
Y228961D03*
Y226461D03*
Y223661D03*
X818906Y228726D03*
Y231226D03*
Y226226D03*
Y223726D03*
X829381Y348036D03*
X824650Y446740D03*
X822040Y444091D03*
X826262Y462326D03*
Y459326D03*
X818973Y491258D03*
Y488758D03*
X822418Y485070D03*
Y482570D03*
X823790Y713375D03*
X823843Y732109D03*
X819890Y736924D03*
X828423Y964731D03*
X837283Y101701D03*
X837331Y229286D03*
X841024Y224712D03*
Y222212D03*
X837331Y231786D03*
X839573Y325327D03*
X856000Y103621D03*
X858563Y293645D03*
Y290845D03*
X856063Y293645D03*
Y290845D03*
X858563Y288345D03*
X856063D03*
X854622Y359004D03*
X873885Y340892D03*
X873733Y357844D03*
X871382Y373971D03*
X875907Y486256D03*
X870137Y669461D03*
X875916Y808965D03*
X886026Y346584D03*
X896592Y362369D03*
Y366369D03*
Y370369D03*
X882907Y480350D03*
X892023Y570176D03*
X890959Y579788D03*
X890956Y588325D03*
X894015Y588253D03*
X895933Y618143D03*
X910076Y304843D03*
X905120D03*
X913206Y336489D03*
X910040Y353532D03*
X902169Y413002D03*
Y418002D03*
Y415502D03*
X913853Y561487D03*
X904393Y570176D03*
X908517D03*
X898815D03*
X898232Y588320D03*
X902635Y588305D03*
X906999Y588274D03*
X905313Y709259D03*
X905050Y720268D03*
X913716Y800815D03*
X899916D03*
X911053Y800510D03*
X901428Y1136426D03*
X904897Y1145169D03*
X902397D03*
X929978Y186854D03*
Y184054D03*
X917906Y321670D03*
X922629Y336609D03*
X922198Y342051D03*
X917858Y331453D03*
X927309Y357267D03*
X921389D03*
X915395D03*
Y363212D03*
X927309Y363239D03*
Y369210D03*
X921468D03*
X915395D03*
X927072Y386992D03*
X919072D03*
X923072D03*
X914202Y418002D03*
Y413002D03*
Y415502D03*
X916590Y800636D03*
X921790Y810965D03*
X926044Y1545370D03*
Y1542370D03*
X938125Y230891D03*
X942805Y223860D03*
X936369Y221292D03*
X940158Y245707D03*
X946064Y252998D03*
X941845Y278968D03*
X939606Y310521D03*
X939653Y317474D03*
X940924Y328959D03*
X936608Y326058D03*
X945120Y326441D03*
X930398Y342050D03*
X936453Y345336D03*
X945599Y345383D03*
X940972Y338238D03*
X943663Y355674D03*
X944900Y363700D03*
X938499Y362202D03*
X940600Y370600D03*
X939314Y707847D03*
X931244Y720471D03*
X936026Y730600D03*
X941916Y808965D03*
X949359Y198710D03*
X951040Y223885D03*
X956348Y356371D03*
X952170Y356131D03*
X958823Y362802D03*
X954888Y369513D03*
X948400Y370045D03*
X956035Y1545333D03*
X959035D03*
X953035D03*
X950035D03*
X959035Y1542333D03*
X956035D03*
X953035D03*
X950035D03*
X968906Y223726D03*
Y228726D03*
Y231226D03*
X979362Y223661D03*
X968906Y226226D03*
X973338Y345018D03*
X978581Y572975D03*
X971144Y908972D03*
X965405Y1136426D03*
X987283Y101701D03*
X987331Y229286D03*
X991024Y224712D03*
Y222212D03*
X979362Y231461D03*
Y228961D03*
Y226461D03*
X987331Y231786D03*
X992045Y366559D03*
X984045D03*
X988045D03*
X981795Y572842D03*
X985903Y579475D03*
X985357Y585507D03*
X989950D03*
X985401Y590145D03*
X989995Y590190D03*
X989857Y605443D03*
X983712Y722064D03*
X1006000Y103621D03*
X1008563Y293645D03*
X1006063D03*
Y290845D03*
Y288345D03*
X1008563Y290845D03*
Y288345D03*
X997857Y605443D03*
X1010606Y1547824D03*
X1010659Y1568771D03*
Y1565771D03*
X1010653Y1571669D03*
X1021451Y322879D03*
X1026032Y322906D03*
X1018238Y678647D03*
X1018155Y684132D03*
X1025116Y698332D03*
X1024932Y717856D03*
X1016320Y828481D03*
X1026340Y917761D03*
X1025448Y1008262D03*
Y1011762D03*
X1013606Y1547824D03*
X1016606D03*
X1019606D03*
X1013659Y1568771D03*
X1016659D03*
X1019659D03*
X1013659Y1565771D03*
X1016659D03*
X1019659D03*
X1013653Y1571669D03*
X1016653D03*
X1019653D03*
X1031674Y198883D03*
Y201683D03*
X1038065Y236121D03*
X1035099Y238589D03*
X1030184Y288709D03*
X1038068Y298789D03*
X1033112D03*
X1030753Y732213D03*
X1051055Y213539D03*
X1044501Y238689D03*
X1052736Y238714D03*
X1048695Y280161D03*
X1057359Y402291D03*
Y397335D03*
X1054959Y411509D03*
Y425682D03*
Y416465D03*
Y430638D03*
Y439855D03*
Y444811D03*
Y468609D03*
Y473565D03*
Y487738D03*
Y482782D03*
Y517699D03*
Y512743D03*
Y531872D03*
Y526916D03*
X1071268Y226226D03*
Y223726D03*
Y228726D03*
Y231226D03*
X1065361Y390223D03*
Y395179D03*
Y404396D03*
Y409352D03*
Y423525D03*
Y418569D03*
Y432743D03*
Y437699D03*
Y489895D03*
Y480677D03*
Y475721D03*
Y494851D03*
Y519855D03*
Y524811D03*
Y538984D03*
Y534028D03*
X1089645Y101701D03*
X1081724Y226461D03*
Y223661D03*
X1089693Y229286D03*
X1081724Y231461D03*
Y228961D03*
X1089693Y231786D03*
X1079863Y345660D03*
X1090747Y1617415D03*
X1108362Y103621D03*
X1093386Y224712D03*
Y222212D03*
X1108425Y293645D03*
Y290845D03*
Y288345D03*
X1096264Y1562285D03*
X1093713Y1585583D03*
X1110925Y293645D03*
Y290845D03*
Y288345D03*
X1117913Y565414D03*
Y567914D03*
Y570414D03*
Y572914D03*
Y575414D03*
X1122718Y598857D03*
X1121191Y612555D03*
X1120512Y617332D03*
X1121022Y607750D03*
X1134036Y198883D03*
Y201683D03*
X1137461Y238589D03*
X1140427Y236121D03*
X1138166Y534759D03*
X1153417Y213539D03*
X1146863Y238689D03*
X1155098Y238714D03*
X1149437Y728541D03*
X1152316Y746625D03*
X1173630Y226226D03*
Y223726D03*
Y228726D03*
Y231226D03*
X1161274Y550462D03*
X1170603Y715281D03*
X1163751Y719498D03*
X1168577Y733812D03*
X1169266Y800799D03*
X1184086Y231461D03*
Y228961D03*
Y226461D03*
Y223661D03*
X1176577Y885974D03*
X1188431Y936568D03*
X1192007Y101701D03*
X1192055Y229286D03*
X1195748Y224712D03*
Y222212D03*
X1192055Y231786D03*
X1192990Y914873D03*
X1195118Y936296D03*
X1210724Y103621D03*
X1213287Y293645D03*
Y290845D03*
Y288345D03*
X1210787Y293645D03*
Y290845D03*
Y288345D03*
X1217139Y324139D03*
X1222909Y-83456D03*
Y-78500D03*
Y-68500D03*
Y-73456D03*
X1228265Y-44406D03*
Y-39450D03*
Y-29450D03*
Y-34406D03*
X1236398Y198883D03*
Y201683D03*
X1224186Y316731D03*
X1237662Y466528D03*
Y471484D03*
Y480701D03*
Y485657D03*
Y515617D03*
Y510661D03*
Y524835D03*
Y529791D03*
Y565657D03*
Y560701D03*
Y589047D03*
Y574874D03*
Y579830D03*
Y603221D03*
Y594003D03*
Y608177D03*
X1239823Y238589D03*
X1242789Y236121D03*
X1248064Y473640D03*
Y487813D03*
Y478596D03*
Y492769D03*
Y517774D03*
Y522730D03*
Y531947D03*
Y536903D03*
X1255779Y213539D03*
X1257460Y238714D03*
X1264481Y300223D03*
X1261623Y447486D03*
X1259223Y458334D03*
X1267843Y488618D03*
Y491118D03*
Y493618D03*
X1275992Y223726D03*
Y226226D03*
Y231226D03*
Y228726D03*
X1286448Y223661D03*
Y226461D03*
Y228961D03*
Y231461D03*
X1279127Y450091D03*
X1281737Y452740D03*
X1279505Y487570D03*
Y490070D03*
X1276060Y496258D03*
Y493758D03*
X1294369Y101701D03*
X1294417Y229286D03*
X1298110Y222212D03*
Y224712D03*
X1294417Y231786D03*
X1313086Y103621D03*
X1313149Y288345D03*
Y290845D03*
Y293645D03*
X1315649Y288345D03*
Y290845D03*
Y293645D03*
X1308010Y466409D03*
X1307996Y487382D03*
X1313459Y1081599D03*
X1310589Y1097278D03*
X1313089D03*
X1334223Y33425D03*
X1333049Y399268D03*
Y401768D03*
Y396768D03*
X1321016Y399161D03*
Y401661D03*
Y396661D03*
X1325927Y474513D03*
X1386399Y201683D03*
X1383669Y1011303D03*
Y1017303D03*
Y1023303D03*
X1386399Y198883D03*
X1399226Y238689D03*
X1392790Y236121D03*
X1389824Y238589D03*
X1395669Y1011303D03*
X1389669D03*
X1395669Y1017303D03*
Y1023303D03*
X1389669D03*
X1405780Y213539D03*
X1407461Y238714D03*
X1425993Y231226D03*
Y228726D03*
Y226226D03*
Y223726D03*
X1444370Y101701D03*
X1436449Y228961D03*
X1444418Y229286D03*
X1436449Y226461D03*
Y223661D03*
X1448111Y222212D03*
Y224712D03*
X1436449Y231461D03*
X1444418Y231786D03*
X1438882Y572842D03*
X1447037Y585507D03*
X1442444D03*
X1442990Y579475D03*
X1435668Y572975D03*
X1442488Y590145D03*
X1447082Y590190D03*
X1446944Y605443D03*
X1443041Y873683D03*
X1463087Y103621D03*
X1465650Y293645D03*
Y288345D03*
Y290845D03*
X1463150Y288345D03*
Y290845D03*
Y293645D03*
X1454944Y605443D03*
X1479409Y-83456D03*
Y-78500D03*
Y-68500D03*
Y-73456D03*
X1476822Y40780D03*
X1498621Y15043D03*
Y35043D03*
Y27043D03*
X1488761Y198883D03*
Y201683D03*
X1492186Y238589D03*
X1495152Y236121D03*
X1483813Y368516D03*
X1482535Y1008262D03*
Y1002453D03*
Y1011762D03*
X1514765Y-44536D03*
Y-39580D03*
Y-29580D03*
Y-34536D03*
X1508142Y213539D03*
X1509823Y238714D03*
X1501588Y238689D03*
X1514446Y402291D03*
Y397335D03*
X1512046Y411509D03*
Y425682D03*
Y416465D03*
Y439855D03*
Y430638D03*
Y444811D03*
Y468609D03*
Y473565D03*
Y487738D03*
Y482782D03*
Y517699D03*
Y512743D03*
Y531872D03*
Y526916D03*
X1528355Y228726D03*
Y223726D03*
Y226226D03*
Y231226D03*
X1515779Y351594D03*
X1522448Y390223D03*
Y395179D03*
Y404396D03*
Y409352D03*
Y423525D03*
Y418569D03*
Y437699D03*
Y432743D03*
Y489895D03*
Y480677D03*
Y475721D03*
Y494851D03*
Y519855D03*
Y538984D03*
Y534028D03*
Y524811D03*
X1546732Y101701D03*
X1538811Y226461D03*
Y228961D03*
Y231461D03*
X1546780Y229286D03*
X1538811Y223661D03*
X1546780Y231786D03*
X1550473Y222212D03*
Y224712D03*
X1565449Y103621D03*
X1565512Y288345D03*
X1568012Y293645D03*
Y290845D03*
Y288345D03*
X1565512Y293645D03*
Y290845D03*
X1575000Y565414D03*
Y567914D03*
Y570414D03*
Y572914D03*
Y575414D03*
X1579753Y599100D03*
X1578679Y613047D03*
X1578114Y607563D03*
X1591123Y198883D03*
Y201683D03*
X1594548Y238589D03*
X1610504Y213539D03*
X1597514Y236121D03*
X1612185Y238714D03*
X1603950Y238689D03*
X1641173Y231461D03*
X1630717Y223726D03*
Y226226D03*
Y231226D03*
Y228726D03*
X1641173Y223661D03*
Y226461D03*
Y228961D03*
X1649094Y101701D03*
X1649142Y229286D03*
X1652835Y222212D03*
Y224712D03*
X1649142Y231786D03*
X1667811Y103621D03*
X1670374Y290845D03*
Y288345D03*
X1667874Y290845D03*
Y288345D03*
X1670374Y293645D03*
X1667874D03*
X1674226Y324139D03*
X1693485Y198883D03*
Y201683D03*
X1681273Y316731D03*
X1699876Y236121D03*
X1696910Y238589D03*
X1706312Y238689D03*
X1694749Y466528D03*
Y471484D03*
X1705151Y473640D03*
Y487813D03*
Y478596D03*
X1694749Y480701D03*
Y485657D03*
X1705151Y492769D03*
Y517774D03*
Y522730D03*
X1694749Y510661D03*
Y515617D03*
X1705151Y536903D03*
Y531947D03*
X1694749Y524835D03*
Y529791D03*
X1705151Y572769D03*
Y567813D03*
X1694749Y565657D03*
Y560701D03*
Y579830D03*
X1705151Y586943D03*
Y581987D03*
X1694749Y589047D03*
Y574874D03*
Y603221D03*
X1705151Y601116D03*
Y596160D03*
X1694749Y594003D03*
X1705151Y615289D03*
X1694749Y608177D03*
X1705151Y610333D03*
X1712866Y213539D03*
X1714547Y238714D03*
X1718710Y447486D03*
X1716310Y458334D03*
X1724930Y491118D03*
Y488618D03*
Y493618D03*
Y496118D03*
X1733909Y-83456D03*
Y-78500D03*
Y-68500D03*
Y-73456D03*
X1733079Y223726D03*
Y226226D03*
Y231226D03*
Y228726D03*
X1743535Y223661D03*
X1738824Y452740D03*
X1736214Y450091D03*
X1736592Y487570D03*
Y490070D03*
X1733147Y493758D03*
Y496258D03*
X1751456Y101701D03*
X1743535Y226461D03*
X1755197Y224712D03*
X1743535Y228961D03*
Y231461D03*
X1751504Y229286D03*
X1755197Y222212D03*
X1751504Y231786D03*
X1770173Y103621D03*
X1772736Y293645D03*
X1770236D03*
Y290845D03*
Y288345D03*
X1772736Y290845D03*
Y288345D03*
X1765097Y466409D03*
X1765083Y487382D03*
X1772768Y818696D03*
X1790136Y399161D03*
Y401661D03*
Y396661D03*
X1778103Y399161D03*
Y401661D03*
Y396661D03*
X1783014Y474513D03*
X1778801Y836469D03*
X1786256Y927626D03*
X1784306Y924601D03*
X1786256Y930626D03*
X1799265Y-44666D03*
Y-39710D03*
Y-29710D03*
Y-34666D03*
X1791302Y829031D03*
X1816385Y1136912D03*
X1813885D03*
Y1144912D03*
X1816385D03*
G54D21*
X51043Y60709D03*
Y150197D03*
X153405Y60709D03*
Y150197D03*
X255767Y60709D03*
Y150197D03*
X279360Y368760D03*
Y421555D03*
Y501752D03*
Y550020D03*
Y636752D03*
X358129Y60709D03*
Y150197D03*
X508130Y60709D03*
Y150197D03*
X610492Y60709D03*
Y150197D03*
X712854Y60709D03*
Y150197D03*
X736446Y368760D03*
Y421555D03*
Y501752D03*
Y550020D03*
Y636752D03*
X815216Y60709D03*
Y150197D03*
X965216Y60709D03*
Y150197D03*
X1067578Y60709D03*
Y150197D03*
X1169940Y60709D03*
Y150197D03*
X1193533Y368760D03*
Y421555D03*
Y501752D03*
Y550020D03*
Y636752D03*
X1272302Y60709D03*
Y150197D03*
X1422303Y60709D03*
Y150197D03*
X1524665Y60709D03*
Y150197D03*
X1627027Y60709D03*
Y150197D03*
X1650620Y368760D03*
Y421555D03*
Y501752D03*
Y550020D03*
Y636752D03*
X1729389Y60709D03*
Y150197D03*
G54D49*
X843012Y1592787D03*
Y1602787D03*
Y1612787D03*
Y1622787D03*
X853012Y1592787D03*
Y1602787D03*
Y1612787D03*
Y1622787D03*
X878012Y1592787D03*
Y1602787D03*
Y1612787D03*
Y1622787D03*
X888012Y1592787D03*
Y1602787D03*
Y1612787D03*
Y1622787D03*
X913012Y1592787D03*
Y1602787D03*
Y1612787D03*
Y1622787D03*
X923012Y1592787D03*
Y1602787D03*
Y1612787D03*
Y1622787D03*
X948012Y1592787D03*
Y1602787D03*
Y1612787D03*
Y1622787D03*
X958012Y1592787D03*
Y1602787D03*
Y1612787D03*
Y1622787D03*
X983012Y1592787D03*
X993012D03*
X983012Y1602787D03*
Y1612787D03*
X993012Y1602787D03*
Y1612787D03*
X983012Y1622787D03*
X993012D03*
X1018012Y1592787D03*
X1028012D03*
X1018012Y1602787D03*
Y1612787D03*
X1028012Y1602787D03*
Y1612787D03*
X1018012Y1622787D03*
X1028012D03*
G54D12*
X3035Y1578036D03*
X3017Y1639466D03*
X14751Y62381D03*
X12601Y92110D03*
X9364Y107501D03*
X16728Y107910D03*
X12652Y116894D03*
X13615Y153263D03*
X10966Y155873D03*
Y152873D03*
X12709Y175777D03*
X9745Y245784D03*
X19075Y278429D03*
X7036Y268371D03*
X14252Y1121333D03*
X11552D03*
X16752D03*
X8952D03*
X14152Y1111633D03*
X11452D03*
X8852D03*
X16652D03*
X14252Y1130333D03*
X16752D03*
X14306Y1138705D03*
X16806D03*
X20079Y1429347D03*
X12327Y1519202D03*
X11995Y1535134D03*
X6567Y1554215D03*
X14375Y1553121D03*
X18409Y1554202D03*
X12000Y1644980D03*
X33288Y109410D03*
Y116497D03*
X30788D03*
X25988D03*
X22439Y106495D03*
X30788Y123584D03*
X33288Y123583D03*
X25988Y123584D03*
X33288Y130670D03*
X30788D03*
X25988D03*
X30788Y137757D03*
X25988D03*
X29201Y151651D03*
X26201D03*
X20709Y175777D03*
X28740Y247292D03*
X21449Y253198D03*
X28740Y267292D03*
X21386Y273198D03*
X23479Y295619D03*
X32452Y581222D03*
X29652D03*
X35252D03*
Y591215D03*
X29652D03*
X32452D03*
X34254Y611091D03*
X29451Y633560D03*
X30369Y663048D03*
X27854Y671553D03*
X30414Y671508D03*
X26596Y874520D03*
X26844Y920354D03*
X24132Y958151D03*
X25371Y980696D03*
X34314Y1215403D03*
X22284Y1464612D03*
X32079Y1525641D03*
X35237Y1532096D03*
X35850Y1556096D03*
X32000Y1644980D03*
X46450Y82984D03*
Y77784D03*
Y75184D03*
Y80384D03*
X48364Y92473D03*
X46450Y85584D03*
X37988Y109410D03*
Y102323D03*
Y116496D03*
Y130670D03*
Y123583D03*
X52437Y137756D03*
X37988D03*
X45984Y163264D03*
X37284Y285272D03*
X42690Y451466D03*
X48596Y458466D03*
X39643Y555194D03*
X36843D03*
X39643Y563194D03*
X36843D03*
X39643Y571194D03*
X36843D03*
X49265Y886660D03*
X52922Y900295D03*
X47916Y947622D03*
X50366Y1086981D03*
Y1082388D03*
X38200Y1089721D03*
X44365Y1086404D03*
X38216Y1093757D03*
X49500Y1199066D03*
X51197Y1218206D03*
X39452Y1250932D03*
X48195Y1511279D03*
X48079Y1525641D03*
Y1529641D03*
Y1521641D03*
X52048Y1556062D03*
X52000Y1644980D03*
X56098Y109410D03*
Y116496D03*
X55964Y103037D03*
X56098Y123583D03*
Y130670D03*
X68896Y226141D03*
X58279Y293796D03*
X66293Y285690D03*
X68793D03*
X66293Y288190D03*
X68793D03*
X60779Y293796D03*
X65759Y437508D03*
X61759D03*
X57759D03*
X54936Y449352D03*
X59522Y448874D03*
X68619Y447269D03*
X68497Y450201D03*
X64550Y504699D03*
X62050D03*
X59550D03*
X68236Y519458D03*
X61752Y516979D03*
X64252D03*
X59252D03*
X55318Y629362D03*
X53129Y627948D03*
X55307Y688473D03*
X66342Y880067D03*
X67316Y865869D03*
X64175Y897500D03*
X67461Y912983D03*
X63303Y912835D03*
X57178Y981386D03*
X69263Y1053152D03*
X55049Y1082343D03*
X55004Y1086937D03*
X58981Y1105100D03*
X56381D03*
X61581D03*
X64281D03*
X61681Y1114800D03*
X56481D03*
X59081D03*
X64381D03*
X57218Y1123867D03*
X55397Y1133688D03*
X57897D03*
X58250Y1220896D03*
X65940Y1209382D03*
X58250Y1227796D03*
Y1230296D03*
Y1237196D03*
Y1234696D03*
Y1223396D03*
X57185Y1480808D03*
X57144Y1491047D03*
X56114Y1556061D03*
X68743Y1583498D03*
X73381Y94017D03*
X69381D03*
X71422Y151540D03*
X75072Y191941D03*
X81572Y184619D03*
X74939Y188727D03*
X83552Y206760D03*
X71696Y226141D03*
X76766Y256535D03*
X84766D03*
X71593Y285690D03*
Y288190D03*
X75819Y290755D03*
X79819D03*
X83819D03*
X71826Y480705D03*
X75736Y519458D03*
X73236D03*
X70736D03*
X81740Y636250D03*
X69670Y633205D03*
Y636005D03*
X81740Y633450D03*
X69670Y638805D03*
X81740Y639050D03*
X74414Y681907D03*
X76991Y946134D03*
X84679Y1018368D03*
X70059Y1071656D03*
X69373Y1063389D03*
X70059Y1079656D03*
X80290Y1345691D03*
Y1350683D03*
X75334Y1345691D03*
Y1350683D03*
X80290Y1357603D03*
Y1362595D03*
X75334Y1357603D03*
Y1362595D03*
X80290Y1381801D03*
Y1369889D03*
Y1374881D03*
X75334Y1381801D03*
Y1374881D03*
Y1369889D03*
X80290Y1386793D03*
X75334D03*
X87000Y1597855D03*
X76005Y1580680D03*
X82433Y1580590D03*
X72000Y1644980D03*
X88080Y103603D03*
X87002Y146461D03*
X85904Y152367D03*
X87604Y180572D03*
X92287Y180527D03*
X96010Y192421D03*
X92242Y185121D03*
X87604Y185165D03*
X85796Y279208D03*
X89900Y281307D03*
X90257Y445506D03*
X88875Y840940D03*
X91581Y877859D03*
Y874859D03*
X87853Y899220D03*
X91128Y1006487D03*
X99836Y997860D03*
X95836D03*
X100594Y1035088D03*
X97247Y1030568D03*
X103124Y1165091D03*
X87574Y1345691D03*
Y1350683D03*
X99814D03*
Y1345691D03*
X92530D03*
Y1350683D03*
X87574Y1362595D03*
Y1357603D03*
X99814Y1362595D03*
Y1357603D03*
X92530Y1362595D03*
Y1357603D03*
X87574Y1374881D03*
Y1369795D03*
Y1381801D03*
X99814D03*
Y1374881D03*
Y1369889D03*
X92530Y1374881D03*
Y1369795D03*
Y1381801D03*
X87574Y1399079D03*
Y1393993D03*
Y1386793D03*
X99814Y1399079D03*
Y1394087D03*
Y1386793D03*
X92530Y1393993D03*
Y1399079D03*
Y1386793D03*
X87574Y1410991D03*
Y1405999D03*
X99814Y1410991D03*
Y1405999D03*
X92530Y1410991D03*
Y1405999D03*
X92000Y1644980D03*
X107364Y113394D03*
Y110394D03*
X110013Y110784D03*
X110152Y130898D03*
X117607Y133298D03*
X111754Y134579D03*
X107540Y172665D03*
Y180665D03*
X107572Y200864D03*
Y212864D03*
Y216864D03*
Y221864D03*
X109329Y252371D03*
X112474Y716315D03*
X114397Y727974D03*
X113601Y881266D03*
X107641Y865224D03*
X103836Y997860D03*
X111836D03*
X114770Y1009354D03*
X107836Y997860D03*
X115836D03*
X108933Y1102091D03*
X112433D03*
X103124D03*
X112433Y1114691D03*
X103124D03*
X108933D03*
Y1127291D03*
X112433D03*
X103124D03*
X112433Y1139891D03*
X103124Y1152491D03*
X108933D03*
X112433D03*
X108933Y1165091D03*
X112433D03*
X103184Y1177691D03*
X108933D03*
X112433D03*
X109415Y1202103D03*
X112795Y1223749D03*
X104770Y1350683D03*
Y1345691D03*
X112054D03*
Y1350683D03*
X117010Y1345691D03*
Y1350683D03*
X104770Y1362595D03*
Y1357603D03*
X112054Y1362595D03*
Y1357603D03*
X117010Y1362595D03*
Y1357603D03*
Y1369889D03*
Y1374881D03*
Y1381801D03*
X104770D03*
Y1374881D03*
Y1369889D03*
X112054D03*
Y1374881D03*
Y1381801D03*
X104770Y1399079D03*
Y1394087D03*
Y1386793D03*
X112054Y1399079D03*
Y1394087D03*
Y1386793D03*
X117010Y1394087D03*
Y1399079D03*
Y1386793D03*
X104770Y1410991D03*
Y1405999D03*
X112054Y1410991D03*
Y1405999D03*
X117010Y1410991D03*
Y1405999D03*
X107669Y1456451D03*
Y1465913D03*
X116330Y1465513D03*
X107669Y1461182D03*
X116330Y1460782D03*
X107669Y1481267D03*
X116330Y1480867D03*
X107669Y1476536D03*
X116330Y1476136D03*
Y1470244D03*
X107669Y1471805D03*
X116330Y1491490D03*
Y1485598D03*
X107669Y1487159D03*
Y1496621D03*
X116330Y1496221D03*
X107669Y1491890D03*
X116330Y1506845D03*
Y1500952D03*
X107669Y1502514D03*
X116330Y1511576D03*
X107669Y1511976D03*
Y1507245D03*
X116330Y1516307D03*
X107669Y1563544D03*
X116330Y1563144D03*
X107669Y1558813D03*
Y1568275D03*
X116330Y1567875D03*
X107669Y1578898D03*
X116330Y1578498D03*
Y1572606D03*
X107669Y1574167D03*
Y1583629D03*
X116330Y1583229D03*
X107669Y1594253D03*
X116330Y1593853D03*
Y1587960D03*
X107669Y1589522D03*
Y1609607D03*
X116330Y1609207D03*
X107669Y1598984D03*
X116330Y1598584D03*
Y1603315D03*
X107669Y1604876D03*
X116330Y1613938D03*
Y1618669D03*
X107669Y1614338D03*
X112000Y1644980D03*
X128350Y116497D03*
X133150D03*
X124606Y106495D03*
X125599Y109172D03*
X122599D03*
X133150Y123584D03*
X128350D03*
X133150Y130670D03*
X128350D03*
Y137757D03*
X133150D03*
X126246Y141228D03*
X124340Y146012D03*
X129134Y150847D03*
X131102Y247292D03*
X123811Y253198D03*
X125125Y362403D03*
X118122Y747565D03*
X122887Y884000D03*
X127067Y891495D03*
X124079Y1009354D03*
X119836Y997860D03*
X131836D03*
X127836D03*
X123836D03*
X120579Y1009354D03*
Y1021954D03*
X124079D03*
X133870Y1105091D03*
Y1117691D03*
Y1130291D03*
Y1142891D03*
Y1155491D03*
Y1168091D03*
X121211Y1215195D03*
X126937Y1209607D03*
X124294Y1350683D03*
Y1345691D03*
X129250Y1350683D03*
Y1345691D03*
X124294Y1362595D03*
Y1357603D03*
X129250D03*
Y1362595D03*
X124294Y1374881D03*
Y1369889D03*
Y1381801D03*
X129250Y1374881D03*
Y1369889D03*
Y1381801D03*
X124294Y1394087D03*
Y1399079D03*
Y1386793D03*
X129250Y1394087D03*
Y1399079D03*
Y1386793D03*
X124294Y1405999D03*
Y1410991D03*
X129250Y1405999D03*
Y1410991D03*
X124992Y1465913D03*
Y1456451D03*
Y1461182D03*
X133653Y1465513D03*
Y1460782D03*
X124992Y1471805D03*
Y1476536D03*
Y1481267D03*
X133653Y1476136D03*
Y1470244D03*
Y1480867D03*
Y1496221D03*
X124992Y1487159D03*
Y1491890D03*
Y1496621D03*
X133653Y1491490D03*
Y1485598D03*
Y1506845D03*
Y1500952D03*
Y1511576D03*
X124992Y1511976D03*
Y1507245D03*
Y1502514D03*
X133653Y1516307D03*
X124992Y1558813D03*
Y1563544D03*
X133653Y1563144D03*
Y1567875D03*
X124992Y1574167D03*
Y1578898D03*
X133653Y1578498D03*
Y1572606D03*
X124992Y1568275D03*
Y1589522D03*
Y1594253D03*
X133653Y1593853D03*
Y1587960D03*
X124992Y1583629D03*
X133653Y1583229D03*
X124992Y1609607D03*
Y1604876D03*
Y1598984D03*
X133653Y1609207D03*
Y1598584D03*
Y1603315D03*
X124992Y1614338D03*
X133653Y1613938D03*
Y1618669D03*
X132000Y1644980D03*
X148812Y80384D03*
Y82984D03*
Y75184D03*
Y77784D03*
Y85584D03*
X135650Y109410D03*
X140350Y116496D03*
Y109410D03*
Y102323D03*
X135650Y116497D03*
Y123583D03*
Y130670D03*
X140350D03*
Y123583D03*
Y137756D03*
X136604Y450750D03*
X140703Y536382D03*
X145670Y597580D03*
X147893Y599588D03*
X147155Y589556D03*
X147094Y592354D03*
X145609Y594668D03*
X147896Y596095D03*
X147925Y615600D03*
X147893Y607588D03*
X139836Y997860D03*
X147836D03*
X143836D03*
X135836D03*
X145516Y1024954D03*
Y1012354D03*
X148534Y1046476D03*
X134457Y1180654D03*
X141490Y1345691D03*
Y1350683D03*
X136534D03*
Y1345691D03*
X148774Y1350683D03*
Y1345691D03*
X141490Y1357603D03*
Y1362595D03*
X136534D03*
Y1357603D03*
X148774D03*
Y1362595D03*
X141490Y1369889D03*
Y1374881D03*
Y1381801D03*
X136534Y1369889D03*
Y1381801D03*
Y1374881D03*
X148774Y1369889D03*
Y1381801D03*
Y1374881D03*
X141490Y1386793D03*
Y1394087D03*
Y1399079D03*
X136534D03*
Y1394087D03*
Y1386793D03*
X148774Y1394087D03*
Y1399079D03*
Y1386793D03*
X141490Y1405999D03*
Y1410991D03*
X136534D03*
Y1405999D03*
X148774D03*
Y1410991D03*
X142315Y1456451D03*
Y1461182D03*
Y1465913D03*
Y1471805D03*
Y1476536D03*
Y1481267D03*
Y1487159D03*
Y1491890D03*
Y1496621D03*
Y1507245D03*
Y1502514D03*
Y1511976D03*
Y1558813D03*
Y1563544D03*
Y1574167D03*
Y1578898D03*
Y1568275D03*
Y1589522D03*
Y1594253D03*
Y1583629D03*
Y1609607D03*
Y1604876D03*
Y1598984D03*
Y1614338D03*
X151366Y92849D03*
X158460Y116496D03*
X158326Y103037D03*
X158460Y109410D03*
Y130670D03*
Y123583D03*
X155051Y137756D03*
X163141Y293796D03*
X160641D03*
X166528Y312392D03*
X157375Y555234D03*
X157090Y562003D03*
X152386Y634946D03*
X151836Y997860D03*
X159836D03*
X164028Y1041468D03*
X155513Y1065148D03*
X161014Y1345691D03*
Y1350683D03*
X153730Y1345691D03*
Y1350683D03*
X165970Y1345691D03*
Y1350683D03*
X161014Y1362595D03*
Y1357603D03*
X153730Y1362595D03*
Y1357603D03*
X165970Y1362595D03*
Y1357603D03*
X161014Y1381801D03*
Y1369889D03*
Y1374881D03*
X153730Y1369889D03*
Y1381801D03*
Y1374881D03*
X165970D03*
Y1381801D03*
Y1369889D03*
X161014Y1394087D03*
Y1386793D03*
X153730Y1394087D03*
Y1386793D03*
X165970Y1394087D03*
Y1386793D03*
X161014Y1399079D03*
X153730D03*
X165970D03*
X161014Y1410991D03*
Y1405999D03*
X153730D03*
Y1410991D03*
X165970D03*
Y1405999D03*
X159637Y1461182D03*
X150976Y1465513D03*
Y1460782D03*
X159637Y1465913D03*
Y1456451D03*
X150976Y1476136D03*
Y1470244D03*
Y1480867D03*
X159637Y1471805D03*
Y1476536D03*
Y1481267D03*
Y1496621D03*
X150976Y1491490D03*
Y1485598D03*
Y1496221D03*
X159637Y1487159D03*
Y1491890D03*
X150976Y1500952D03*
Y1511576D03*
X159637Y1507245D03*
Y1502514D03*
Y1511976D03*
X150976Y1506845D03*
Y1516307D03*
X159637Y1558813D03*
Y1563544D03*
X150976Y1563144D03*
X159637Y1578898D03*
X150976Y1567875D03*
Y1578498D03*
Y1572606D03*
X159637Y1568275D03*
Y1574167D03*
X150976Y1583229D03*
Y1593853D03*
Y1587960D03*
X159637Y1583629D03*
Y1589522D03*
Y1594253D03*
X150976Y1609207D03*
Y1598584D03*
Y1603315D03*
X159637Y1609607D03*
Y1604876D03*
Y1598984D03*
X150976Y1613938D03*
Y1618669D03*
X159637Y1614338D03*
X152000Y1644980D03*
X179743Y94017D03*
X175743D03*
X171743D03*
X175871Y110445D03*
X180863Y115401D03*
Y110445D03*
X175871Y115401D03*
X180863Y129574D03*
Y124618D03*
X175871Y129574D03*
Y124618D03*
X173784Y151540D03*
X177434Y191941D03*
X177301Y188727D03*
X171258Y226141D03*
X174058D03*
X179128Y256535D03*
X173955Y285690D03*
Y288190D03*
X171155Y285690D03*
X168655Y288190D03*
X171155D03*
X168655Y285690D03*
X182181Y290755D03*
X178181D03*
X177369Y389154D03*
Y396240D03*
Y403327D03*
Y410413D03*
Y417500D03*
Y424587D03*
Y431673D03*
Y438760D03*
Y445847D03*
Y467539D03*
Y474626D03*
Y488799D03*
Y481713D03*
Y495886D03*
Y511673D03*
Y518760D03*
Y525847D03*
Y532933D03*
Y540020D03*
Y547106D03*
X176650Y602197D03*
X177114Y595108D03*
X173254Y1345691D03*
Y1350683D03*
X178210Y1345691D03*
Y1350683D03*
X173254Y1362595D03*
Y1357603D03*
X178210D03*
Y1362595D03*
X173254Y1374881D03*
Y1369889D03*
Y1381801D03*
X178210Y1374881D03*
Y1369889D03*
Y1381801D03*
X173254Y1394087D03*
Y1386793D03*
X178210Y1394087D03*
Y1386793D03*
X173254Y1399079D03*
X178210D03*
X173254Y1405999D03*
Y1410991D03*
X178210Y1405999D03*
Y1410991D03*
X168299Y1465513D03*
Y1460782D03*
X176960Y1465914D03*
Y1456452D03*
Y1461183D03*
X168299Y1476136D03*
Y1470244D03*
Y1480867D03*
X176960Y1476537D03*
Y1471806D03*
Y1481268D03*
X168299Y1491490D03*
Y1485598D03*
Y1496221D03*
X176960Y1491891D03*
Y1487160D03*
Y1496622D03*
Y1507246D03*
Y1502515D03*
X168299Y1506845D03*
Y1500952D03*
Y1511576D03*
X176960Y1511977D03*
X168299Y1516307D03*
Y1563144D03*
X176960Y1563544D03*
Y1558813D03*
Y1568275D03*
X168299Y1578498D03*
Y1572606D03*
Y1567875D03*
Y1583229D03*
X176960Y1583629D03*
X168299Y1593853D03*
Y1587960D03*
X176960Y1594253D03*
Y1589522D03*
X168299Y1609207D03*
Y1598584D03*
Y1603315D03*
X176960Y1609607D03*
Y1598984D03*
Y1604876D03*
X168299Y1613938D03*
Y1618669D03*
X176960Y1614338D03*
X172000Y1644980D03*
X188820Y80140D03*
Y84140D03*
Y76140D03*
X183752Y94017D03*
X186273Y117557D03*
X191265D03*
X186273Y131731D03*
Y122513D03*
X191265D03*
Y131731D03*
X189364Y146461D03*
X186273Y136687D03*
X191265D03*
X188266Y152367D03*
X194649Y180527D03*
X189966Y180572D03*
X198372Y192421D03*
X189966Y185165D03*
X194604Y185121D03*
X183934Y184619D03*
X185914Y206760D03*
X187128Y256535D03*
X188158Y279208D03*
X192262Y281307D03*
X186181Y290755D03*
X191988Y389154D03*
X190518Y396240D03*
X194603Y422864D03*
X195295Y414823D03*
X194673Y429832D03*
X194278Y436447D03*
X196313Y447953D03*
X195480Y467539D03*
X194222Y472772D03*
X194956Y487711D03*
X195069Y479104D03*
X195480Y495886D03*
X190829Y516841D03*
X194080Y510565D03*
X185654Y552872D03*
X185776Y550123D03*
X185099Y562443D03*
X186867Y560675D03*
X187408Y572334D03*
X185640Y574102D03*
X193723Y656942D03*
X185494Y1345597D03*
Y1350683D03*
X190450Y1345597D03*
Y1350683D03*
X197734Y1345691D03*
Y1350683D03*
X185494Y1362595D03*
Y1357603D03*
X197734Y1362595D03*
Y1357603D03*
X190450Y1362595D03*
Y1357603D03*
X185494Y1374881D03*
Y1381801D03*
Y1369889D03*
X197734D03*
Y1381801D03*
Y1374881D03*
X190450Y1369889D03*
Y1374881D03*
Y1381801D03*
X185494Y1393993D03*
Y1386793D03*
X190450Y1393993D03*
Y1386793D03*
X197734Y1394087D03*
Y1386793D03*
X185494Y1399079D03*
X190450D03*
X197734D03*
X185494Y1410991D03*
Y1405999D03*
X190450Y1410991D03*
Y1405999D03*
X197734D03*
Y1410991D03*
X185622Y1465513D03*
Y1460782D03*
Y1480868D03*
Y1476137D03*
Y1470244D03*
Y1485599D03*
X192000Y1644980D03*
X211262Y60922D03*
X206398Y55513D03*
X208463Y96472D03*
X202195Y117261D03*
X209726Y113394D03*
Y110394D03*
X212375Y110784D03*
X211969Y133298D03*
X214116Y134579D03*
X209902Y172665D03*
Y180665D03*
X209934Y200864D03*
Y212864D03*
Y216864D03*
Y221864D03*
X211691Y252371D03*
X215380Y389153D03*
X210580D03*
X215380Y396240D03*
X208080Y403327D03*
X215380Y403326D03*
X210580D03*
X208080Y410413D03*
X210580D03*
X215380D03*
X208080Y396240D03*
X210580D03*
X208080Y417500D03*
X215380Y417499D03*
X210580D03*
X208080Y424586D03*
X210580D03*
X215380D03*
X208080Y431673D03*
Y438760D03*
X210580D03*
X215380D03*
Y431673D03*
X210580D03*
X208080Y445847D03*
X215380Y467539D03*
X210580D03*
X208080Y474626D03*
X210580D03*
X215380D03*
Y488799D03*
X208080D03*
X210580D03*
Y481712D03*
X208080D03*
X215380D03*
X208080Y495886D03*
X215380Y518760D03*
X210580D03*
X208080D03*
X210580Y511673D03*
X215380D03*
X210580Y532933D03*
X208080D03*
Y540020D03*
Y525846D03*
X210580D03*
X215380D03*
Y532933D03*
X212460Y560500D03*
X209429Y625300D03*
X202690Y1345597D03*
Y1350683D03*
Y1362595D03*
Y1357603D03*
Y1369889D03*
Y1381801D03*
Y1374881D03*
Y1394087D03*
Y1386793D03*
Y1399079D03*
Y1405999D03*
Y1410991D03*
X211473Y1446675D03*
X213296Y1438215D03*
X211473Y1451631D03*
Y1462631D03*
Y1457675D03*
X224961Y109172D03*
X226968Y106495D03*
X230712Y116497D03*
X227961Y109172D03*
X230712Y123584D03*
Y130670D03*
X219969Y133298D03*
X228608Y141228D03*
X230712Y137757D03*
X226702Y146012D03*
X231496Y150847D03*
X226173Y253198D03*
X228760Y316122D03*
X223925Y543925D03*
X224500Y555000D03*
X222646Y607542D03*
X217945Y1423924D03*
X217799Y1433684D03*
X216465Y1446675D03*
X222253Y1438483D03*
X216465Y1451631D03*
Y1462631D03*
Y1457675D03*
X229260Y1469587D03*
X218171Y1474460D03*
X224176Y1492816D03*
X223235Y1506770D03*
X222908Y1502028D03*
X226957Y1510442D03*
X216342Y1515642D03*
X217519Y1537172D03*
X242712Y116496D03*
Y109410D03*
Y102323D03*
X238012Y116497D03*
X235512D03*
X238012Y109410D03*
Y123583D03*
Y130670D03*
X235512D03*
X242712D03*
Y123583D03*
X235512Y123584D03*
Y137757D03*
X242712Y137756D03*
X233464Y247292D03*
X236349Y339428D03*
X247333Y599506D03*
X241967Y616063D03*
X243078Y636486D03*
X240249Y628328D03*
X241084Y638243D03*
X246583Y665140D03*
X241850Y678462D03*
X247600Y848500D03*
X240845Y1345691D03*
Y1350683D03*
X245801Y1345691D03*
Y1350683D03*
X240845Y1357603D03*
Y1362595D03*
X245801Y1357603D03*
Y1362595D03*
X240845Y1381801D03*
Y1374881D03*
Y1369889D03*
X245801Y1381801D03*
Y1374881D03*
Y1369889D03*
X240845Y1386793D03*
X245801D03*
X232675Y1466801D03*
X240466Y1503857D03*
X243268Y1501903D03*
X237700Y1531600D03*
X251174Y77784D03*
Y80384D03*
Y82984D03*
Y75184D03*
Y85584D03*
X253728Y92849D03*
X260688Y103037D03*
X260822Y116496D03*
Y109410D03*
Y130670D03*
Y123583D03*
X257413Y137756D03*
X263003Y293796D03*
X257226Y312081D03*
X265011Y403307D03*
X255000Y427017D03*
X254692Y431029D03*
X253758Y435029D03*
X254678Y449873D03*
X261605Y465492D03*
Y472579D03*
X259105D03*
X254305D03*
X261605Y486752D03*
X254305D03*
X259105Y479666D03*
X261605D03*
X254305D03*
X259105Y486752D03*
X254305Y493839D03*
X259105D03*
X261605Y516713D03*
X259105D03*
Y523800D03*
X261605D03*
X254305D03*
Y516713D03*
X261605Y509626D03*
Y530886D03*
X259105D03*
Y537973D03*
X254305Y530886D03*
Y537973D03*
Y566752D03*
X261605Y559665D03*
Y566752D03*
X259105D03*
X261605Y588012D03*
X259105Y588013D03*
X254305Y573839D03*
X261605D03*
X259105D03*
X261605Y580926D03*
X259105D03*
X254305D03*
Y588013D03*
X259105Y602186D03*
X254305D03*
Y595099D03*
X259105D03*
X261605D03*
Y602185D03*
X254305Y609272D03*
X259105D03*
X261605D03*
X259105Y616359D03*
X254305D03*
X248984Y638125D03*
X258867Y680499D03*
X258041Y1350683D03*
Y1345691D03*
X253085Y1350683D03*
Y1345691D03*
X258041Y1362595D03*
X253085D03*
X258041Y1357603D03*
X253085D03*
X258041Y1381801D03*
Y1369795D03*
Y1374881D03*
X253085Y1381801D03*
Y1369795D03*
Y1374881D03*
Y1393993D03*
Y1399079D03*
X258041Y1386793D03*
Y1399079D03*
Y1393993D03*
X253085Y1386793D03*
X258041Y1405999D03*
Y1410991D03*
X253085Y1405999D03*
Y1410991D03*
X248042Y1532900D03*
X274105Y94017D03*
X278105D03*
X278233Y115401D03*
Y110445D03*
Y129574D03*
Y124618D03*
X276146Y151540D03*
X279796Y191941D03*
X279663Y188727D03*
X276420Y226141D03*
X273620D03*
X276317Y288190D03*
X273517Y285690D03*
X271017Y288190D03*
X273517D03*
X271017Y285690D03*
X265503Y293796D03*
X276317Y285690D03*
X274425Y390500D03*
X265011Y410394D03*
X266405Y451319D03*
Y458406D03*
Y465492D03*
X266229Y462264D03*
X266405Y472579D03*
Y479665D03*
Y486752D03*
Y493839D03*
Y523799D03*
Y516713D03*
Y509626D03*
Y530886D03*
Y537973D03*
Y566752D03*
Y559665D03*
Y580926D03*
Y588012D03*
Y573839D03*
Y602185D03*
Y595099D03*
Y609272D03*
Y616358D03*
X269700Y884600D03*
X269900Y914200D03*
X270100Y946500D03*
X277565Y1350683D03*
Y1345691D03*
X265325D03*
Y1350683D03*
X270281Y1345691D03*
Y1350683D03*
X277565Y1362595D03*
X265325D03*
X270281D03*
X277565Y1357603D03*
X265325D03*
X270281D03*
X277565Y1381801D03*
Y1374881D03*
Y1369889D03*
X265325D03*
Y1374881D03*
Y1381801D03*
X270281Y1369889D03*
Y1374881D03*
Y1381801D03*
X277565Y1386793D03*
Y1394087D03*
Y1399079D03*
X265325Y1394087D03*
Y1399079D03*
Y1386793D03*
X270281Y1399079D03*
Y1394087D03*
Y1386793D03*
X265325Y1405999D03*
Y1410991D03*
X270281Y1405999D03*
Y1410991D03*
X277565Y1405999D03*
Y1410991D03*
X272000Y1644980D03*
X291182Y84140D03*
Y80140D03*
Y76140D03*
X282105Y94017D03*
X286114D03*
X288635Y117557D03*
X283225Y115401D03*
Y110445D03*
X293627Y117557D03*
X288635Y131731D03*
Y122513D03*
X283225Y129574D03*
Y124618D03*
X293627Y122513D03*
Y131731D03*
X291726Y146461D03*
X293627Y136687D03*
X288635D03*
X290628Y152367D03*
X292328Y180572D03*
Y185165D03*
X286296Y184619D03*
X288276Y206760D03*
X281490Y256535D03*
X289490D03*
X290520Y279208D03*
X294624Y281307D03*
X284543Y290755D03*
X280543D03*
X288543D03*
X284075Y381500D03*
X284482Y460250D03*
X284516Y465492D03*
X282247Y470136D03*
X284516Y472579D03*
Y479665D03*
Y486752D03*
Y493839D03*
Y516713D03*
Y509626D03*
X283377Y532756D03*
X283456Y525483D03*
X280976Y537973D03*
X284516Y559665D03*
Y566752D03*
X284366Y579978D03*
X284516Y573839D03*
X284580Y608117D03*
X282521Y1345691D03*
X289805Y1350683D03*
Y1345691D03*
X294761Y1350683D03*
Y1345691D03*
X282521Y1350683D03*
X289805Y1362595D03*
X294761D03*
X282521D03*
X289805Y1357603D03*
X294761D03*
X282521D03*
X289805Y1374881D03*
Y1369889D03*
Y1381801D03*
X294761Y1374881D03*
Y1369889D03*
Y1381801D03*
X282521D03*
Y1374881D03*
Y1369889D03*
X289805Y1394087D03*
Y1399079D03*
Y1386793D03*
X294761Y1394087D03*
Y1399079D03*
Y1386793D03*
X282521D03*
Y1399079D03*
Y1394087D03*
X289805Y1405999D03*
Y1410991D03*
X294761Y1405999D03*
Y1410991D03*
X282521Y1405999D03*
Y1410991D03*
X280897Y1465913D03*
X289558Y1465513D03*
X280897Y1461182D03*
X289558Y1460782D03*
X280897Y1456451D03*
X289558Y1480867D03*
X280897Y1476536D03*
X289558Y1476136D03*
Y1470244D03*
X280897Y1471805D03*
Y1481267D03*
Y1491890D03*
X289558Y1491490D03*
Y1485598D03*
X280897Y1487159D03*
Y1496621D03*
X289558Y1496221D03*
X280897Y1507245D03*
X289558Y1506845D03*
Y1500952D03*
X280897Y1502514D03*
X289558Y1511576D03*
X280897Y1511976D03*
X289558Y1516307D03*
X280897Y1563544D03*
X289558Y1563144D03*
X280897Y1558813D03*
Y1574167D03*
Y1568275D03*
X289558Y1567875D03*
X280897Y1578898D03*
X289558Y1578498D03*
Y1572606D03*
Y1593853D03*
Y1587960D03*
X280897Y1589522D03*
Y1583629D03*
X289558Y1583229D03*
X280897Y1594253D03*
Y1609607D03*
X289558Y1609207D03*
X280897Y1598984D03*
X289558Y1598584D03*
Y1603315D03*
X280897Y1604876D03*
Y1614338D03*
X289558Y1613938D03*
Y1618669D03*
X292000Y1644980D03*
X308760Y55513D03*
X310882Y96613D03*
X305953Y91951D03*
X312088Y113394D03*
X304557Y117261D03*
X297011Y180527D03*
X312264Y172665D03*
Y180665D03*
X299759Y190285D03*
X296966Y185121D03*
X312296Y212864D03*
Y200864D03*
Y221864D03*
Y216864D03*
X306812Y342319D03*
X309258Y389912D03*
Y393924D03*
Y385912D03*
Y409924D03*
Y405924D03*
Y401924D03*
X306673Y418838D03*
X298507Y445908D03*
X302457Y445787D03*
X302045Y1345691D03*
Y1350683D03*
X307001D03*
Y1345691D03*
X302045Y1362595D03*
X307001D03*
X302045Y1357603D03*
X307001D03*
X302045Y1374881D03*
Y1381801D03*
Y1369889D03*
X307001Y1374881D03*
Y1369889D03*
Y1381801D03*
X302045Y1386793D03*
Y1394087D03*
Y1399079D03*
X307001Y1386793D03*
Y1399079D03*
Y1394087D03*
X302045Y1405999D03*
Y1410991D03*
X307001Y1405999D03*
Y1410991D03*
X298220Y1465913D03*
Y1456451D03*
Y1461182D03*
X306881Y1465513D03*
Y1460782D03*
Y1470244D03*
Y1480867D03*
X298220Y1471805D03*
Y1476536D03*
Y1481267D03*
X306881Y1476136D03*
X298220Y1487159D03*
Y1491890D03*
Y1496621D03*
X306881Y1491490D03*
Y1485598D03*
Y1496221D03*
X298220Y1507245D03*
Y1502514D03*
X306881Y1506845D03*
Y1500952D03*
Y1511576D03*
X298220Y1511976D03*
X306881Y1516307D03*
X298220Y1558813D03*
Y1563544D03*
X306881Y1563144D03*
X298220Y1568275D03*
X306881Y1567875D03*
X298220Y1574167D03*
Y1578898D03*
X306881Y1578498D03*
Y1572606D03*
X298220Y1583629D03*
X306881Y1583229D03*
X298220Y1589522D03*
Y1594253D03*
X306881Y1593853D03*
Y1587960D03*
Y1598584D03*
Y1603315D03*
X298220Y1609607D03*
Y1604876D03*
Y1598984D03*
X306881Y1609207D03*
X298220Y1614338D03*
X306881Y1613938D03*
Y1618669D03*
X312000Y1644980D03*
X313624Y60922D03*
X327323Y109172D03*
X314737Y110784D03*
X314854Y130898D03*
X322331Y133298D03*
X329064Y146012D03*
X316478Y134579D03*
X328535Y253198D03*
X314053Y252371D03*
X323882Y303839D03*
X315904Y336324D03*
X320483Y353506D03*
X319241Y1350683D03*
Y1345691D03*
X314285D03*
Y1350683D03*
X326525Y1345691D03*
Y1350683D03*
X319241Y1362595D03*
X314285D03*
X326525D03*
X319241Y1357603D03*
X314285D03*
X326525D03*
X319241Y1374881D03*
Y1381801D03*
Y1369889D03*
X314285Y1374881D03*
Y1381801D03*
Y1369889D03*
X326525Y1381801D03*
Y1369889D03*
Y1374881D03*
X319241Y1386793D03*
Y1399079D03*
Y1394087D03*
X314285Y1386793D03*
Y1399079D03*
Y1394087D03*
X326525Y1399079D03*
Y1394087D03*
Y1386793D03*
X319241Y1410991D03*
Y1405999D03*
X314285Y1410991D03*
Y1405999D03*
X326525Y1410991D03*
Y1405999D03*
X315543Y1465913D03*
Y1456451D03*
Y1461182D03*
X324204Y1465513D03*
Y1460782D03*
Y1480867D03*
X315543Y1471805D03*
Y1476536D03*
Y1481267D03*
X324204Y1476136D03*
Y1470244D03*
X315543Y1487159D03*
Y1491890D03*
Y1496621D03*
X324204Y1491490D03*
Y1485598D03*
Y1496221D03*
Y1500952D03*
Y1511576D03*
X315543Y1507245D03*
Y1502514D03*
Y1511976D03*
X324204Y1506845D03*
Y1516307D03*
X315543Y1558813D03*
Y1563544D03*
X324204Y1563144D03*
X315543Y1574167D03*
Y1578898D03*
X324204Y1567875D03*
Y1578498D03*
Y1572606D03*
X315543Y1568275D03*
Y1583629D03*
Y1589522D03*
Y1594253D03*
X324204Y1583229D03*
Y1593853D03*
Y1587960D03*
X315543Y1609607D03*
Y1604876D03*
Y1598984D03*
X324204Y1609207D03*
Y1598584D03*
Y1603315D03*
X315543Y1614338D03*
X324204Y1613938D03*
Y1618669D03*
X329330Y106495D03*
X345074Y116496D03*
X337874Y116497D03*
X340374D03*
X345074Y109410D03*
Y102323D03*
X340374Y109410D03*
X333074Y116497D03*
X330323Y109172D03*
X337874Y130670D03*
X345074D03*
Y123583D03*
X340374D03*
X337874Y123584D03*
X333074D03*
Y130670D03*
X340374D03*
X333074Y137757D03*
X337874D03*
X330970Y141228D03*
X345074Y137756D03*
X333858Y150847D03*
X335826Y247292D03*
X338358Y554861D03*
X337564Y1018294D03*
X337629Y1186071D03*
X336901Y1196407D03*
X338765Y1350683D03*
Y1345691D03*
X331481D03*
Y1350683D03*
X343721Y1345691D03*
Y1350683D03*
X331481Y1362595D03*
X343721D03*
X338765D03*
X331481Y1357603D03*
X343721D03*
X338765D03*
X331481Y1374881D03*
Y1381801D03*
Y1369889D03*
X343721Y1381801D03*
Y1369889D03*
Y1374881D03*
X338765Y1381801D03*
Y1369889D03*
Y1374881D03*
X331481Y1399079D03*
Y1394087D03*
Y1386793D03*
X343721D03*
Y1394087D03*
Y1399079D03*
X338765Y1386793D03*
Y1394087D03*
Y1399079D03*
X331481Y1410991D03*
Y1405999D03*
X343721Y1410991D03*
Y1405999D03*
X338765Y1410991D03*
Y1405999D03*
X341527Y1460782D03*
X332865Y1465913D03*
Y1456451D03*
Y1461182D03*
X341527Y1465513D03*
Y1476136D03*
Y1470244D03*
Y1480867D03*
X332865Y1471805D03*
Y1476536D03*
Y1481267D03*
X341527Y1491490D03*
Y1485598D03*
Y1496221D03*
X332865Y1487159D03*
Y1491890D03*
Y1496621D03*
Y1511976D03*
X341527Y1506845D03*
Y1500952D03*
Y1511576D03*
X332865Y1507245D03*
Y1502514D03*
X341527Y1516307D03*
X332865Y1558813D03*
Y1563544D03*
X341527Y1563144D03*
X332865Y1578898D03*
X341527Y1567875D03*
Y1578498D03*
Y1572606D03*
X332865Y1568275D03*
Y1574167D03*
Y1583629D03*
Y1589522D03*
Y1594253D03*
X341527Y1583229D03*
Y1593853D03*
Y1587960D03*
X332865Y1598984D03*
X341527Y1609207D03*
Y1598584D03*
Y1603315D03*
X332865Y1609607D03*
Y1604876D03*
X341527Y1613938D03*
Y1618669D03*
X332865Y1614338D03*
X332000Y1644980D03*
X353536Y82984D03*
Y80384D03*
Y77784D03*
Y75184D03*
X356090Y92849D03*
X353536Y85584D03*
X359525Y137756D03*
X356423Y301288D03*
X348375Y322284D03*
X348968Y333138D03*
X359278Y491870D03*
X356778D03*
X358096Y867459D03*
X358086Y884616D03*
X357962Y898800D03*
X358024Y912085D03*
X358085Y923327D03*
X355929Y1132042D03*
X351563Y1132410D03*
X349700Y1148000D03*
X357947Y1159455D03*
X352536Y1160168D03*
X357297Y1192709D03*
X360659Y1209789D03*
X355961Y1350683D03*
X351005Y1345597D03*
Y1350683D03*
X355961Y1345597D03*
X351005Y1362595D03*
X355961D03*
X351005Y1357603D03*
X355961D03*
X351005Y1374881D03*
Y1381801D03*
Y1369889D03*
X355961Y1381801D03*
Y1374881D03*
Y1369889D03*
X351005Y1399079D03*
Y1393993D03*
Y1386793D03*
X355961D03*
Y1399079D03*
Y1393993D03*
X351005Y1410991D03*
Y1405999D03*
X355961D03*
Y1410991D03*
X350188Y1491891D03*
Y1487160D03*
Y1496622D03*
Y1507246D03*
Y1502515D03*
Y1511977D03*
X358850Y1511576D03*
Y1506845D03*
Y1516307D03*
X350188Y1563544D03*
Y1558813D03*
Y1568275D03*
Y1578898D03*
Y1574167D03*
Y1583629D03*
Y1594253D03*
Y1589522D03*
Y1604876D03*
Y1609607D03*
Y1598984D03*
Y1614338D03*
X352000Y1644980D03*
X376467Y94017D03*
X363050Y103037D03*
X363184Y116496D03*
Y109410D03*
Y130670D03*
Y123583D03*
X375982Y226141D03*
X378782D03*
X365365Y293796D03*
X367865D03*
X373379Y288190D03*
X375879Y285690D03*
X373379D03*
X375879Y288190D03*
X368057Y354184D03*
X364933Y374232D03*
X373264Y370010D03*
X366443Y472189D03*
X373504Y517954D03*
X375040Y932959D03*
X371424Y937185D03*
X367944Y946082D03*
X368657Y1146937D03*
X366133Y1162817D03*
X368661Y1182649D03*
X368917Y1195419D03*
X365029Y1214158D03*
X362735Y1211864D03*
X369839Y1218940D03*
X363245Y1345691D03*
Y1350683D03*
X368201Y1345691D03*
Y1350683D03*
X363245Y1362595D03*
X368201D03*
X363245Y1357603D03*
X368201D03*
X363245Y1369889D03*
Y1381801D03*
Y1374881D03*
X368201D03*
Y1381801D03*
Y1369889D03*
X363245Y1399079D03*
Y1394087D03*
Y1386793D03*
X368201D03*
Y1394087D03*
Y1399079D03*
X363245Y1405999D03*
Y1410991D03*
X368201D03*
Y1405999D03*
X372000Y1644980D03*
X393544Y76140D03*
Y84140D03*
Y80140D03*
X384467Y94017D03*
X388476D03*
X380467D03*
X390997Y117557D03*
X385587Y115401D03*
X380595D03*
X385587Y110445D03*
X380595D03*
X390997Y131731D03*
Y122513D03*
X385587Y129574D03*
X380595D03*
X385587Y124618D03*
X380595D03*
X390997Y136687D03*
X382158Y191941D03*
X388658Y184619D03*
X382025Y188727D03*
X390638Y206760D03*
X391852Y256535D03*
X383852D03*
X392882Y279208D03*
X378679Y285690D03*
Y288190D03*
X386905Y290755D03*
X382905D03*
X390905D03*
X392387Y337599D03*
Y342555D03*
X392444Y401949D03*
X393893Y413611D03*
X393833Y423944D03*
X393652Y482382D03*
X393746Y478382D03*
X388593Y664232D03*
X386350Y693559D03*
X391478Y690675D03*
X391614Y938651D03*
X381377Y1003008D03*
X381045Y1009444D03*
X391284Y1307238D03*
X394000Y1508100D03*
X382017Y1555700D03*
Y1547700D03*
Y1551700D03*
X392000Y1644980D03*
X408493Y117577D03*
X395989Y117557D03*
Y131731D03*
Y122513D03*
Y136687D03*
X399373Y180527D03*
X394690Y180572D03*
X403096Y192421D03*
X394690Y185165D03*
X399328Y185121D03*
X396986Y281307D03*
X409484Y314921D03*
X398951Y333711D03*
X397374Y344439D03*
X407493Y354142D03*
X394237Y370899D03*
X394944Y398949D03*
X399518Y402642D03*
X402018D03*
X396633Y423944D03*
X396693Y413611D03*
X399193D03*
X401693D03*
X401633Y423944D03*
X399133D03*
X409284Y741316D03*
X401121Y936686D03*
X409121Y939186D03*
X401121D03*
X409121Y936686D03*
X409231Y1123101D03*
X406105Y1139435D03*
X410131Y1129301D03*
X407631D03*
X409231Y1125801D03*
X406105Y1131935D03*
Y1134435D03*
Y1136935D03*
Y1141935D03*
Y1146935D03*
Y1144435D03*
X403263Y1152684D03*
X406319Y1204405D03*
Y1206905D03*
Y1211905D03*
Y1209405D03*
X397695Y1287071D03*
X399716Y1295198D03*
X408523Y1332967D03*
X404657D03*
X408937Y1351568D03*
X403981D03*
X401990Y1446807D03*
X399731Y1442755D03*
X397245Y1511640D03*
X404053Y1513673D03*
X397220Y1521207D03*
X409461Y1569560D03*
X405461D03*
X426147Y151540D03*
X414626Y180665D03*
Y172665D03*
X414658Y212864D03*
Y200864D03*
Y216864D03*
Y221864D03*
X422873Y309966D03*
X419955Y306966D03*
X414999D03*
X411984Y314921D03*
X421231Y338523D03*
Y331255D03*
Y345776D03*
X413432Y346797D03*
X416318Y367903D03*
X424479Y367859D03*
X418754Y468607D03*
X418226Y653288D03*
Y646480D03*
Y648980D03*
Y655788D03*
X425121Y936686D03*
Y939186D03*
X417121Y936686D03*
Y939186D03*
X417677Y1052215D03*
X425175Y1098767D03*
X417171Y1098887D03*
X419987Y1098518D03*
X419731Y1123101D03*
X417231D03*
X422631Y1125801D03*
X425131Y1129301D03*
X422631D03*
X420131D03*
X417631D03*
X415131D03*
X412631D03*
X420131Y1125801D03*
X417631D03*
X425131D03*
X422495Y1152713D03*
Y1155213D03*
X412095Y1152713D03*
Y1155213D03*
X422934Y1200821D03*
Y1198321D03*
X420619Y1204617D03*
Y1207117D03*
Y1209617D03*
Y1212117D03*
X411174Y1282776D03*
X418537Y1300197D03*
X423741Y1300115D03*
X413354Y1300197D03*
X425582Y1291743D03*
X423762Y1305298D03*
X413374D03*
X418558Y1310523D03*
X413395Y1310481D03*
X423721Y1310523D03*
X425283Y1373958D03*
X411147Y1474993D03*
X419818Y1474945D03*
X415241Y1492990D03*
X415095Y1502750D03*
X411353Y1519440D03*
X419467Y1519706D03*
X420279Y1525978D03*
X410626Y1525991D03*
X413461Y1569560D03*
X412000Y1644980D03*
X441727Y146461D03*
X440629Y152367D03*
X435703Y306966D03*
X430747D03*
X427829Y309966D03*
X428459Y331255D03*
X435793D03*
X428500Y345776D03*
X435793Y345738D03*
X430439Y358115D03*
X435702Y367813D03*
X430746D03*
X427782Y464026D03*
X438396Y511493D03*
X435834Y509580D03*
X431804Y536682D03*
Y539182D03*
X441832Y626193D03*
X433206Y1055498D03*
X430706D03*
Y1057998D03*
X433206D03*
Y1060498D03*
Y1062998D03*
X430706D03*
Y1060498D03*
X441359Y1123101D03*
X438233Y1139435D03*
X441359Y1125801D03*
X439759Y1129301D03*
X442259D03*
X429331Y1136935D03*
Y1134435D03*
Y1139435D03*
Y1131935D03*
X435733D03*
Y1134435D03*
Y1136935D03*
Y1139435D03*
X438233Y1131935D03*
Y1134435D03*
Y1136935D03*
X429331Y1141935D03*
X435733D03*
Y1146935D03*
Y1144435D03*
X438233Y1141935D03*
Y1146935D03*
Y1144435D03*
X437231Y1154902D03*
Y1152402D03*
X429331Y1146935D03*
Y1144435D03*
X433249Y1204405D03*
Y1209405D03*
Y1211905D03*
Y1206905D03*
X437991Y1286544D03*
X440896Y1311366D03*
X432485Y1325784D03*
X439624Y1345691D03*
Y1350683D03*
Y1357603D03*
Y1362595D03*
Y1381801D03*
Y1369889D03*
Y1374881D03*
X436002Y1382252D03*
X439624Y1386793D03*
X437675Y1550158D03*
X429784Y1548222D03*
X432000Y1644980D03*
X458454Y328963D03*
Y324007D03*
Y339755D03*
Y344711D03*
X453463Y370694D03*
X448092Y375770D03*
X443094Y491251D03*
X455104Y536582D03*
Y539082D03*
X447279Y633881D03*
X454815Y974622D03*
X448999Y994483D03*
X456210Y1004680D03*
X452319Y1000828D03*
X449731Y1000855D03*
X453710Y1018825D03*
X443091Y1022766D03*
Y1030266D03*
X450063Y1043140D03*
X449767Y1047047D03*
X457303Y1098767D03*
X452115Y1098518D03*
X446863Y1098428D03*
X449359Y1123101D03*
X451859D03*
X457259Y1129301D03*
X449759Y1125801D03*
X452259D03*
X444759Y1129301D03*
X447259D03*
X449759D03*
X452259D03*
X454759Y1125801D03*
X457259D03*
X454759Y1129301D03*
X443223Y1155213D03*
Y1152713D03*
X452623D03*
Y1155213D03*
X447549Y1204617D03*
X449864Y1198321D03*
Y1200821D03*
X447549Y1209617D03*
Y1207117D03*
Y1212117D03*
X454120Y1269498D03*
X456213Y1286776D03*
X451304Y1293045D03*
X456820Y1345691D03*
X451864D03*
Y1350683D03*
X456820D03*
X444580Y1345691D03*
Y1350683D03*
X456820Y1362595D03*
Y1357603D03*
X451864Y1362595D03*
Y1357603D03*
X444580D03*
Y1362595D03*
X456820Y1374881D03*
X451864D03*
X444580Y1369889D03*
X456820Y1369795D03*
X451864D03*
X444580Y1374881D03*
Y1381801D03*
X456820D03*
X451864D03*
X456820Y1399079D03*
X451864Y1393993D03*
Y1399079D03*
X456820Y1393993D03*
Y1386793D03*
X451864D03*
X444580D03*
X456820Y1405999D03*
X451864D03*
Y1410991D03*
X456820D03*
X454125Y1461182D03*
Y1465913D03*
Y1471805D03*
Y1481267D03*
Y1476536D03*
Y1491890D03*
Y1487159D03*
Y1496621D03*
Y1511976D03*
Y1507245D03*
Y1502514D03*
Y1558813D03*
Y1578898D03*
Y1568275D03*
Y1563544D03*
Y1574167D03*
Y1583629D03*
Y1589522D03*
Y1594253D03*
Y1609607D03*
Y1598984D03*
Y1604876D03*
Y1614338D03*
X452000Y1644980D03*
X464738Y110784D03*
X462089Y113394D03*
X472332Y133298D03*
X464332D03*
X466479Y134579D03*
X464054Y252371D03*
X461454Y336837D03*
Y331881D03*
Y347629D03*
Y352585D03*
X466375Y366365D03*
X470389Y389553D03*
X468558Y491669D03*
Y503669D03*
Y507669D03*
Y512669D03*
X462242Y809792D03*
X475032Y843252D03*
X474678Y857919D03*
X463134Y859203D03*
X460455Y867050D03*
X475046Y885952D03*
X467494Y924532D03*
X462427Y1030218D03*
X460277Y1090268D03*
Y1093068D03*
X474818Y1123101D03*
X469192Y1131935D03*
X474818Y1125801D03*
X473218Y1129301D03*
X461459Y1136935D03*
Y1134435D03*
Y1139435D03*
Y1131935D03*
X471692Y1139435D03*
Y1136935D03*
Y1134435D03*
Y1131935D03*
X469192Y1139435D03*
Y1136935D03*
Y1134435D03*
X471692Y1146935D03*
Y1141935D03*
X469192Y1144435D03*
Y1146935D03*
Y1141935D03*
X471692Y1144435D03*
X461459D03*
X462687Y1152684D03*
X468850D03*
X461459Y1141935D03*
Y1146935D03*
X463216Y1254164D03*
Y1250760D03*
Y1244055D03*
X461613Y1286776D03*
X469060Y1345691D03*
Y1350683D03*
X464104Y1345691D03*
Y1350683D03*
X469060Y1357603D03*
Y1362595D03*
X464104D03*
Y1357603D03*
Y1381801D03*
X469060D03*
X464104Y1369889D03*
X469060D03*
X464104Y1374881D03*
X469060D03*
Y1386793D03*
X464104D03*
X469060Y1399079D03*
X464104Y1394087D03*
X469060D03*
X464104Y1399079D03*
Y1405999D03*
X469060D03*
X464104Y1410991D03*
X469060D03*
X471448Y1461182D03*
X462786Y1460782D03*
X471448Y1465913D03*
X462786Y1465513D03*
X471448Y1481267D03*
X462786Y1480867D03*
X471448Y1471805D03*
Y1476536D03*
X462786Y1476136D03*
Y1470244D03*
X471448Y1496621D03*
X462786Y1496221D03*
X471448Y1491890D03*
X462786Y1491490D03*
Y1485598D03*
X471448Y1487159D03*
Y1511976D03*
Y1502514D03*
Y1507245D03*
X462786Y1511576D03*
Y1506845D03*
Y1500952D03*
Y1516307D03*
Y1563144D03*
X471448Y1558813D03*
X462786Y1578498D03*
X471448Y1574167D03*
Y1568275D03*
Y1563544D03*
X462786Y1567875D03*
Y1572606D03*
X471448Y1578898D03*
Y1594253D03*
X462786Y1593853D03*
X471448Y1589522D03*
Y1583629D03*
X462786Y1583229D03*
Y1587960D03*
X471448Y1598984D03*
X462786Y1609207D03*
Y1598584D03*
Y1603315D03*
X471448Y1609607D03*
Y1604876D03*
Y1614338D03*
X462786Y1613938D03*
Y1618669D03*
X472000Y1644980D03*
X480324Y109172D03*
X477324D03*
X479331Y106495D03*
X483075Y116497D03*
X487875D03*
X490375Y109410D03*
Y116497D03*
X483075Y130670D03*
X487875Y123584D03*
Y130670D03*
X490375Y123583D03*
Y130670D03*
X483075Y123584D03*
X479065Y146012D03*
X480971Y141228D03*
X483075Y137757D03*
X487875D03*
X483859Y150847D03*
X485827Y247292D03*
X478536Y253198D03*
X483242Y366481D03*
X483584Y375840D03*
X483736Y371266D03*
X483541Y380306D03*
X481724Y391589D03*
Y387089D03*
X488438Y425464D03*
X482532Y418464D03*
X482484Y444517D03*
X486738Y581222D03*
X489538D03*
Y591215D03*
X486738D03*
X491340Y611091D03*
X485005Y659771D03*
X491324Y667293D03*
X485303Y681841D03*
X486246Y804497D03*
X485824Y819787D03*
X481593Y826387D03*
X491453Y834546D03*
X491527Y843206D03*
X488469Y857013D03*
X481943Y924633D03*
X488388Y938903D03*
X483636Y952152D03*
X490143Y989521D03*
X476148Y1057998D03*
Y1055498D03*
X478648D03*
Y1057998D03*
X476148Y1060498D03*
Y1062998D03*
X478648D03*
Y1060498D03*
X490762Y1098767D03*
X485574Y1098518D03*
X480322Y1098428D03*
X485318Y1123101D03*
X482818D03*
X490718Y1129301D03*
X483218Y1125801D03*
X485718D03*
X475718Y1129301D03*
X478218D03*
X480718D03*
X483218D03*
X485718D03*
X488218Y1125801D03*
X490718D03*
X488218Y1129301D03*
X477682Y1152713D03*
Y1155213D03*
X488082D03*
Y1152713D03*
X479521Y1204405D03*
Y1206905D03*
Y1211905D03*
Y1209405D03*
X488584Y1345691D03*
Y1350683D03*
X481300Y1345691D03*
X476344D03*
X481300Y1350683D03*
X476344D03*
X488584Y1357603D03*
Y1362595D03*
X481300D03*
Y1357603D03*
X476344Y1362595D03*
Y1357603D03*
X488584Y1381801D03*
X481300D03*
X488584Y1374881D03*
Y1369889D03*
X481300D03*
Y1374881D03*
X476344Y1381801D03*
Y1369889D03*
Y1374881D03*
X488584Y1386793D03*
X481300D03*
Y1399079D03*
X476344Y1394087D03*
Y1399079D03*
X488584Y1394087D03*
X481300D03*
X488584Y1399079D03*
X476344Y1386793D03*
Y1410991D03*
X481300Y1405999D03*
X476344D03*
X488584D03*
Y1410991D03*
X481300D03*
X480109Y1460782D03*
Y1465513D03*
X488771Y1465913D03*
Y1461182D03*
X480109Y1476136D03*
Y1470244D03*
X488771Y1471805D03*
Y1476536D03*
Y1481267D03*
X480109Y1480867D03*
Y1496221D03*
X488771Y1487159D03*
Y1491890D03*
X480109Y1491490D03*
Y1485598D03*
X488771Y1496621D03*
Y1511976D03*
X480109Y1511576D03*
Y1506845D03*
Y1500952D03*
X488771Y1502514D03*
Y1507245D03*
X480109Y1516307D03*
X488771Y1558813D03*
X480109Y1563144D03*
X488771Y1578898D03*
X480109Y1578498D03*
X488771Y1574167D03*
Y1568275D03*
Y1563544D03*
X480109Y1567875D03*
Y1572606D03*
X488771Y1589522D03*
Y1583629D03*
X480109Y1583229D03*
Y1587960D03*
X488771Y1594253D03*
X480109Y1593853D03*
X488771Y1609607D03*
Y1604876D03*
Y1598984D03*
X480109Y1609207D03*
Y1598584D03*
Y1603315D03*
X488771Y1614338D03*
X480109Y1613938D03*
Y1618669D03*
X503537Y77784D03*
Y75184D03*
Y80384D03*
Y82984D03*
X506091Y92849D03*
X503537Y85584D03*
X495075Y116496D03*
Y102323D03*
Y109410D03*
Y130670D03*
Y123583D03*
Y137756D03*
X497424Y354559D03*
X492317Y376252D03*
X503682Y455466D03*
X497776Y448466D03*
X493929Y555194D03*
X496729D03*
X493929Y563194D03*
X496729D03*
X493929Y571194D03*
X496729D03*
X492338Y581222D03*
Y591215D03*
X494632Y654622D03*
X501618Y698355D03*
X499012Y699819D03*
X503311Y715652D03*
X500705Y705524D03*
X507546Y738539D03*
X505673Y767961D03*
X500717D03*
X504341Y812040D03*
X491655Y829173D03*
X506246Y824689D03*
X492799Y846488D03*
X503741Y846830D03*
X497467Y833027D03*
X499640Y861538D03*
X499595Y963963D03*
X493050Y976078D03*
X506566Y1000766D03*
Y1004766D03*
Y1016266D03*
Y1030766D03*
X505981Y1052487D03*
X506946Y1123101D03*
Y1125801D03*
X505346Y1129301D03*
X507846D03*
X503820Y1139435D03*
Y1136935D03*
Y1134435D03*
Y1131935D03*
X501320Y1139435D03*
Y1136935D03*
Y1134435D03*
Y1131935D03*
X494918Y1136935D03*
Y1134435D03*
Y1139435D03*
Y1131935D03*
X503820Y1144435D03*
Y1146935D03*
Y1141935D03*
X501320Y1144435D03*
Y1146935D03*
Y1141935D03*
X494918Y1146935D03*
Y1144435D03*
Y1141935D03*
X502562Y1152713D03*
Y1155213D03*
X506451Y1204405D03*
X493821Y1204617D03*
X496136Y1200821D03*
Y1198321D03*
X506451Y1206905D03*
Y1211905D03*
Y1209405D03*
X493821Y1207117D03*
Y1209617D03*
Y1212117D03*
X500824Y1350683D03*
Y1345691D03*
X505780Y1350683D03*
Y1345691D03*
X493540D03*
Y1350683D03*
X505780Y1362595D03*
Y1357603D03*
X500824Y1362595D03*
Y1357603D03*
X493540Y1362595D03*
Y1357603D03*
Y1381801D03*
Y1374881D03*
Y1369889D03*
X505780Y1381801D03*
Y1374881D03*
Y1369889D03*
X500824D03*
Y1381801D03*
Y1374881D03*
Y1394087D03*
X505780Y1399079D03*
X500824D03*
X505780Y1394087D03*
X493540Y1386793D03*
Y1394087D03*
Y1399079D03*
X505780Y1386793D03*
X500824D03*
X505780Y1410991D03*
X500824D03*
X505780Y1405999D03*
X500824D03*
X493540D03*
Y1410991D03*
X497432Y1465513D03*
X506093Y1465913D03*
X497432Y1460782D03*
X506093Y1461182D03*
X497432Y1480867D03*
X506093Y1481267D03*
X497432Y1476136D03*
Y1470244D03*
X506093Y1471805D03*
Y1476536D03*
X497432Y1496221D03*
Y1491490D03*
Y1485598D03*
X506093Y1487159D03*
Y1491890D03*
Y1496621D03*
Y1511976D03*
X497432Y1506845D03*
Y1500952D03*
X506093Y1502514D03*
Y1507245D03*
X497432Y1511576D03*
Y1516307D03*
Y1563144D03*
X506093Y1558813D03*
X497432Y1578498D03*
X506093Y1578898D03*
X497432Y1567875D03*
Y1572606D03*
X506093Y1574167D03*
Y1568275D03*
Y1563544D03*
X497432Y1587960D03*
X506093Y1589522D03*
Y1583629D03*
X497432Y1593853D03*
X506093Y1594253D03*
X497432Y1583229D03*
X506093Y1604876D03*
Y1598984D03*
X497432Y1609207D03*
X506093Y1609607D03*
X497432Y1598584D03*
Y1603315D03*
Y1613938D03*
Y1618669D03*
X506093Y1614338D03*
X492000Y1644980D03*
X513051Y103037D03*
X513185Y116496D03*
Y109410D03*
Y130670D03*
Y123583D03*
X509251Y137756D03*
X517866Y293796D03*
X515366D03*
X523380Y285690D03*
Y288190D03*
X511342Y311124D03*
X520845Y434508D03*
X516845D03*
X512845D03*
X514608Y445874D03*
X510022Y446352D03*
X523705Y444269D03*
X523583Y447201D03*
X521636Y504699D03*
X516636D03*
X519136D03*
X516338Y516979D03*
X521338D03*
X518838D03*
X512404Y629362D03*
X510215Y627948D03*
X511990Y686365D03*
X518001Y694940D03*
X522410Y694881D03*
X518067Y699378D03*
X518530Y703584D03*
X522628Y703884D03*
X508237Y723585D03*
X512502Y738539D03*
X516953Y738575D03*
X521909D03*
X520159Y758832D03*
X509063Y782867D03*
X517194Y773232D03*
X522316Y793574D03*
X509316Y793224D03*
X508130Y787488D03*
X521178Y814001D03*
X521565Y820931D03*
X520720Y846133D03*
X517832Y834558D03*
X508049Y877789D03*
X523272Y880067D03*
X509428Y888390D03*
X521115Y897500D03*
X511025Y911443D03*
X509673Y900295D03*
X516256Y939157D03*
X514886Y952189D03*
X519792Y1031271D03*
X517702Y1098518D03*
X512450Y1098428D03*
X522890Y1098767D03*
X514946Y1123101D03*
X517446D03*
X522846Y1129301D03*
X515346Y1125801D03*
X517846D03*
X510346Y1129301D03*
X512846D03*
X515346D03*
X517846D03*
X520346Y1125801D03*
X522846D03*
X520346Y1129301D03*
X518210Y1155213D03*
Y1152713D03*
X508810D03*
Y1155213D03*
X520751Y1204617D03*
X523066Y1200821D03*
Y1198321D03*
X520751Y1207117D03*
Y1209617D03*
Y1212117D03*
X513064Y1345691D03*
X518020Y1350683D03*
X513064D03*
X518020Y1345691D03*
Y1357603D03*
X513064Y1362595D03*
Y1357603D03*
X518020Y1362595D03*
X513064Y1369889D03*
Y1381801D03*
Y1374881D03*
X518020Y1369889D03*
Y1381801D03*
Y1374881D03*
Y1394087D03*
Y1399079D03*
X513064Y1394087D03*
Y1399079D03*
Y1386793D03*
X518020D03*
Y1405999D03*
Y1410991D03*
X513064D03*
Y1405999D03*
X514755Y1460782D03*
Y1465513D03*
Y1480867D03*
Y1476136D03*
Y1470244D03*
Y1491490D03*
Y1485598D03*
Y1496221D03*
Y1511576D03*
Y1506845D03*
Y1500952D03*
Y1516307D03*
Y1563144D03*
Y1567875D03*
Y1572606D03*
Y1578498D03*
Y1593853D03*
Y1583229D03*
Y1587960D03*
Y1603315D03*
Y1609207D03*
Y1598584D03*
Y1613938D03*
Y1618669D03*
X512000Y1644980D03*
X526468Y94017D03*
X534468D03*
X538477D03*
X530468D03*
X530596Y115401D03*
X535588Y110445D03*
Y115401D03*
X530596Y110445D03*
Y124618D03*
Y129574D03*
X535588Y124618D03*
Y129574D03*
X528509Y151540D03*
X538659Y184619D03*
X532159Y191941D03*
X532026Y188727D03*
X528783Y226141D03*
X525983D03*
X533853Y256535D03*
X525880Y285690D03*
X528680D03*
X525880Y288190D03*
X528680D03*
X532906Y290755D03*
X536906D03*
X540906D03*
X524206Y354119D03*
X533027Y351836D03*
X530215Y364422D03*
X535142Y397552D03*
X532936Y519544D03*
X527936D03*
X525436D03*
X530436D03*
X538826Y633450D03*
X526756Y636005D03*
Y633205D03*
X538826Y636250D03*
Y639050D03*
X526756Y638805D03*
X524653Y643595D03*
X534940Y684489D03*
X539111Y681459D03*
X526956Y694959D03*
X526951Y699443D03*
X535387Y712617D03*
X526933Y703820D03*
X532628Y720776D03*
X526276Y721339D03*
X539763Y734097D03*
X534807D03*
X531763Y739097D03*
X526807D03*
X532450Y767474D03*
X532278Y762736D03*
X531501Y792331D03*
X531260Y794934D03*
X531666Y815724D03*
X531313Y822693D03*
X527733Y847026D03*
X527346Y911458D03*
X528674Y964851D03*
X527046Y1131935D03*
Y1139435D03*
Y1134435D03*
Y1136935D03*
X528274Y1152684D03*
X527046Y1146935D03*
Y1144435D03*
Y1141935D03*
X525304Y1345691D03*
X530260D03*
X537544Y1350683D03*
X525304D03*
X530260D03*
X537544Y1345691D03*
Y1357603D03*
X525304Y1362595D03*
X530260D03*
X525304Y1357603D03*
X530260D03*
X537544Y1362595D03*
Y1374881D03*
X525304Y1369889D03*
Y1381801D03*
Y1374881D03*
X530260Y1369889D03*
Y1381801D03*
Y1374881D03*
X537544Y1369889D03*
Y1381801D03*
Y1399079D03*
Y1394087D03*
X530260D03*
Y1399079D03*
X525304Y1394087D03*
Y1399079D03*
X537544Y1386793D03*
X525304D03*
X530260D03*
X537544Y1410991D03*
Y1405999D03*
X530260D03*
X525304D03*
X530260Y1410991D03*
X525304D03*
X532000Y1644980D03*
X543545Y84140D03*
Y80140D03*
Y76140D03*
X540998Y117557D03*
X545990D03*
Y122513D03*
Y131731D03*
X540998Y122513D03*
Y131731D03*
X544089Y146461D03*
X545990Y136687D03*
X540998D03*
X542991Y152367D03*
X549374Y180527D03*
X544691Y180572D03*
X553097Y192421D03*
X549329Y185121D03*
X544691Y185165D03*
X540639Y206760D03*
X541853Y256535D03*
X542883Y279208D03*
X546987Y281307D03*
X541644Y389047D03*
X553731Y388487D03*
X541706Y381723D03*
X552905Y430829D03*
X550274Y658676D03*
X556574Y684031D03*
Y700031D03*
Y688987D03*
Y716031D03*
Y704987D03*
Y720987D03*
X552384Y762892D03*
X552188Y766577D03*
X553871Y811298D03*
X545741Y804149D03*
X548464Y823156D03*
X540807Y816556D03*
X541129Y828335D03*
Y838865D03*
X545981Y846389D03*
X549241Y841388D03*
X545237Y850319D03*
X548521Y877859D03*
Y874859D03*
X545144Y909025D03*
X544793Y899220D03*
X548215Y1006560D03*
X552923Y997860D03*
X541766Y1018368D03*
X557681Y1035088D03*
X554740Y1345597D03*
X542500Y1345691D03*
X549784Y1345597D03*
X542500Y1350683D03*
X549784D03*
X554740D03*
Y1362595D03*
Y1357603D03*
X542500Y1362595D03*
X549784D03*
X542500Y1357603D03*
X549784D03*
X554740Y1381801D03*
Y1374881D03*
X542500D03*
X549784Y1369889D03*
Y1381801D03*
Y1374881D03*
X542500Y1369889D03*
Y1381801D03*
X554740Y1369889D03*
Y1399079D03*
Y1393993D03*
X542500Y1399079D03*
X549784Y1393993D03*
Y1399079D03*
X542500Y1394087D03*
X554740Y1386793D03*
X549784D03*
X542500D03*
X554740Y1410991D03*
Y1405999D03*
X542500Y1410991D03*
X549784D03*
X542500Y1405999D03*
X549784D03*
X552000Y1644980D03*
X566287Y60922D03*
X561123Y55513D03*
X563224Y96813D03*
X558316Y91951D03*
X556920Y117261D03*
X567100Y110784D03*
X564451Y113394D03*
X567290Y130898D03*
X568841Y134579D03*
X564627Y180665D03*
Y172665D03*
X569969Y195176D03*
X564659Y212864D03*
Y200864D03*
X569829Y203393D03*
X564659Y221864D03*
Y216864D03*
X566416Y252371D03*
X570634Y375453D03*
X559074Y696987D03*
Y692031D03*
Y712987D03*
Y708031D03*
X561886Y728138D03*
X559625Y739609D03*
X557813Y747814D03*
X570578Y749800D03*
X570695Y767052D03*
X564276Y776701D03*
X558241Y796389D03*
X569186Y787332D03*
X561401Y811242D03*
X567316Y806224D03*
X561061Y803606D03*
X563099Y829943D03*
X567316Y827724D03*
X559741Y822149D03*
X572171Y842346D03*
X559196Y846296D03*
X569577Y886913D03*
X560814Y901022D03*
X564923Y997860D03*
X560923D03*
X568923D03*
X556923D03*
X571857Y1009354D03*
X565451Y1035102D03*
X569520Y1102091D03*
X560211D03*
X566020D03*
X569520Y1114691D03*
X566020D03*
X560211D03*
X569520Y1139891D03*
X566020D03*
X560211D03*
X566020Y1127291D03*
X560211D03*
X569520D03*
X566020Y1152491D03*
X560211D03*
X569520D03*
X566020Y1165091D03*
X560211D03*
X569520D03*
X560211Y1177691D03*
X566020D03*
X569520D03*
X566502Y1202103D03*
X569882Y1223749D03*
X562024Y1350683D03*
Y1345691D03*
X566980D03*
Y1350683D03*
X562024Y1357603D03*
X566980D03*
Y1362595D03*
X562024D03*
Y1369889D03*
Y1381801D03*
Y1374881D03*
X566980Y1369889D03*
Y1381801D03*
Y1374881D03*
Y1399079D03*
Y1394087D03*
X562024Y1399079D03*
Y1394087D03*
X566980Y1386793D03*
X562024D03*
X566980Y1410991D03*
X562024D03*
X566980Y1405999D03*
X562024D03*
X565600Y1530800D03*
X569349Y1541947D03*
X560635Y1543531D03*
X566800Y1541800D03*
X582686Y109172D03*
X579686D03*
X581693Y106495D03*
X585437Y116497D03*
X574694Y133298D03*
X585437Y123584D03*
Y130670D03*
X581427Y146012D03*
X583333Y141228D03*
X585437Y137757D03*
X586221Y150847D03*
X588189Y247292D03*
X580898Y253198D03*
X581487Y336676D03*
X573805Y728301D03*
X574620Y772724D03*
X584624Y781850D03*
X581001Y814123D03*
X579758Y817753D03*
X579827Y884000D03*
X579251Y903364D03*
X582706Y908959D03*
X580923Y997860D03*
X576923D03*
X588923D03*
X577666Y1009354D03*
X581166D03*
X572923Y997860D03*
X584923D03*
X581166Y1021954D03*
X577666D03*
X578298Y1215195D03*
X584024Y1209607D03*
X587689Y1505724D03*
X583661Y1529142D03*
X573784Y1530646D03*
X575332Y1523740D03*
X583800Y1518000D03*
X583740Y1520640D03*
X587858Y1517942D03*
X577645Y1540982D03*
X580700Y1544100D03*
X592737Y109410D03*
X590237Y116497D03*
X592737D03*
X597437Y102323D03*
Y109410D03*
Y116496D03*
Y123583D03*
Y130670D03*
X592737Y123583D03*
X590237Y123584D03*
Y130670D03*
X592737D03*
X597437Y137756D03*
X590237Y137757D03*
X590178Y309760D03*
X593690Y450750D03*
X597872Y512743D03*
X592880D03*
X597789Y536382D03*
X602756Y597580D03*
X604979Y599588D03*
X604241Y589556D03*
X604180Y592354D03*
X602695Y594668D03*
X604982Y596095D03*
X605011Y615600D03*
X604979Y607588D03*
X592238Y880612D03*
X597129Y913386D03*
X602385Y940920D03*
X596923Y997860D03*
X592923D03*
X604923D03*
X600923D03*
X602603Y1012354D03*
Y1024954D03*
X604405Y1034870D03*
X591898Y1035011D03*
X590957Y1105091D03*
Y1117691D03*
Y1130291D03*
Y1155491D03*
Y1142891D03*
Y1168091D03*
Y1180691D03*
X592978Y1514812D03*
X591858Y1523542D03*
X598800Y1546400D03*
X605899Y80384D03*
Y82984D03*
Y77784D03*
Y75184D03*
X608453Y92849D03*
X605899Y85584D03*
X615413Y103037D03*
X615547Y116496D03*
Y109410D03*
Y130670D03*
Y123583D03*
X612138Y137756D03*
X617728Y293796D03*
X620228D03*
X614461Y555234D03*
X614176Y562003D03*
X609472Y634946D03*
X612489Y941024D03*
X616923Y997860D03*
X608923D03*
X620151Y1040363D03*
X619086Y1056453D03*
X620715Y1046785D03*
X612000Y1644980D03*
X636830Y94017D03*
X628830D03*
X632830D03*
X632958Y110445D03*
Y115401D03*
Y124618D03*
Y129574D03*
X630871Y151540D03*
X634521Y191941D03*
X634388Y188727D03*
X631145Y226141D03*
X628345D03*
X636215Y256535D03*
X631042Y288190D03*
Y285690D03*
X625742Y288190D03*
X628242Y285690D03*
X625742D03*
X628242Y288190D03*
X635268Y290755D03*
X634455Y389154D03*
Y396240D03*
Y403327D03*
Y410413D03*
Y417500D03*
Y424587D03*
Y431673D03*
Y438760D03*
Y445847D03*
Y467539D03*
Y474626D03*
Y488799D03*
Y481713D03*
Y495886D03*
Y511673D03*
Y518760D03*
Y525847D03*
Y532933D03*
Y540020D03*
Y547106D03*
X633736Y602197D03*
X634200Y595108D03*
X622270Y864781D03*
X630466Y1394087D03*
X625510Y1399079D03*
Y1394087D03*
X630466Y1399079D03*
X625510Y1405999D03*
X630466D03*
X625510Y1410991D03*
X630466D03*
X636015Y1460782D03*
X627354Y1461182D03*
X636015Y1465513D03*
X627354Y1465913D03*
Y1456451D03*
X636015Y1476136D03*
X627354Y1476536D03*
X636015Y1480867D03*
X627354Y1481267D03*
Y1471805D03*
X636015Y1470244D03*
X627354Y1487159D03*
X636015Y1485598D03*
Y1491490D03*
X627354Y1491890D03*
X636015Y1496221D03*
X627354Y1496621D03*
Y1507245D03*
Y1511976D03*
X636015Y1511576D03*
X627354Y1502514D03*
X636015Y1500952D03*
Y1506845D03*
Y1516307D03*
X627354Y1558813D03*
X636015Y1563144D03*
X627354Y1563544D03*
X636015Y1567875D03*
X627354Y1568275D03*
Y1574167D03*
X636015Y1572606D03*
Y1578498D03*
X627354Y1578898D03*
X636015Y1593853D03*
X627354Y1594253D03*
X636015Y1583229D03*
X627354Y1583629D03*
Y1589522D03*
X636015Y1587960D03*
X627354Y1604876D03*
X636015Y1603315D03*
Y1598584D03*
X627354Y1598984D03*
X636015Y1609207D03*
X627354Y1609607D03*
X636015Y1618669D03*
Y1613938D03*
X627354Y1614338D03*
X632000Y1644980D03*
X645907Y76140D03*
Y84140D03*
Y80140D03*
X640839Y94017D03*
X643360Y117557D03*
X637950Y110445D03*
Y115401D03*
X648352Y117557D03*
X643360Y122513D03*
Y131731D03*
X637950Y124618D03*
Y129574D03*
X648352Y122513D03*
Y131731D03*
X646451Y146461D03*
X643360Y136687D03*
X648352D03*
X645353Y152367D03*
X647053Y180572D03*
X651736Y180527D03*
X651691Y185121D03*
X647053Y185165D03*
X641021Y184619D03*
X643001Y206760D03*
X644215Y256535D03*
X645245Y279208D03*
X649349Y281307D03*
X639268Y290755D03*
X643268D03*
X649074Y389154D03*
X647604Y396240D03*
X652381Y414823D03*
X651689Y422864D03*
X651759Y429832D03*
X651364Y436447D03*
X653399Y447953D03*
X652566Y467539D03*
X651308Y472772D03*
X652042Y487711D03*
X652155Y479104D03*
X652566Y495886D03*
X647915Y516841D03*
X651166Y510565D03*
X642862Y550123D03*
X642740Y552872D03*
X644494Y572334D03*
X642185Y562443D03*
X643953Y560675D03*
X642726Y574102D03*
X647361Y653161D03*
X648352Y645467D03*
X650958Y677843D03*
X649990Y1350683D03*
Y1345691D03*
Y1357603D03*
Y1362595D03*
Y1381801D03*
X642706Y1374881D03*
Y1381801D03*
Y1369889D03*
X649990Y1374881D03*
Y1369889D03*
X637750Y1374881D03*
Y1381801D03*
Y1369889D03*
X649990Y1399079D03*
Y1394087D03*
X642706Y1386793D03*
X649990D03*
X637750Y1399079D03*
X642706Y1394087D03*
X637750D03*
X642706Y1399079D03*
X637750Y1386793D03*
X649990Y1405999D03*
Y1410991D03*
X637750D03*
X642706D03*
Y1405999D03*
X637750D03*
X653338Y1465513D03*
X644677Y1461182D03*
Y1456451D03*
Y1465913D03*
X653338Y1460782D03*
X644677Y1476536D03*
Y1471805D03*
X653338Y1480867D03*
Y1470244D03*
Y1476136D03*
X644677Y1481267D03*
X653338Y1491490D03*
X644677Y1496621D03*
Y1491890D03*
Y1487159D03*
X653338Y1496221D03*
Y1485598D03*
X644677Y1511976D03*
X653338Y1511576D03*
Y1500952D03*
Y1506845D03*
X644677Y1502514D03*
Y1507245D03*
X653338Y1516307D03*
X644677Y1558813D03*
X653338Y1563144D03*
X644677Y1563544D03*
X653338Y1572606D03*
Y1578498D03*
X644677Y1578898D03*
Y1574167D03*
X653338Y1567875D03*
X644677Y1568275D03*
X653338Y1587960D03*
Y1593853D03*
X644677Y1594253D03*
Y1589522D03*
X653338Y1583229D03*
X644677Y1583629D03*
X653338Y1609207D03*
X644677Y1598984D03*
Y1604876D03*
Y1609607D03*
X653338Y1603315D03*
Y1598584D03*
Y1613938D03*
X644677Y1614338D03*
X653338Y1618669D03*
X652000Y1644980D03*
X668649Y60922D03*
X666209Y57297D03*
X665423Y96853D03*
X660678Y91951D03*
X659282Y117261D03*
X666813Y113394D03*
X669462Y110784D03*
X669056Y133298D03*
X666989Y172665D03*
Y180665D03*
X655459Y192421D03*
X667021Y200864D03*
Y212864D03*
Y221864D03*
Y216864D03*
X668778Y252371D03*
X667666Y389153D03*
X665166Y396240D03*
X667666D03*
X665166Y403327D03*
X667666Y403326D03*
X665166Y410413D03*
X667666D03*
Y417499D03*
X665166Y424586D03*
X667666D03*
X665166Y417500D03*
Y431673D03*
Y438760D03*
X667666D03*
Y431673D03*
X665166Y445847D03*
X667666Y467539D03*
X665166Y474626D03*
X667666D03*
X665166Y488799D03*
X667666D03*
Y481712D03*
X665166D03*
Y495886D03*
X667666Y518760D03*
X665166D03*
X667666Y511673D03*
Y532933D03*
X665166D03*
Y540020D03*
Y525846D03*
X667666D03*
X669546Y560500D03*
X655752Y668885D03*
X661776Y662981D03*
X656157Y691851D03*
X661768Y705043D03*
X654946Y1350683D03*
X662230D03*
X667186D03*
Y1345691D03*
X654946D03*
X662230D03*
X654946Y1357603D03*
Y1362595D03*
X662230Y1357603D03*
Y1362595D03*
X667186Y1357603D03*
Y1362595D03*
X662230Y1369889D03*
X667186Y1374881D03*
Y1381801D03*
Y1369889D03*
X662230Y1374881D03*
Y1381801D03*
X654946D03*
Y1369889D03*
Y1374881D03*
X667186Y1399079D03*
Y1393993D03*
X662230D03*
Y1399079D03*
X655046D03*
Y1394087D03*
X667186Y1386793D03*
X662230D03*
X654946D03*
X667186Y1410991D03*
Y1405999D03*
X662230D03*
Y1410991D03*
X655046Y1405999D03*
Y1410991D03*
X662000Y1456451D03*
Y1465913D03*
Y1461182D03*
Y1481267D03*
Y1476536D03*
Y1471805D03*
Y1496621D03*
Y1491890D03*
Y1487159D03*
Y1511976D03*
Y1502514D03*
Y1507245D03*
Y1563544D03*
Y1558813D03*
Y1568275D03*
Y1578898D03*
Y1574167D03*
Y1594253D03*
Y1589522D03*
Y1583629D03*
Y1598984D03*
Y1604876D03*
Y1609607D03*
Y1614338D03*
X682048Y109172D03*
X685048D03*
X684055Y106495D03*
X677056Y133298D03*
X671203Y134579D03*
X683789Y146012D03*
X685695Y141228D03*
X677331Y195176D03*
X676950Y198883D03*
X683260Y253198D03*
X686012Y339795D03*
X672466Y389153D03*
Y410413D03*
Y396240D03*
Y403326D03*
Y424586D03*
Y417499D03*
Y438760D03*
Y431673D03*
Y467539D03*
Y474626D03*
Y488799D03*
Y481712D03*
Y518760D03*
Y511673D03*
Y525846D03*
Y532933D03*
X681586Y555000D03*
X681011Y543925D03*
X679426Y1350683D03*
X674470Y1345691D03*
X679426D03*
X674470Y1350683D03*
Y1357603D03*
Y1362595D03*
X679426Y1357603D03*
Y1362595D03*
Y1374881D03*
X674470D03*
Y1381801D03*
X679426D03*
Y1369889D03*
X674470D03*
X679426Y1399079D03*
X674470Y1394087D03*
X679426D03*
X674470Y1399079D03*
Y1386793D03*
X679426D03*
X674470Y1405999D03*
X679426D03*
X674470Y1410991D03*
X679426D03*
X679322Y1461182D03*
Y1456451D03*
Y1465913D03*
X670661Y1460782D03*
Y1465513D03*
Y1470244D03*
Y1476136D03*
X679322Y1481267D03*
Y1476536D03*
Y1471805D03*
X670661Y1480867D03*
X679322Y1487159D03*
X670661Y1496221D03*
Y1485598D03*
Y1491490D03*
X679322Y1496621D03*
Y1491890D03*
X670661Y1500952D03*
Y1506845D03*
X679322Y1511976D03*
Y1502514D03*
Y1507245D03*
X670661Y1511576D03*
Y1516307D03*
X679322Y1558813D03*
X670661Y1563144D03*
X679322Y1563544D03*
Y1578898D03*
Y1574167D03*
Y1568275D03*
X670661Y1572606D03*
Y1578498D03*
Y1567875D03*
X679322Y1583629D03*
X670661Y1587960D03*
Y1593853D03*
Y1583229D03*
X679322Y1594253D03*
Y1589522D03*
Y1604876D03*
Y1609607D03*
X670661Y1603315D03*
Y1598584D03*
Y1609207D03*
X679322Y1598984D03*
Y1614338D03*
X670661Y1618669D03*
Y1613938D03*
X672000Y1644980D03*
X695099Y109410D03*
X687799Y116497D03*
X692599D03*
X695099D03*
X699799Y116496D03*
Y109410D03*
Y102323D03*
X687799Y123584D03*
X695099Y123583D03*
X692599Y123584D03*
X687799Y130670D03*
X692599D03*
X695099D03*
X699799Y123583D03*
Y130670D03*
X687799Y137757D03*
X692599D03*
X699799Y137756D03*
X688583Y150847D03*
X690551Y247292D03*
X700164Y636842D03*
X698936Y678462D03*
X702691Y766471D03*
Y753471D03*
X702677Y771159D03*
Y784659D03*
X698950Y1350683D03*
Y1345597D03*
X686710Y1350683D03*
X691666D03*
X686710Y1345691D03*
X691666D03*
X698950Y1362595D03*
Y1357603D03*
X686710D03*
Y1362595D03*
X691666Y1357603D03*
Y1362595D03*
X698950Y1374881D03*
Y1381801D03*
Y1369889D03*
X691666D03*
Y1374881D03*
Y1381801D03*
X686710Y1374881D03*
Y1369889D03*
Y1381801D03*
X698950Y1399079D03*
Y1394087D03*
X686710D03*
Y1399079D03*
X691666Y1394087D03*
Y1399079D03*
X698950Y1386793D03*
X691666D03*
X686710D03*
X698950Y1405999D03*
Y1410991D03*
X686710D03*
X691666D03*
X686710Y1405999D03*
X691666D03*
X696645Y1461183D03*
Y1456452D03*
Y1465914D03*
X687984Y1460782D03*
Y1465513D03*
Y1470244D03*
Y1476136D03*
X696645Y1481268D03*
Y1471806D03*
Y1476537D03*
X687984Y1480867D03*
X696645Y1491891D03*
X687984Y1496221D03*
Y1485598D03*
Y1491490D03*
X696645Y1496622D03*
Y1487160D03*
Y1511977D03*
Y1502515D03*
Y1507246D03*
X687984Y1511576D03*
Y1500952D03*
Y1506845D03*
Y1516307D03*
X696645Y1558813D03*
Y1563544D03*
X687984Y1563144D03*
X696645Y1574167D03*
Y1578898D03*
X687984Y1572606D03*
Y1578498D03*
X696645Y1568275D03*
X687984Y1567875D03*
Y1583229D03*
X696645Y1589522D03*
Y1594253D03*
X687984Y1587960D03*
Y1593853D03*
X696645Y1583629D03*
Y1598984D03*
Y1609607D03*
X687984Y1603315D03*
Y1598584D03*
Y1609207D03*
X696645Y1604876D03*
X687984Y1613938D03*
X696645Y1614338D03*
X687984Y1618669D03*
X692000Y1644980D03*
X718488Y-27642D03*
X718503Y-25127D03*
X708261Y82984D03*
Y80384D03*
Y77784D03*
Y75184D03*
X710815Y92849D03*
X708261Y85584D03*
X717775Y103037D03*
X717909Y116496D03*
Y109410D03*
Y130670D03*
Y123583D03*
X714500Y137756D03*
X713162Y434493D03*
X711764Y449873D03*
X718691Y465492D03*
Y472579D03*
X716191D03*
X711391D03*
X716191Y479666D03*
X718691D03*
X711391D03*
Y486752D03*
X716191D03*
X718691D03*
X711391Y493839D03*
X716191D03*
Y516713D03*
Y523800D03*
X718691D03*
X711391D03*
Y516713D03*
X718691D03*
Y509626D03*
Y530886D03*
X716191D03*
Y537973D03*
X711391Y530886D03*
Y537973D03*
Y566752D03*
X718691Y559665D03*
Y566752D03*
X716191D03*
X711391Y573839D03*
X718691D03*
X716191D03*
X711391Y588013D03*
X718691Y588012D03*
X716191Y588013D03*
X718691Y580926D03*
X716191D03*
X711391D03*
X716191Y602186D03*
X711391D03*
X718691Y602185D03*
Y595099D03*
X711391D03*
X716191D03*
X711391Y609272D03*
X716191D03*
X718691D03*
X716191Y616359D03*
X711391D03*
X706070Y638125D03*
X716656Y646429D03*
X703669Y665140D03*
X716350Y699477D03*
X703604Y699653D03*
X716146Y1350683D03*
X711190D03*
X716146Y1345691D03*
X711190D03*
X703906Y1350683D03*
Y1345597D03*
X716146Y1357603D03*
X711190D03*
Y1362595D03*
X716146D03*
X703906Y1357603D03*
Y1362595D03*
X716146Y1374881D03*
Y1381801D03*
Y1369889D03*
X711190D03*
Y1374881D03*
Y1381801D03*
X703906D03*
Y1369889D03*
Y1374881D03*
X716146Y1399079D03*
X711190D03*
X716146Y1393993D03*
X711190D03*
X703906Y1394087D03*
Y1399079D03*
X716146Y1386793D03*
X711190D03*
X703906D03*
X716146Y1405999D03*
X711190D03*
X716146Y1410991D03*
X711190D03*
X703906Y1405999D03*
Y1410991D03*
X712000Y1644980D03*
X721741Y-27628D03*
X721756Y-25113D03*
X724781Y-26433D03*
X735192Y94017D03*
X731192D03*
X733233Y151540D03*
X736750Y188727D03*
X730707Y226141D03*
X733507D03*
X733404Y285690D03*
X720090Y293796D03*
X722590D03*
X728104Y288190D03*
X730604Y285690D03*
X728104D03*
X730604Y288190D03*
X733404D03*
X731511Y390500D03*
X734606Y379562D03*
X722097Y410394D03*
Y403307D03*
X723491Y458406D03*
Y451319D03*
Y465492D03*
X723315Y462264D03*
X723491Y472579D03*
Y479665D03*
Y486752D03*
Y493839D03*
Y523799D03*
Y516713D03*
Y509626D03*
Y530886D03*
Y537973D03*
Y566752D03*
Y559665D03*
Y573839D03*
Y588012D03*
Y580926D03*
Y595099D03*
Y602185D03*
Y609272D03*
Y616358D03*
X734819Y646429D03*
X725318Y890354D03*
X720373Y940310D03*
X724547Y958287D03*
X723430Y1350683D03*
X728386Y1345691D03*
X723430D03*
X728386Y1350683D03*
Y1357603D03*
Y1362595D03*
X723430Y1357603D03*
Y1362595D03*
X728386Y1381801D03*
Y1374881D03*
Y1369889D03*
X723430D03*
Y1381801D03*
Y1374881D03*
X728386Y1386793D03*
X723430D03*
X728386Y1398985D03*
Y1393993D03*
X723430Y1398985D03*
Y1393993D03*
X728386Y1410897D03*
Y1405905D03*
X723430Y1410897D03*
Y1405905D03*
X732000Y1644980D03*
X748269Y84140D03*
Y76140D03*
Y80140D03*
X743201Y94017D03*
X739192D03*
X750714Y117557D03*
X745722D03*
X740312Y115401D03*
Y110445D03*
X735320D03*
Y115401D03*
X745722Y131731D03*
Y122513D03*
X740312Y129574D03*
Y124618D03*
X735320D03*
Y129574D03*
X750714Y131731D03*
Y122513D03*
Y136687D03*
X745722D03*
X748813Y146461D03*
X747715Y152367D03*
X749415Y180572D03*
Y185165D03*
X743383Y184619D03*
X736883Y191941D03*
X745363Y206760D03*
X738577Y256535D03*
X746577D03*
X747607Y279208D03*
X751711Y281307D03*
X741630Y290755D03*
X737630D03*
X745630D03*
X741161Y381500D03*
X741602Y465492D03*
X741568Y460250D03*
X739333Y470136D03*
X741602Y472579D03*
X741072Y478958D03*
X741602Y486752D03*
Y493839D03*
Y509626D03*
Y516713D03*
X738062Y537973D03*
X740542Y525483D03*
X740463Y532756D03*
X741602Y559665D03*
Y566752D03*
X741452Y579978D03*
X741602Y573839D03*
X741666Y608117D03*
X741000Y771100D03*
X738707Y987952D03*
X745673Y1007009D03*
X747910Y1345691D03*
Y1350683D03*
X735670D03*
X740626D03*
X735670Y1345691D03*
X740626D03*
X747910Y1357603D03*
Y1362595D03*
X735670Y1357603D03*
Y1362595D03*
X740626Y1357603D03*
Y1362595D03*
X747910Y1374881D03*
Y1381801D03*
Y1369889D03*
X740626Y1381801D03*
Y1369889D03*
Y1374881D03*
X735670Y1381801D03*
Y1369889D03*
Y1374881D03*
X747910Y1386793D03*
X735670Y1393993D03*
X740626D03*
Y1398985D03*
X735670D03*
X740626Y1386793D03*
X735670D03*
Y1405905D03*
Y1410897D03*
X740626Y1405905D03*
Y1410897D03*
X742655Y1445733D03*
X747590Y1627871D03*
X765847Y55513D03*
X762065Y117040D03*
X754098Y180527D03*
X757821Y192421D03*
X754053Y185121D03*
X756201Y288345D03*
Y290845D03*
X753701Y288345D03*
Y290845D03*
Y293645D03*
X756201D03*
X763898Y342319D03*
X766344Y393924D03*
Y389912D03*
Y385912D03*
X758038Y381143D03*
X766344Y409924D03*
Y405924D03*
Y401924D03*
X752341Y407148D03*
X756800Y403824D03*
X758381Y395391D03*
X759543Y445787D03*
X755593Y445908D03*
X765106Y1350683D03*
Y1345597D03*
X760150D03*
Y1350683D03*
X752866Y1345691D03*
Y1350683D03*
X765106Y1362595D03*
Y1357603D03*
X760150D03*
Y1362595D03*
X752866Y1357603D03*
Y1362595D03*
X765106Y1374881D03*
Y1381801D03*
Y1369889D03*
X760150Y1374881D03*
Y1381801D03*
Y1369889D03*
X752866Y1374881D03*
Y1381801D03*
Y1369889D03*
X765106Y1386793D03*
X760150D03*
X752866D03*
X766433Y1583713D03*
X752150Y1627871D03*
X762776Y1629415D03*
X752000Y1644980D03*
X771011Y60922D03*
X767929Y96890D03*
X771824Y110784D03*
X769175Y113394D03*
X779418Y133298D03*
X771960Y130898D03*
X773565Y134579D03*
X769351Y172665D03*
Y180665D03*
X769383Y200864D03*
Y212864D03*
Y221864D03*
Y216864D03*
X771140Y252371D03*
X780968Y303839D03*
X772990Y336324D03*
X777569Y353506D03*
X772390Y1350683D03*
X777346D03*
Y1345691D03*
X772390D03*
Y1357603D03*
Y1362595D03*
X777346Y1357603D03*
Y1362595D03*
X777114Y1442270D03*
X778045Y1622545D03*
X782289Y1620109D03*
X773822Y1627418D03*
X772000Y1644980D03*
X784410Y109172D03*
X787410D03*
X794961Y116497D03*
X797461D03*
X790161D03*
X786417Y106495D03*
X797461Y109410D03*
Y123583D03*
X794961Y123584D03*
X790161D03*
X794961Y130670D03*
X797461D03*
X790161D03*
X794961Y137757D03*
X790161D03*
X788057Y141228D03*
X786151Y146012D03*
X793221Y140296D03*
X790945Y150847D03*
X792913Y247292D03*
X785622Y253198D03*
X788522Y290304D03*
X799937Y347340D03*
X791686Y1025440D03*
X794716Y1186071D03*
X792183Y1334030D03*
Y1331230D03*
X789383Y1334030D03*
Y1331230D03*
X794506Y1411307D03*
X793723Y1468071D03*
X793564Y1642682D03*
X810623Y77784D03*
Y82984D03*
Y80384D03*
Y75184D03*
X813177Y92849D03*
X810623Y85584D03*
X802161Y116496D03*
Y109410D03*
Y102323D03*
Y130670D03*
Y123583D03*
Y137756D03*
X816364Y486870D03*
X813864D03*
X813566Y744187D03*
X812661Y810032D03*
X812980Y824166D03*
X816016Y838036D03*
X813182Y852800D03*
X814731Y889365D03*
X812811Y908162D03*
X809682Y1133284D03*
X806787Y1148000D03*
X815034Y1159455D03*
X809623Y1160168D03*
X809393Y1187252D03*
X807487Y1193019D03*
X815487D03*
X811487D03*
X817446Y1210089D03*
X800627Y1392748D03*
X800703Y1426779D03*
X811457Y1639797D03*
X820137Y103037D03*
X820271Y116496D03*
Y109410D03*
Y130670D03*
Y123583D03*
X816637Y137756D03*
X824952Y293796D03*
X822452D03*
X830466Y285690D03*
Y288190D03*
X825792Y305225D03*
X823529Y467189D03*
X830318Y674164D03*
X829784Y713939D03*
X832284Y731216D03*
X830484Y746701D03*
X819993Y754109D03*
X817500Y760000D03*
X820547Y780314D03*
X826925Y769000D03*
X820500Y777500D03*
X826925Y787000D03*
X820500Y792000D03*
X818500Y814000D03*
X820432Y800529D03*
X826925Y805000D03*
Y823000D03*
X826165Y863000D03*
X819134Y863607D03*
X829000Y852000D03*
X825686Y869496D03*
X826797Y883756D03*
X825508Y913869D03*
X822462Y915095D03*
X818347Y939610D03*
X828193Y949324D03*
X832432Y977982D03*
X832711Y993268D03*
X828385Y1120599D03*
X817006Y1133027D03*
X822006Y1130208D03*
X825744Y1146937D03*
X823220Y1162817D03*
X823487Y1193019D03*
X819487D03*
X826612Y1219254D03*
X819522Y1212164D03*
X821816Y1214458D03*
X832084Y1461072D03*
X831457Y1639797D03*
X844781Y-65613D03*
X841756Y-64293D03*
X838503Y-64307D03*
X841741Y-66808D03*
X838488Y-66822D03*
X841554Y94017D03*
X837554D03*
X845563D03*
X833554D03*
X837682Y110445D03*
Y115401D03*
X848084Y117557D03*
X842674Y115401D03*
Y110445D03*
Y129574D03*
Y124618D03*
X837682D03*
Y129574D03*
X848084Y131731D03*
Y122513D03*
Y136687D03*
X839112Y188727D03*
X839245Y191941D03*
X845745Y184619D03*
X847725Y206760D03*
X833069Y226141D03*
X835869D03*
X848939Y256535D03*
X840939D03*
X832966Y288190D03*
Y285690D03*
X835766Y288190D03*
Y285690D03*
X843992Y290755D03*
X839992D03*
X847992D03*
X835236Y533174D03*
X845729Y661263D03*
X836503Y667845D03*
X845784Y713939D03*
X848284Y731181D03*
X846484Y746701D03*
X841500Y758161D03*
Y776161D03*
Y794161D03*
Y812161D03*
X838685Y832987D03*
X845654Y895437D03*
X833870Y881860D03*
X839381Y915839D03*
X839122Y939655D03*
X843734Y1008778D03*
X848520Y1016855D03*
X850631Y84140D03*
Y80140D03*
Y76140D03*
X864006Y117261D03*
X853076Y117557D03*
Y131731D03*
Y122513D03*
Y136687D03*
X851777Y180572D03*
X856460Y180527D03*
X860183Y192421D03*
X851777Y185165D03*
X856415Y185121D03*
X849969Y279208D03*
X854073Y281307D03*
X864920Y343168D03*
X854086Y385000D03*
X858586D03*
X850733Y461382D03*
X850832Y473382D03*
X850738Y477382D03*
X850909Y482382D03*
X853900Y627700D03*
X858202Y646330D03*
X851111Y656635D03*
X856145Y677887D03*
X855646Y685230D03*
X858186Y713170D03*
X867227Y722060D03*
X849500Y761000D03*
X864575Y770500D03*
X849500Y779000D03*
X864575Y788500D03*
X849500Y797000D03*
Y815000D03*
X864575Y806500D03*
X865004Y831273D03*
X864464Y828503D03*
X864575Y824500D03*
X851782Y823720D03*
X851161Y855205D03*
X856628Y915242D03*
X864253D03*
X849600Y915266D03*
X855867Y935540D03*
X849088Y951081D03*
X852247Y1009529D03*
X849996Y1091073D03*
X850023Y1095179D03*
X863342Y1120636D03*
X855542D03*
X858142D03*
X860842D03*
X863442Y1130336D03*
X858242D03*
X855642D03*
X860942D03*
Y1139336D03*
X863442D03*
X861119Y1148080D03*
X863619D03*
X851457Y1639797D03*
X873373Y60922D03*
X868209Y55513D03*
X870395Y96738D03*
X865402Y91951D03*
X871713Y172665D03*
Y180665D03*
X871745Y200864D03*
Y212864D03*
Y216864D03*
Y221864D03*
X876246Y302754D03*
X869313Y688486D03*
X872069Y700894D03*
X876286Y686970D03*
X880501Y710611D03*
X873021Y715729D03*
X877616Y749484D03*
X873318Y744597D03*
X873250Y798750D03*
X872700Y816615D03*
X872628Y915242D03*
X880628D03*
X876481Y941126D03*
X868908Y933640D03*
X867199Y949372D03*
X869390Y978003D03*
X878004Y1224406D03*
X883142Y1259935D03*
X875700Y1299700D03*
X871457Y1639797D03*
X886011Y154100D03*
X895780Y237517D03*
Y232634D03*
X886261Y252090D03*
X885741Y261150D03*
X894844Y418983D03*
X889219Y426952D03*
X887770Y415290D03*
X890270D03*
X897344Y418983D03*
X894519Y426952D03*
X889596Y437264D03*
X896388Y437614D03*
X887096Y437264D03*
X892019Y426952D03*
X897019D03*
X882891Y536122D03*
X896449Y550863D03*
X893949Y550363D03*
X882949Y557363D03*
X887949Y608863D03*
X894449Y606363D03*
X884903Y694119D03*
X886836Y729778D03*
X889083Y780371D03*
X888545Y785528D03*
X888514Y797602D03*
X891916Y808965D03*
X882609Y994245D03*
X897056Y1091391D03*
X891055Y1095407D03*
X897056Y1095984D03*
X884906Y1102760D03*
X884890Y1098724D03*
X893190Y1208069D03*
X894887Y1227209D03*
X891003Y1292765D03*
X890738Y1311132D03*
X891457Y1639797D03*
X898813Y146461D03*
X897715Y152367D03*
X898851Y231496D03*
Y238583D03*
Y245669D03*
X910977Y238583D03*
X898851Y259843D03*
X898576Y253056D03*
X910977Y252756D03*
Y257480D03*
X898851Y274016D03*
X910977Y266929D03*
X898851D03*
X912786Y306697D03*
X901848Y307782D03*
Y312738D03*
X909417Y323302D03*
X912085Y332335D03*
X898888Y437614D03*
X906996Y530707D03*
X902459Y530755D03*
X911630Y543998D03*
X910578Y550186D03*
X909362Y555614D03*
X898156Y554812D03*
X909024Y586768D03*
X908730Y619120D03*
X913686D03*
X899898Y619040D03*
X904854D03*
X910036Y702285D03*
X910753Y715864D03*
X912864Y864189D03*
Y870488D03*
Y867338D03*
X899693Y895207D03*
X904833Y915340D03*
X912628Y928101D03*
X911355Y944909D03*
X906710Y962433D03*
X906909Y951494D03*
X909296Y1020224D03*
X909300Y1014639D03*
X901739Y1091346D03*
X897815Y1078042D03*
X901366Y1078069D03*
X901694Y1095940D03*
X911071Y1123803D03*
X905771D03*
X903171D03*
X908371D03*
X910971Y1114103D03*
X908271D03*
X903071D03*
X905671D03*
X911699Y1129488D03*
X909041Y1126328D03*
X911641D03*
X903908Y1132870D03*
X904063Y1135946D03*
X901940Y1236799D03*
Y1229899D03*
Y1232399D03*
Y1246199D03*
Y1243699D03*
Y1239299D03*
X904703Y1297398D03*
X911457Y1639797D03*
X919175Y113394D03*
X921824Y110784D03*
X921418Y133298D03*
X929418D03*
X923565Y134579D03*
X920142Y308501D03*
X926801Y323302D03*
X923902Y332411D03*
X924600Y533706D03*
X920961Y550075D03*
X915949Y563363D03*
X915712Y613792D03*
X915194Y666671D03*
X928043Y677795D03*
X917286Y679625D03*
X924932Y701051D03*
X920628Y928101D03*
X928628D03*
X916628D03*
X924628D03*
X924487Y951244D03*
X918648Y964717D03*
X915490Y969886D03*
X916749Y1080659D03*
Y1088659D03*
X917110Y1101902D03*
X927598Y1120636D03*
X924898D03*
X914661Y1132612D03*
X914299Y1129488D03*
X914241Y1126328D03*
X924919Y1130336D03*
X927619D03*
X924919Y1139336D03*
X927419D03*
X925097Y1147708D03*
X927597D03*
X927146Y1328597D03*
Y1323641D03*
X929094Y1542353D03*
Y1545353D03*
X926041Y1554503D03*
Y1551503D03*
Y1548503D03*
Y1557503D03*
Y1560503D03*
X944961Y116497D03*
X934410Y109172D03*
X936417Y106495D03*
X937410Y109172D03*
X940161Y116497D03*
Y123584D03*
X944961D03*
X940161Y130670D03*
X944961D03*
X940161Y137757D03*
X944961D03*
X936151Y146012D03*
X938057Y141228D03*
X940945Y150847D03*
X932388Y330517D03*
X932622Y336817D03*
X944694Y352192D03*
X931627Y561578D03*
Y565578D03*
X943825Y581222D03*
Y591215D03*
X935281Y677795D03*
X945626Y789761D03*
X932000Y831000D03*
X942634Y886520D03*
X933700Y887508D03*
X944839Y902400D03*
X938188Y900853D03*
X944628Y928101D03*
X932628D03*
X936628D03*
X940497D03*
X941981Y1224406D03*
X947119Y1259935D03*
X933254Y1308273D03*
X940848Y1310181D03*
X930441Y1455039D03*
Y1458039D03*
Y1464039D03*
Y1461039D03*
Y1467039D03*
X938670Y1510528D03*
X941270D03*
Y1505328D03*
X938670D03*
X940170Y1507928D03*
X943870Y1510528D03*
Y1505328D03*
X945370Y1507928D03*
X942770D03*
X935094Y1542353D03*
X932094D03*
X935094Y1545353D03*
X932094D03*
X938094Y1542353D03*
Y1545353D03*
X941094Y1542353D03*
X944094D03*
X941094Y1545353D03*
X944094D03*
X931457Y1639797D03*
X960623Y82984D03*
Y77784D03*
Y80384D03*
Y75184D03*
Y85584D03*
X947461Y116497D03*
X952161Y116496D03*
Y109410D03*
Y102323D03*
X947461Y109410D03*
Y130670D03*
X952161D03*
Y123583D03*
X947461D03*
X952161Y137756D03*
X949443Y208206D03*
X949579Y330517D03*
X949813Y336817D03*
X956863Y451466D03*
X953816Y555194D03*
X951016D03*
X953816Y571194D03*
X951016D03*
X953816Y563194D03*
X951016D03*
X946625Y581222D03*
X949425D03*
Y591215D03*
X946625D03*
X948427Y611091D03*
X957551Y698251D03*
X954023Y725336D03*
X951195Y727165D03*
X952681Y735256D03*
X956323Y748412D03*
X957474Y764426D03*
X955086Y779798D03*
X956051Y793937D03*
X947735Y824921D03*
X948935Y835800D03*
X954700Y842700D03*
X947735Y854935D03*
X953091Y857440D03*
X953217Y861440D03*
X955967Y860376D03*
X946700Y849200D03*
X950251Y874268D03*
X950291Y870240D03*
Y866240D03*
X953145Y874240D03*
X952738Y886624D03*
X953587Y902814D03*
X961479Y927643D03*
X957671Y991564D03*
X946642Y991361D03*
X961033Y1091391D03*
X948883Y1102760D03*
X948867Y1098724D03*
X955032Y1095407D03*
X961033Y1095984D03*
X957167Y1208069D03*
X958864Y1227209D03*
X949970Y1321749D03*
X952070Y1367717D03*
X949070D03*
X956238Y1455139D03*
Y1458139D03*
Y1461139D03*
Y1464139D03*
X952676Y1461039D03*
Y1464039D03*
Y1458039D03*
Y1455039D03*
X956238Y1467139D03*
Y1469902D03*
X952676Y1467039D03*
X946470Y1510528D03*
Y1505328D03*
X947094Y1545353D03*
Y1542353D03*
X951457Y1639797D03*
X963177Y92849D03*
X970137Y103037D03*
X970271Y116496D03*
Y109410D03*
Y130670D03*
Y123583D03*
X966347Y137756D03*
X974952Y293796D03*
X972452D03*
X972147Y323681D03*
X975932Y437508D03*
X971932D03*
X962769Y458466D03*
X973695Y448874D03*
X969109Y449352D03*
X978723Y504699D03*
X976223D03*
X973723D03*
X978425Y516979D03*
X973425D03*
X975925D03*
X967302Y627948D03*
X969491Y629362D03*
X963187Y667620D03*
X973138Y667621D03*
X978059Y747438D03*
X976764Y786563D03*
X964070Y807686D03*
Y813006D03*
X977218Y802178D03*
X964036Y818961D03*
X968319Y826191D03*
X976635Y835018D03*
X976800Y838011D03*
X974282D03*
X976902Y847135D03*
X971808Y851242D03*
X975925Y854783D03*
X978201Y897500D03*
X969806Y993033D03*
X965716Y1091346D03*
X965671Y1095940D03*
X967148Y1123803D03*
X969748D03*
X969648Y1114103D03*
X967048D03*
X972348Y1123803D03*
X975048D03*
X972248Y1114103D03*
X974948D03*
X970485Y1132870D03*
X967885D03*
X968874Y1145169D03*
X966374D03*
X965917Y1236799D03*
Y1229899D03*
Y1232399D03*
Y1246199D03*
Y1243699D03*
Y1239299D03*
X978727Y1284908D03*
X971467Y1509515D03*
X974067D03*
X972567Y1512115D03*
X969967D03*
X976667Y1509515D03*
X977767Y1506915D03*
X975167D03*
X969967D03*
X972567D03*
X975167Y1512115D03*
X977767D03*
X971140Y1514693D03*
X968540D03*
X973740D03*
X976340D03*
X971457Y1639797D03*
X983554Y94017D03*
X987554D03*
X991554D03*
X987682Y115401D03*
X992674D03*
Y110445D03*
X987682D03*
X992674Y124618D03*
X987682D03*
Y129574D03*
X992674D03*
X985595Y151540D03*
X989245Y191941D03*
X989112Y188727D03*
X983069Y226141D03*
X985869D03*
X990939Y256535D03*
X985766Y288190D03*
X982966D03*
X985766Y285690D03*
X982966D03*
X980466Y288190D03*
Y285690D03*
X993992Y290755D03*
X989992D03*
X979932Y437508D03*
X982792Y447269D03*
X982670Y450201D03*
X989936Y519531D03*
X987436D03*
X982436D03*
X984936D03*
X983843Y633205D03*
Y636005D03*
Y638805D03*
X984307Y748432D03*
X985030Y781204D03*
X988329Y781445D03*
X991990Y773974D03*
X984963Y785387D03*
X979313Y814316D03*
X987903Y818645D03*
X993061Y833135D03*
X979203Y837159D03*
X988820Y858903D03*
X980529Y879097D03*
X988231Y878203D03*
X984892Y868720D03*
X987790Y896596D03*
X995133Y888503D03*
X982787Y899757D03*
X988461Y1013841D03*
X980726Y1080659D03*
Y1088659D03*
X981087Y1101902D03*
X988389Y1302558D03*
X980501Y1369685D03*
X983501D03*
X979538Y1464039D03*
Y1461039D03*
Y1458039D03*
Y1455039D03*
Y1467039D03*
Y1469802D03*
X979267Y1509515D03*
X984467D03*
X981867D03*
X985567Y1512115D03*
Y1506915D03*
X980367D03*
X982967D03*
Y1512115D03*
X980367D03*
X989667Y1509515D03*
X992267D03*
X987067D03*
X988167Y1512115D03*
X990767D03*
Y1506915D03*
X988167D03*
X984140Y1514693D03*
X981540D03*
X978940D03*
X986740D03*
X989340D03*
X991457Y1639797D03*
X1005256Y-25113D03*
X1002003Y-25027D03*
X1005241Y-27628D03*
X1001988Y-27542D03*
X1008281Y-26433D03*
X1000631Y84140D03*
Y76140D03*
Y80140D03*
X995563Y94017D03*
X1003076Y117557D03*
X998084D03*
X1003076Y122513D03*
Y131731D03*
X998084Y122513D03*
Y131731D03*
X1001175Y146461D03*
X1003076Y136687D03*
X998084D03*
X1000077Y152367D03*
X1001777Y180572D03*
X1006460Y180527D03*
X1010183Y192421D03*
X1001777Y185165D03*
X1006415Y185121D03*
X995745Y184619D03*
X997725Y206760D03*
X998939Y256535D03*
X999826Y278734D03*
X1004061Y280808D03*
X997992Y290755D03*
X1004544Y318050D03*
X1004933Y314535D03*
X997921Y333654D03*
X995913Y633450D03*
Y636250D03*
Y639050D03*
X1008342Y761735D03*
X1003539Y762632D03*
X1002834Y777394D03*
X1006053Y787745D03*
X999825Y819488D03*
X1002887Y834342D03*
X1000369D03*
X1005607Y874859D03*
Y877859D03*
X1002930Y906785D03*
X1010009Y998100D03*
X1005301Y1006560D03*
X999700Y1018400D03*
X1008312Y1363533D03*
X1008452Y1376752D03*
X1008483Y1372734D03*
X1006211Y1397662D03*
X1009338Y1391597D03*
Y1388597D03*
X1002538Y1463939D03*
Y1460939D03*
Y1457939D03*
Y1454939D03*
Y1466939D03*
Y1469702D03*
X1008549Y1509815D03*
X1007049Y1507215D03*
X1011149Y1509815D03*
X1009649Y1507215D03*
Y1512415D03*
X1007049D03*
X1008222Y1514993D03*
X1005622D03*
X1010822D03*
X1023373Y60922D03*
X1018209Y55513D03*
X1020254Y97068D03*
X1014006Y117261D03*
X1021537Y113394D03*
X1024186Y110784D03*
X1024289Y130898D03*
X1025927Y134579D03*
X1021713Y180665D03*
Y172665D03*
X1026915Y203393D03*
X1021745Y212864D03*
Y200864D03*
Y221864D03*
Y216864D03*
X1023502Y252371D03*
X1013354Y323362D03*
X1013327Y327453D03*
X1013318Y333190D03*
X1022845Y340944D03*
X1013313Y339909D03*
X1015195Y428305D03*
X1015804Y760454D03*
X1026090Y770943D03*
X1019375Y783056D03*
X1018044Y793592D03*
X1015800Y807535D03*
X1014587Y802788D03*
X1025859Y802275D03*
X1020703Y833659D03*
X1021221Y848712D03*
X1025219Y842155D03*
X1025239Y845070D03*
X1022009Y997860D03*
X1018009D03*
X1026009D03*
X1014009D03*
X1014767Y1035088D03*
X1022594Y1035114D03*
X1017297Y1102091D03*
X1026606Y1102591D03*
X1023106Y1102091D03*
X1017297Y1114691D03*
X1023106D03*
X1026606D03*
X1023106Y1127291D03*
X1026606D03*
X1017297Y1139891D03*
X1023106D03*
X1026606D03*
X1017297Y1127291D03*
X1026606Y1152491D03*
X1017297D03*
X1023106D03*
X1017297Y1165091D03*
X1023106D03*
X1026606D03*
X1017297Y1177691D03*
X1023106D03*
X1026606D03*
X1022420Y1203204D03*
X1026968Y1223749D03*
X1025434Y1320606D03*
X1011829Y1347471D03*
Y1342515D03*
X1015286Y1344924D03*
X1021623Y1373216D03*
X1012338Y1388597D03*
Y1391597D03*
X1015338D03*
Y1388597D03*
X1021338D03*
Y1391597D03*
X1018338D03*
Y1388597D03*
X1027338D03*
Y1391597D03*
X1024338D03*
Y1388597D03*
X1025138Y1463839D03*
Y1460839D03*
Y1457839D03*
Y1454839D03*
Y1466839D03*
Y1469602D03*
X1013749Y1509815D03*
X1016349D03*
X1021549D03*
X1018949D03*
X1024149D03*
X1022649Y1507215D03*
X1025249D03*
X1017449D03*
X1020049D03*
X1014849D03*
X1012249D03*
X1026749Y1509815D03*
X1012249Y1512415D03*
X1014849D03*
X1025249D03*
X1022649D03*
X1020049D03*
X1017449D03*
X1013422Y1514993D03*
X1023822D03*
X1021222D03*
X1018622D03*
X1016022D03*
X1026422D03*
X1011457Y1639797D03*
X1036772Y109172D03*
X1039772D03*
X1038779Y106495D03*
X1042523Y116497D03*
X1031780Y133298D03*
X1042523Y130670D03*
Y123584D03*
X1038513Y146012D03*
X1040419Y141228D03*
X1042523Y137757D03*
X1043307Y150847D03*
X1037984Y253198D03*
X1031354Y325901D03*
X1031382Y340947D03*
X1031310Y337888D03*
X1031377Y333671D03*
X1031362Y329268D03*
X1038796Y763272D03*
X1042880Y794924D03*
X1028155Y879413D03*
X1030300Y881400D03*
X1043252Y902501D03*
X1030009Y997860D03*
X1034009D03*
X1038252Y1009354D03*
X1034752D03*
X1028943D03*
X1042009Y997860D03*
X1038009D03*
X1034752Y1021954D03*
X1038252D03*
X1043553Y1035384D03*
X1040600Y1210600D03*
X1035384Y1215195D03*
X1034513Y1333665D03*
X1042586Y1345824D03*
X1030338Y1391597D03*
Y1388597D03*
X1029349Y1509815D03*
X1027849Y1507215D03*
Y1512415D03*
X1031457Y1639797D03*
X1049823Y109410D03*
X1054523Y116496D03*
Y109410D03*
Y102323D03*
X1049823Y116497D03*
X1047323D03*
X1049823Y130670D03*
X1047323D03*
Y123584D03*
X1049823Y123583D03*
X1054523Y130670D03*
Y123583D03*
Y137756D03*
X1047323Y137757D03*
X1045275Y247292D03*
X1050777Y450750D03*
X1054876Y536382D03*
X1059843Y597580D03*
X1059782Y594668D03*
X1062098Y615600D03*
X1044112Y778835D03*
X1045744Y800835D03*
X1048328Y808166D03*
X1057961Y931919D03*
X1046009Y997860D03*
X1054009D03*
X1050009D03*
X1058009D03*
X1059689Y1012354D03*
Y1024954D03*
X1048043Y1105091D03*
Y1117691D03*
Y1130291D03*
Y1155491D03*
Y1142891D03*
Y1168091D03*
Y1180691D03*
X1051249Y1290288D03*
X1052221Y1336984D03*
X1058891Y1345691D03*
Y1350683D03*
X1053935Y1345691D03*
Y1350683D03*
X1058891Y1362595D03*
X1053935D03*
X1058891Y1357603D03*
X1053935D03*
X1058891Y1381801D03*
Y1374881D03*
Y1369889D03*
X1053935Y1381801D03*
Y1374881D03*
Y1369889D03*
X1058891Y1386793D03*
X1053935D03*
X1051457Y1639797D03*
X1071988Y-66722D03*
X1075241Y-66808D03*
X1072003Y-64207D03*
X1075256Y-64293D03*
X1062985Y82984D03*
Y75184D03*
Y77784D03*
Y80384D03*
X1065539Y92849D03*
X1062985Y85584D03*
X1072499Y103037D03*
X1072633Y116496D03*
Y109410D03*
Y130670D03*
Y123583D03*
X1069224Y137756D03*
X1074814Y293796D03*
X1061325Y339509D03*
X1060679Y360151D03*
Y364276D03*
X1071548Y555234D03*
X1071263Y562003D03*
X1062066Y599588D03*
X1061328Y589556D03*
X1061267Y592354D03*
X1062069Y596095D03*
X1062066Y607588D03*
X1066559Y634946D03*
X1066009Y997860D03*
X1062009D03*
X1074009D03*
X1070778Y1012252D03*
X1066933Y1040567D03*
X1071641Y1058029D03*
X1060172Y1050481D03*
X1071348Y1050503D03*
X1066175Y1350683D03*
Y1345691D03*
X1071131Y1350683D03*
Y1345691D03*
X1066175Y1357603D03*
Y1362595D03*
X1071131Y1357603D03*
Y1362595D03*
X1066175Y1381801D03*
Y1369795D03*
Y1374881D03*
X1071131Y1381801D03*
Y1369795D03*
Y1374881D03*
X1066175Y1393993D03*
Y1399079D03*
Y1386793D03*
X1071131Y1399079D03*
Y1393993D03*
Y1386793D03*
X1066175Y1405999D03*
Y1410991D03*
X1071131Y1405999D03*
Y1410991D03*
X1071457Y1639797D03*
X1078281Y-65613D03*
X1089916Y94017D03*
X1085916D03*
X1090044Y110445D03*
Y115401D03*
Y124618D03*
Y129574D03*
X1087957Y151540D03*
X1091607Y191941D03*
X1091474Y188727D03*
X1085431Y226141D03*
X1088231D03*
X1088128Y285690D03*
Y288190D03*
X1085328D03*
X1082828Y285690D03*
X1085328D03*
X1082828Y288190D03*
X1077314Y293796D03*
X1092354Y290755D03*
X1077602Y314060D03*
X1091542Y389154D03*
Y410413D03*
Y396240D03*
Y403327D03*
Y417500D03*
Y424587D03*
Y431673D03*
Y438760D03*
Y445847D03*
Y467539D03*
Y474626D03*
Y488799D03*
Y481713D03*
Y495886D03*
Y511673D03*
Y518760D03*
Y525847D03*
Y532933D03*
Y540020D03*
Y547106D03*
X1090823Y602197D03*
X1091287Y595108D03*
X1079809Y1034386D03*
X1090655Y1350683D03*
Y1345691D03*
X1083371D03*
Y1350683D03*
X1078415Y1345691D03*
Y1350683D03*
X1090655Y1357603D03*
Y1362595D03*
X1083371Y1357603D03*
Y1362595D03*
X1078415D03*
Y1357603D03*
X1090655Y1381801D03*
Y1374881D03*
Y1369889D03*
X1083371D03*
Y1374881D03*
Y1381801D03*
X1078415Y1369889D03*
Y1374881D03*
Y1381801D03*
X1090655Y1394087D03*
Y1399079D03*
Y1386793D03*
X1083371D03*
Y1399079D03*
Y1394087D03*
X1078415Y1386793D03*
Y1394087D03*
Y1399079D03*
X1090655Y1405999D03*
Y1410991D03*
X1083371Y1405999D03*
Y1410991D03*
X1078415Y1405999D03*
Y1410991D03*
X1092000Y1644980D03*
X1102993Y84140D03*
Y76140D03*
Y80140D03*
X1097925Y94017D03*
X1093916D03*
X1100446Y117557D03*
X1095036Y115401D03*
Y110445D03*
X1105438Y117557D03*
X1095036Y129574D03*
Y124618D03*
X1105438Y131731D03*
Y122513D03*
X1100446Y131731D03*
Y122513D03*
X1103537Y146461D03*
X1100446Y136687D03*
X1105438D03*
X1102439Y152367D03*
X1104139Y180572D03*
X1108822Y180527D03*
X1104139Y185165D03*
X1108777Y185121D03*
X1098107Y184619D03*
X1100087Y206760D03*
X1101301Y256535D03*
X1093301D03*
X1102331Y279208D03*
X1106435Y281307D03*
X1096354Y290755D03*
X1100354D03*
X1100703Y340560D03*
X1101999Y353495D03*
X1093994Y374003D03*
X1106161Y389154D03*
X1104691Y396240D03*
X1108776Y422864D03*
X1108846Y429832D03*
X1108451Y436447D03*
X1108395Y472772D03*
X1105002Y516841D03*
X1108253Y510565D03*
X1099949Y550123D03*
X1099827Y552872D03*
X1101581Y572334D03*
X1099272Y562443D03*
X1101040Y560675D03*
X1099813Y574102D03*
X1104448Y653161D03*
X1108045Y677843D03*
X1107851Y1345691D03*
X1102895Y1350683D03*
Y1345691D03*
X1107851Y1350683D03*
X1095611D03*
Y1345691D03*
X1107851Y1357603D03*
X1102895Y1362595D03*
Y1357603D03*
X1107851Y1362595D03*
X1095611Y1357603D03*
Y1362595D03*
X1107851Y1369889D03*
Y1374881D03*
Y1381801D03*
X1102895Y1374881D03*
Y1369889D03*
Y1381801D03*
X1095611D03*
Y1374881D03*
Y1369889D03*
X1107851Y1386793D03*
Y1394087D03*
Y1399079D03*
X1102895Y1386793D03*
Y1394087D03*
Y1399079D03*
X1095611D03*
Y1394087D03*
Y1386793D03*
X1107851Y1405999D03*
Y1410991D03*
X1102895Y1405999D03*
Y1410991D03*
X1095611Y1405999D03*
Y1410991D03*
X1099900Y1535700D03*
X1107620Y1606752D03*
X1123052Y57511D03*
X1122613Y97042D03*
X1116368Y117261D03*
X1123899Y113394D03*
X1124075Y180665D03*
Y172665D03*
X1112545Y192421D03*
X1124107Y200864D03*
Y212864D03*
Y216864D03*
Y221864D03*
X1123500Y329000D03*
Y339000D03*
Y334000D03*
X1124753Y389153D03*
X1122253Y396240D03*
X1124753D03*
X1122253Y403327D03*
X1124753Y403326D03*
X1122253Y410413D03*
X1124753D03*
X1109468Y414823D03*
X1122253Y424586D03*
X1124753D03*
X1122253Y417500D03*
X1124753Y417499D03*
X1122253Y438760D03*
X1124753D03*
Y431673D03*
X1122253D03*
X1110486Y447953D03*
X1122253Y445847D03*
X1109653Y467539D03*
X1124753D03*
X1122253Y474626D03*
X1124753D03*
X1122253Y488799D03*
X1124753D03*
X1109129Y487711D03*
X1109242Y479104D03*
X1124753Y481712D03*
X1122253D03*
Y495886D03*
X1109653D03*
X1124753Y518760D03*
X1122253D03*
X1124753Y511673D03*
Y532933D03*
X1122253D03*
Y540020D03*
Y525846D03*
X1124753D03*
X1118863Y662981D03*
X1112839Y668885D03*
X1113244Y691851D03*
X1118855Y705043D03*
X1115135Y1345691D03*
Y1350683D03*
X1120091Y1345691D03*
Y1350683D03*
X1115135Y1357603D03*
Y1362595D03*
X1120091Y1357603D03*
Y1362595D03*
X1115135Y1374881D03*
Y1381801D03*
Y1369889D03*
X1120091D03*
Y1374881D03*
Y1381801D03*
X1115135Y1394087D03*
Y1399079D03*
Y1386793D03*
X1120091Y1399079D03*
Y1394087D03*
Y1386793D03*
X1115135Y1405999D03*
Y1410991D03*
X1120091Y1405999D03*
Y1410991D03*
X1112000Y1644980D03*
X1125735Y60922D03*
X1139134Y109172D03*
X1141141Y106495D03*
X1126548Y110784D03*
X1134142Y133298D03*
X1126142D03*
X1140875Y146012D03*
X1128289Y134579D03*
X1129277Y203393D03*
X1140346Y253198D03*
X1125864Y252371D03*
X1129553Y389153D03*
Y396240D03*
Y403326D03*
Y410413D03*
Y424586D03*
Y417499D03*
Y431673D03*
Y438760D03*
X1126931Y453564D03*
X1130355Y453483D03*
X1129553Y467539D03*
X1125178Y459792D03*
X1129553Y474626D03*
Y488799D03*
Y481712D03*
Y518760D03*
Y511673D03*
Y532933D03*
Y525846D03*
X1138098Y543925D03*
X1138673Y555000D03*
X1126633Y560500D03*
X1139615Y1350683D03*
Y1345691D03*
X1132331D03*
Y1350683D03*
X1127375D03*
Y1345691D03*
X1139615Y1357603D03*
Y1362595D03*
X1132331D03*
Y1357603D03*
X1127375D03*
Y1362595D03*
X1139615Y1374881D03*
Y1369889D03*
Y1381801D03*
X1132331Y1369889D03*
Y1381801D03*
Y1374881D03*
X1127375Y1369889D03*
Y1381801D03*
Y1374881D03*
X1139615Y1394087D03*
Y1399079D03*
Y1386793D03*
X1132331D03*
Y1394087D03*
Y1399079D03*
X1127375Y1386793D03*
Y1394087D03*
Y1399079D03*
X1139615Y1405999D03*
Y1410991D03*
X1132331Y1405999D03*
Y1410991D03*
X1127375Y1405999D03*
Y1410991D03*
X1129637Y1465913D03*
Y1461182D03*
Y1456451D03*
X1138298Y1465513D03*
Y1460782D03*
X1129637Y1476536D03*
Y1481267D03*
X1138298Y1476136D03*
Y1470244D03*
Y1480867D03*
X1129637Y1471805D03*
Y1496621D03*
X1138298Y1491490D03*
Y1485598D03*
Y1496221D03*
X1129637Y1491890D03*
Y1487159D03*
X1138298Y1500952D03*
Y1511576D03*
X1129637Y1507245D03*
Y1502514D03*
Y1511976D03*
X1138298Y1506845D03*
Y1516307D03*
X1129637Y1563544D03*
Y1558813D03*
X1138298Y1563144D03*
Y1572606D03*
X1129637Y1568275D03*
Y1578898D03*
Y1574167D03*
X1138298Y1567875D03*
Y1578498D03*
X1129637Y1583629D03*
Y1594253D03*
Y1589522D03*
X1138298Y1583229D03*
Y1593853D03*
Y1587960D03*
Y1598584D03*
Y1603315D03*
X1129637Y1609607D03*
Y1598984D03*
Y1604876D03*
X1138298Y1609207D03*
X1129637Y1614338D03*
X1138298Y1613938D03*
Y1618669D03*
X1132000Y1644980D03*
X1142134Y109172D03*
X1156885Y116496D03*
Y102323D03*
Y109410D03*
X1152185D03*
Y116497D03*
X1149685D03*
X1144885D03*
X1152185Y130670D03*
X1149685D03*
Y123584D03*
X1152185Y123583D03*
X1144885Y130670D03*
Y123584D03*
X1156885Y130670D03*
Y123583D03*
X1142781Y141228D03*
X1156885Y137756D03*
X1149685Y137757D03*
X1144885D03*
X1145669Y150847D03*
X1147637Y247292D03*
X1145761Y324148D03*
X1157251Y636842D03*
X1156023Y678462D03*
X1149345Y771517D03*
X1145910Y794217D03*
X1151277Y790996D03*
X1149627Y813323D03*
X1146985Y812642D03*
X1152510Y844642D03*
X1156811Y1350683D03*
Y1345691D03*
X1151855D03*
Y1350683D03*
X1144571D03*
Y1345691D03*
X1156811Y1357603D03*
Y1362595D03*
X1151855D03*
Y1357603D03*
X1144571D03*
Y1362595D03*
X1156811Y1374881D03*
Y1369889D03*
Y1381801D03*
X1151855Y1374881D03*
Y1369889D03*
Y1381801D03*
X1144571Y1369889D03*
Y1381801D03*
Y1374881D03*
X1156811Y1386793D03*
Y1399079D03*
Y1394087D03*
X1151855Y1386793D03*
Y1399079D03*
Y1394087D03*
X1144571D03*
Y1399079D03*
Y1386793D03*
X1156811Y1405999D03*
Y1410991D03*
X1151855Y1405999D03*
Y1410991D03*
X1144571Y1405999D03*
Y1410991D03*
X1146960Y1465913D03*
Y1461182D03*
X1155621Y1465513D03*
Y1460782D03*
X1146960Y1456451D03*
X1155621Y1480867D03*
X1146960Y1471805D03*
Y1476536D03*
Y1481267D03*
X1155621Y1476136D03*
Y1470244D03*
Y1491490D03*
Y1485598D03*
Y1496221D03*
X1146960Y1487159D03*
Y1491890D03*
Y1496621D03*
Y1507245D03*
Y1502514D03*
X1155621Y1506845D03*
Y1500952D03*
Y1511576D03*
X1146960Y1511976D03*
X1155621Y1516307D03*
X1146960Y1563544D03*
X1155621Y1563144D03*
X1146960Y1558813D03*
X1155621Y1572606D03*
X1146960Y1568275D03*
X1155621Y1567875D03*
X1146960Y1574167D03*
Y1578898D03*
X1155621Y1578498D03*
X1146960Y1594253D03*
X1155621Y1593853D03*
Y1587960D03*
X1146960Y1583629D03*
X1155621Y1583229D03*
X1146960Y1589522D03*
Y1609607D03*
Y1604876D03*
Y1598984D03*
X1155621Y1609207D03*
Y1598584D03*
Y1603315D03*
X1146960Y1614338D03*
X1155621Y1613938D03*
Y1618669D03*
X1152000Y1644980D03*
X1165347Y82984D03*
Y75184D03*
Y77784D03*
Y80384D03*
X1167756Y92734D03*
X1165347Y85584D03*
X1171586Y137756D03*
X1168902Y431029D03*
X1167931Y435029D03*
X1169173Y427017D03*
X1168851Y449873D03*
X1171255Y456287D03*
X1173278Y472579D03*
X1168478D03*
X1173278Y479666D03*
X1168478D03*
Y486752D03*
X1173278D03*
X1168478Y493839D03*
X1173278D03*
X1168478Y523800D03*
Y516713D03*
X1173278D03*
Y523800D03*
Y537973D03*
X1168478D03*
X1173278Y530886D03*
X1168478D03*
X1173278Y566752D03*
X1168478D03*
Y580926D03*
X1173278D03*
Y588013D03*
X1168478D03*
X1173278Y573839D03*
X1168478D03*
Y602186D03*
X1173278D03*
Y595099D03*
X1168478D03*
X1173278Y609272D03*
X1168478D03*
Y616359D03*
X1173278D03*
X1163157Y638125D03*
X1160756Y665140D03*
X1157985Y791142D03*
X1161291Y791662D03*
X1173697Y791911D03*
X1160516Y800900D03*
X1169051Y1345597D03*
Y1350683D03*
X1164095D03*
Y1345597D03*
X1169051Y1357603D03*
Y1362595D03*
X1164095Y1357603D03*
Y1362595D03*
X1169051Y1381801D03*
Y1374881D03*
Y1369889D03*
X1164095D03*
Y1381801D03*
Y1374881D03*
X1169051Y1393993D03*
Y1399079D03*
Y1386793D03*
X1164095Y1393993D03*
Y1399079D03*
Y1386793D03*
X1169051Y1410991D03*
Y1405999D03*
X1164095D03*
Y1410991D03*
X1164283Y1465913D03*
Y1456451D03*
Y1461182D03*
X1172944Y1465513D03*
Y1460782D03*
Y1470244D03*
Y1480867D03*
X1164283Y1471805D03*
Y1476536D03*
Y1481267D03*
X1172944Y1476136D03*
X1164283Y1487159D03*
Y1491890D03*
Y1496621D03*
X1172944Y1491490D03*
Y1485598D03*
Y1496221D03*
X1164283Y1507245D03*
Y1502514D03*
X1172944Y1506845D03*
Y1500952D03*
Y1511576D03*
X1164283Y1511976D03*
X1172944Y1516307D03*
X1164283Y1558813D03*
Y1563544D03*
X1172944Y1563144D03*
Y1567875D03*
X1164283Y1574167D03*
Y1578898D03*
X1172944Y1578498D03*
Y1572606D03*
X1164283Y1568275D03*
Y1583629D03*
X1172944Y1583229D03*
X1164283Y1589522D03*
Y1594253D03*
X1172944Y1593853D03*
Y1587960D03*
Y1598584D03*
Y1603315D03*
X1164283Y1609607D03*
Y1604876D03*
Y1598984D03*
X1172944Y1609207D03*
X1164283Y1614338D03*
X1172944Y1613938D03*
Y1618669D03*
X1172000Y1644980D03*
X1188278Y94017D03*
X1174861Y103037D03*
X1174995Y116496D03*
Y109410D03*
Y130670D03*
Y123583D03*
X1187793Y226141D03*
X1190593D03*
X1179676Y293796D03*
X1187690Y288190D03*
X1185190Y285690D03*
X1187690D03*
X1185190Y288190D03*
X1177176Y293796D03*
X1182911Y336516D03*
X1177036Y334148D03*
X1188598Y390500D03*
X1179184Y410394D03*
Y403307D03*
X1180578Y458406D03*
Y451319D03*
X1180402Y462264D03*
X1175778Y465492D03*
X1180578D03*
X1175778Y472579D03*
X1180578D03*
X1175778Y479666D03*
X1180578Y479665D03*
Y486752D03*
X1175778D03*
X1180578Y493839D03*
X1175778Y509626D03*
X1180578Y523799D03*
Y516713D03*
Y509626D03*
X1175778Y516713D03*
Y523800D03*
X1180578Y537973D03*
X1175778Y530886D03*
X1180578D03*
Y559665D03*
Y566752D03*
X1175778D03*
Y559665D03*
Y580926D03*
X1180578D03*
Y588012D03*
X1175778D03*
X1180578Y573839D03*
X1175778D03*
Y602185D03*
X1180578D03*
X1175778Y595099D03*
X1180578D03*
X1175778Y609272D03*
X1180578Y616358D03*
Y609272D03*
X1177745Y771744D03*
X1177566Y778539D03*
X1190062Y844378D03*
X1187703Y849734D03*
X1186742Y855466D03*
X1183431Y868340D03*
X1177775Y894053D03*
X1178480Y915220D03*
X1178000Y936500D03*
X1187200Y963400D03*
X1181291Y1350683D03*
Y1345691D03*
X1176335D03*
Y1350683D03*
X1181291Y1362595D03*
Y1357603D03*
X1176335Y1362595D03*
Y1357603D03*
X1181291Y1369889D03*
Y1381801D03*
Y1374881D03*
X1176335Y1369889D03*
Y1381801D03*
Y1374881D03*
X1181291Y1386793D03*
Y1399079D03*
Y1394087D03*
X1176335Y1386793D03*
Y1399079D03*
Y1394087D03*
X1181291Y1405999D03*
Y1410991D03*
X1176335Y1405999D03*
Y1410991D03*
X1181605Y1465913D03*
Y1456451D03*
Y1461182D03*
Y1471805D03*
Y1476536D03*
Y1481267D03*
Y1487159D03*
Y1491890D03*
Y1496621D03*
Y1507245D03*
Y1502514D03*
Y1511976D03*
Y1558813D03*
Y1563544D03*
Y1568275D03*
Y1574167D03*
Y1578898D03*
Y1583629D03*
Y1589522D03*
Y1594253D03*
Y1598984D03*
Y1609607D03*
Y1604876D03*
Y1614338D03*
X1205355Y84140D03*
Y76140D03*
Y80140D03*
X1196278Y94017D03*
X1200287D03*
X1192278D03*
X1202808Y117557D03*
X1197398Y110445D03*
Y115401D03*
X1192406Y110445D03*
Y115401D03*
X1197398Y129574D03*
Y124618D03*
X1192406D03*
Y129574D03*
X1202808Y122513D03*
Y131731D03*
X1205899Y146461D03*
X1202808Y136687D03*
X1204801Y152367D03*
X1190319Y151540D03*
X1200469Y184619D03*
X1193969Y191941D03*
X1193836Y188727D03*
X1202449Y206760D03*
X1203663Y256535D03*
X1195663D03*
X1204693Y279208D03*
X1194716Y290755D03*
X1202716D03*
X1190490Y285690D03*
Y288190D03*
X1198716Y290755D03*
X1198248Y381500D03*
X1198689Y465492D03*
X1198655Y460250D03*
X1196420Y470136D03*
X1198689Y472579D03*
Y486752D03*
Y479665D03*
Y493839D03*
Y509626D03*
Y516713D03*
X1195149Y537973D03*
X1197629Y525483D03*
X1197550Y532756D03*
X1198689Y559665D03*
Y566752D03*
X1198539Y579978D03*
X1198689Y573839D03*
X1198753Y608117D03*
X1198997Y790610D03*
X1198845Y998504D03*
X1204919Y1021860D03*
X1202268Y1013551D03*
X1190267Y1465513D03*
Y1460782D03*
X1198928Y1465914D03*
Y1456452D03*
Y1461183D03*
Y1481268D03*
X1190267Y1476136D03*
Y1470244D03*
Y1480867D03*
X1198928Y1476537D03*
Y1471806D03*
X1190267Y1485598D03*
Y1496221D03*
X1198928Y1491891D03*
Y1487160D03*
Y1496622D03*
X1190267Y1491490D03*
Y1506845D03*
Y1500952D03*
Y1511576D03*
X1198928Y1507246D03*
Y1502515D03*
Y1511977D03*
X1190267Y1516307D03*
X1198928Y1558813D03*
X1190267Y1563144D03*
X1198928Y1563544D03*
X1190267Y1567875D03*
X1198928Y1568275D03*
X1190267Y1578498D03*
Y1572606D03*
X1198928Y1578898D03*
Y1574167D03*
X1190267Y1583229D03*
X1198928Y1583629D03*
X1190267Y1593853D03*
Y1587960D03*
X1198928Y1594253D03*
Y1589522D03*
X1190267Y1609207D03*
Y1598584D03*
Y1603315D03*
X1198928Y1609607D03*
Y1598984D03*
Y1604876D03*
X1190267Y1613938D03*
Y1618669D03*
X1198928Y1614338D03*
X1192000Y1644980D03*
X1218730Y117261D03*
X1207800Y117557D03*
Y122513D03*
Y131731D03*
Y136687D03*
X1206501Y180572D03*
X1211184Y180527D03*
X1214907Y192421D03*
X1206501Y185165D03*
X1211139Y185121D03*
X1208797Y281307D03*
X1220985Y342319D03*
X1212680Y445908D03*
X1216630Y445787D03*
X1212000Y1644980D03*
X1222933Y55513D03*
X1228097Y60922D03*
X1225041Y97080D03*
X1228910Y110784D03*
X1226261Y113394D03*
X1229195Y130898D03*
X1236504Y133298D03*
X1230651Y134579D03*
X1226437Y180665D03*
Y172665D03*
X1226469Y200864D03*
Y212864D03*
Y216864D03*
Y221864D03*
X1228226Y252371D03*
X1238055Y303839D03*
X1230077Y336324D03*
X1234656Y353506D03*
X1223431Y393924D03*
Y389912D03*
Y385912D03*
Y409924D03*
Y405924D03*
Y401924D03*
X1229548Y1350683D03*
Y1345691D03*
X1234504D03*
Y1350683D03*
X1229548Y1362595D03*
Y1357603D03*
X1234504D03*
Y1362595D03*
X1229548Y1369889D03*
Y1374881D03*
Y1381801D03*
X1234504Y1369889D03*
Y1374881D03*
Y1381801D03*
X1229548Y1386793D03*
X1234504D03*
X1232000Y1644980D03*
X1243503Y106495D03*
X1244496Y109172D03*
X1241496D03*
X1247247Y116497D03*
X1254547Y109410D03*
Y116497D03*
X1252047D03*
X1247247Y123584D03*
Y130670D03*
X1252047Y123584D03*
X1254547Y123583D03*
Y130670D03*
X1252047D03*
X1243237Y146012D03*
X1245143Y141228D03*
X1247247Y137757D03*
X1252047D03*
X1250307Y140296D03*
X1248031Y150847D03*
X1249999Y247292D03*
X1242708Y253198D03*
X1248064Y567813D03*
Y572769D03*
Y581987D03*
Y586943D03*
Y601116D03*
Y596160D03*
Y615289D03*
Y610333D03*
X1246800Y1001600D03*
X1249200Y1014000D03*
X1248721Y1025864D03*
X1251802Y1186071D03*
X1254028Y1350683D03*
Y1345691D03*
X1241788D03*
Y1350683D03*
X1246744Y1345691D03*
Y1350683D03*
X1254028Y1357603D03*
Y1362595D03*
X1241788D03*
Y1357603D03*
X1246744Y1362595D03*
Y1357603D03*
X1254028Y1381801D03*
Y1374881D03*
Y1369889D03*
X1241788Y1374881D03*
Y1369795D03*
Y1381801D03*
X1246744Y1374881D03*
Y1369795D03*
Y1381801D03*
X1254028Y1386793D03*
Y1399079D03*
Y1394087D03*
X1241788Y1399079D03*
Y1393993D03*
Y1386793D03*
X1246744Y1393993D03*
Y1399079D03*
Y1386793D03*
X1254028Y1410991D03*
Y1405999D03*
X1241788Y1410991D03*
Y1405999D03*
X1246744Y1410991D03*
Y1405999D03*
X1245900Y1528000D03*
X1267709Y82984D03*
Y75184D03*
Y77784D03*
Y80384D03*
X1270263Y92849D03*
X1267709Y85584D03*
X1259247Y116496D03*
Y102323D03*
Y109410D03*
Y130670D03*
Y123583D03*
Y137756D03*
X1258925Y324075D03*
X1270951Y491870D03*
X1270515Y908277D03*
X1269876Y1132319D03*
X1263873Y1148000D03*
X1266709Y1160168D03*
X1258736Y1188223D03*
X1268573Y1193019D03*
X1264573D03*
X1266268Y1345691D03*
Y1350683D03*
X1258984D03*
Y1345691D03*
X1266268Y1362595D03*
Y1357603D03*
X1258984Y1362595D03*
Y1357603D03*
X1266268Y1369889D03*
Y1374881D03*
Y1381801D03*
X1258984D03*
Y1369889D03*
Y1374881D03*
X1266268Y1399079D03*
Y1394087D03*
Y1386793D03*
X1258984Y1394087D03*
Y1386793D03*
Y1399079D03*
X1266268Y1410991D03*
Y1405999D03*
X1258984D03*
Y1410991D03*
X1263242Y1523458D03*
X1262985Y1519459D03*
X1260260Y1546500D03*
X1277223Y103037D03*
X1277357Y116496D03*
Y109410D03*
Y130670D03*
Y123583D03*
X1273555Y137756D03*
X1279538Y293796D03*
X1282038D03*
X1283494Y339495D03*
X1287437Y370010D03*
X1280616Y472189D03*
X1273451Y491870D03*
X1279539Y772576D03*
Y776576D03*
X1274417Y861964D03*
X1282317Y880193D03*
X1285493Y892175D03*
X1277039Y916484D03*
X1284021Y940008D03*
X1273865Y1132497D03*
X1282830Y1146937D03*
X1272120Y1159455D03*
X1280306Y1162817D03*
X1276573Y1193019D03*
X1280573D03*
X1272573D03*
X1277108Y1211664D03*
X1279402Y1213958D03*
X1275032Y1209589D03*
X1284198Y1218754D03*
X1283464Y1345691D03*
Y1350683D03*
X1278508Y1345691D03*
Y1350683D03*
X1271224Y1345691D03*
Y1350683D03*
X1283464Y1362595D03*
Y1357603D03*
X1278508D03*
Y1362595D03*
X1271224D03*
Y1357603D03*
X1283464Y1381801D03*
Y1369889D03*
Y1374881D03*
X1278508Y1381801D03*
Y1369889D03*
Y1374881D03*
X1271224Y1369889D03*
Y1374881D03*
Y1381801D03*
X1283464Y1386793D03*
Y1399079D03*
Y1394087D03*
X1278508Y1386793D03*
Y1399079D03*
Y1394087D03*
X1271224D03*
Y1399079D03*
Y1386793D03*
X1283464Y1410991D03*
Y1405999D03*
X1278508Y1410991D03*
Y1405999D03*
X1271224Y1410991D03*
Y1405999D03*
X1291756Y-25143D03*
X1288503Y-25157D03*
X1291741Y-27658D03*
X1288488Y-27672D03*
X1294781Y-26463D03*
X1302649Y94017D03*
X1298640D03*
X1290640D03*
X1294640D03*
X1299760Y110445D03*
Y115401D03*
X1294768Y110445D03*
Y115401D03*
Y129574D03*
X1299760D03*
Y124618D03*
X1294768D03*
X1296331Y191941D03*
X1302831Y184619D03*
X1296198Y188727D03*
X1292955Y226141D03*
X1290155D03*
X1298025Y256535D03*
X1290052Y288190D03*
X1292852D03*
Y285690D03*
X1305078Y290755D03*
X1297078D03*
X1301078D03*
X1287552Y288190D03*
X1290052Y285690D03*
X1287552D03*
X1294425Y321425D03*
X1299959Y351454D03*
X1296783Y511956D03*
X1303520Y748403D03*
X1300516Y832047D03*
X1300504Y835985D03*
X1300204Y859088D03*
X1300097Y851193D03*
X1300091Y854824D03*
X1291955Y901295D03*
X1289547Y928047D03*
X1298090Y940852D03*
X1295453Y940953D03*
X1302988Y1345691D03*
Y1350683D03*
X1290748D03*
Y1345691D03*
X1295704Y1350683D03*
Y1345691D03*
X1302988Y1362595D03*
Y1357603D03*
X1290748Y1362595D03*
Y1357603D03*
X1295704Y1362595D03*
Y1357603D03*
X1302988Y1374881D03*
Y1381801D03*
Y1369889D03*
X1290748D03*
Y1381801D03*
Y1374881D03*
X1295704Y1381801D03*
Y1374881D03*
Y1369889D03*
X1302988Y1386793D03*
Y1399079D03*
Y1394087D03*
X1290748Y1399079D03*
Y1394087D03*
Y1386793D03*
X1295704Y1394087D03*
Y1399079D03*
Y1386793D03*
X1302988Y1410991D03*
Y1405999D03*
X1290748Y1410991D03*
Y1405999D03*
X1295704Y1410991D03*
Y1405999D03*
X1302866Y1461182D03*
Y1456451D03*
Y1465913D03*
Y1476536D03*
Y1471805D03*
Y1481267D03*
Y1491890D03*
Y1487159D03*
Y1496621D03*
Y1507245D03*
Y1502514D03*
Y1511976D03*
Y1558813D03*
Y1563544D03*
Y1578898D03*
Y1574167D03*
Y1568275D03*
Y1594253D03*
Y1589522D03*
Y1583629D03*
Y1609607D03*
Y1598984D03*
Y1604876D03*
Y1614338D03*
X1292000Y1644980D03*
X1307717Y84140D03*
Y76140D03*
Y80140D03*
X1310162Y117557D03*
X1305170D03*
X1310162Y122513D03*
Y131731D03*
X1305170Y122513D03*
Y131731D03*
X1310162Y136687D03*
X1305170D03*
X1313546Y180527D03*
X1308863Y180572D03*
Y185165D03*
X1317269Y192421D03*
X1313501Y185121D03*
X1304811Y206760D03*
X1306025Y256535D03*
X1307055Y279208D03*
X1311159Y281307D03*
X1314569Y318013D03*
X1312069D03*
X1317584Y313058D03*
X1316017Y349889D03*
X1308410Y370899D03*
X1313691Y402642D03*
X1316191D03*
X1309117Y398949D03*
X1306617Y401949D03*
X1308066Y413611D03*
X1310866D03*
X1313366D03*
X1315866D03*
X1315806Y423944D03*
X1313306D03*
X1310806D03*
X1308006D03*
X1307919Y478382D03*
X1307825Y482382D03*
X1305134Y812065D03*
X1313756Y829871D03*
X1308857Y836076D03*
X1316906Y842470D03*
Y867665D03*
Y883413D03*
Y892862D03*
X1316893Y925603D03*
X1318375Y943951D03*
X1303907Y960093D03*
X1307580Y990314D03*
X1304664Y1023462D03*
X1309937Y1037038D03*
X1319326Y1040723D03*
X1317437Y1152684D03*
X1307167Y1245696D03*
X1308276Y1276446D03*
X1315228Y1345691D03*
Y1350683D03*
X1307944D03*
Y1345691D03*
X1315228Y1362595D03*
Y1357603D03*
X1307944D03*
Y1362595D03*
X1315228Y1381801D03*
Y1369889D03*
Y1374881D03*
X1307944D03*
Y1381801D03*
Y1369889D03*
X1315228Y1399079D03*
Y1394087D03*
Y1386793D03*
X1307944D03*
Y1399079D03*
Y1394087D03*
X1315228Y1410991D03*
Y1405999D03*
X1307944Y1410991D03*
Y1405999D03*
X1311527Y1465513D03*
Y1460782D03*
Y1480867D03*
Y1476136D03*
Y1470244D03*
Y1491490D03*
Y1485598D03*
Y1496221D03*
Y1506845D03*
Y1500952D03*
Y1511576D03*
Y1516307D03*
Y1563144D03*
Y1567875D03*
Y1578498D03*
Y1572606D03*
Y1583229D03*
Y1593853D03*
Y1587960D03*
Y1609207D03*
Y1598584D03*
Y1603315D03*
Y1613938D03*
Y1618669D03*
X1312000Y1644980D03*
X1331756Y-64193D03*
X1328503Y-64207D03*
X1331741Y-66708D03*
X1328488Y-66722D03*
X1334781Y-65513D03*
X1321092Y117261D03*
X1328799Y172665D03*
Y180665D03*
X1328831Y212864D03*
Y200864D03*
Y221864D03*
Y216864D03*
X1330414Y310058D03*
X1325458D03*
X1322540Y313058D03*
X1333332D03*
X1331085Y334347D03*
X1323816D03*
Y341615D03*
X1331085Y348868D03*
X1323816D03*
X1332927Y468607D03*
X1326912Y493153D03*
X1325630Y513238D03*
X1335000Y590500D03*
Y586500D03*
Y633000D03*
Y637000D03*
Y677500D03*
Y681500D03*
Y724500D03*
Y728500D03*
X1324217Y780595D03*
X1332654Y836170D03*
X1323205Y861367D03*
X1335803Y851918D03*
Y877114D03*
X1326355Y886562D03*
X1328457Y959986D03*
X1321104Y964398D03*
X1323554Y967623D03*
X1331890Y1051919D03*
X1331359Y1098898D03*
X1334161Y1098518D03*
X1333905Y1123101D03*
X1331405D03*
X1323405D03*
X1320279Y1131935D03*
Y1134435D03*
Y1136935D03*
Y1139435D03*
X1334305Y1129301D03*
X1331805D03*
X1329305D03*
X1326805D03*
X1324305D03*
X1321805D03*
X1334305Y1125801D03*
X1331805D03*
X1323405D03*
X1320279Y1141935D03*
Y1146935D03*
Y1144435D03*
X1326269Y1152713D03*
Y1155213D03*
X1320493Y1204405D03*
X1334793Y1204617D03*
X1320493Y1206905D03*
Y1211905D03*
Y1209405D03*
X1334793Y1207117D03*
Y1209617D03*
Y1212117D03*
X1330070Y1297498D03*
X1335470D03*
X1332424Y1345691D03*
Y1350683D03*
X1327468D03*
Y1345691D03*
X1320184Y1350683D03*
Y1345691D03*
X1332424Y1362595D03*
Y1357603D03*
X1327468D03*
Y1362595D03*
X1320184D03*
Y1357603D03*
X1332424Y1381801D03*
Y1369889D03*
Y1374881D03*
X1327468Y1381801D03*
Y1369889D03*
Y1374881D03*
X1320184Y1381801D03*
Y1374881D03*
Y1369889D03*
X1332424Y1386793D03*
Y1394087D03*
Y1399079D03*
X1327468Y1386793D03*
Y1394087D03*
Y1399079D03*
X1320184D03*
Y1394087D03*
Y1386793D03*
X1332424Y1410991D03*
Y1405999D03*
X1327468Y1410991D03*
Y1405999D03*
X1320184Y1410991D03*
Y1405999D03*
X1328850Y1465513D03*
Y1460782D03*
X1320189Y1465913D03*
Y1456451D03*
Y1461182D03*
X1328850Y1476136D03*
Y1470244D03*
X1320189Y1481267D03*
X1328850Y1480867D03*
X1320189Y1471805D03*
Y1476536D03*
X1328850Y1491490D03*
Y1485598D03*
X1320189Y1496621D03*
X1328850Y1496221D03*
X1320189Y1487159D03*
Y1491890D03*
Y1502514D03*
X1328850Y1506845D03*
Y1500952D03*
Y1511576D03*
X1320189Y1511976D03*
Y1507245D03*
X1328850Y1516307D03*
X1320189Y1558813D03*
Y1563544D03*
X1328850Y1563144D03*
Y1567875D03*
X1320189Y1574167D03*
Y1578898D03*
X1328850Y1578498D03*
Y1572606D03*
X1320189Y1568275D03*
X1328850Y1583229D03*
X1320189Y1589522D03*
Y1594253D03*
X1328850Y1593853D03*
Y1587960D03*
X1320189Y1583629D03*
X1328850Y1603315D03*
X1320189Y1609607D03*
Y1604876D03*
Y1598984D03*
X1328850Y1609207D03*
Y1598584D03*
Y1613938D03*
Y1618669D03*
X1320189Y1614338D03*
X1332000Y1644980D03*
X1340320Y151540D03*
X1338288Y313058D03*
X1338378Y334347D03*
X1338275Y341603D03*
X1338378Y348830D03*
X1345451Y699032D03*
X1347136Y780040D03*
X1351550Y839320D03*
Y855068D03*
X1345252D03*
X1342103D03*
Y861367D03*
X1338953D03*
Y858218D03*
X1338952Y855067D03*
X1338953Y870814D03*
X1342103Y867665D03*
X1338953D03*
X1351550Y873964D03*
X1345252D03*
X1342103D03*
X1338952Y873965D03*
X1345252Y892862D03*
X1341820Y947407D03*
X1347380Y1057998D03*
Y1055498D03*
X1344880D03*
Y1057998D03*
X1347380Y1060498D03*
Y1062998D03*
X1344880D03*
Y1060498D03*
X1339349Y1098767D03*
X1339305Y1129301D03*
X1336805D03*
X1339305Y1125801D03*
X1336805D03*
X1343505Y1136935D03*
Y1134435D03*
Y1139435D03*
Y1131935D03*
X1349907D03*
Y1134435D03*
Y1136935D03*
Y1139435D03*
X1352407Y1131935D03*
Y1134435D03*
Y1136935D03*
Y1139435D03*
X1343505Y1146935D03*
Y1144435D03*
Y1141935D03*
X1349907D03*
Y1146935D03*
Y1144435D03*
X1352407Y1141935D03*
Y1146935D03*
Y1144435D03*
X1336669Y1152713D03*
Y1155213D03*
X1351405Y1154902D03*
Y1152402D03*
X1347423Y1204405D03*
X1337108Y1200821D03*
Y1198321D03*
X1347423Y1209405D03*
Y1211905D03*
Y1206905D03*
X1340870Y1297498D03*
X1346270D03*
X1351670D03*
X1351948Y1350683D03*
Y1345691D03*
X1339708Y1345597D03*
Y1350683D03*
X1344664Y1345597D03*
Y1350683D03*
X1351948Y1357603D03*
Y1362595D03*
X1339708D03*
Y1357603D03*
X1344664Y1362595D03*
Y1357603D03*
X1351948Y1374881D03*
Y1381801D03*
Y1369889D03*
X1339708Y1374881D03*
Y1381801D03*
Y1369889D03*
X1344664D03*
Y1374881D03*
Y1381801D03*
X1351948Y1386793D03*
Y1394087D03*
Y1399079D03*
X1339708D03*
Y1393993D03*
Y1386793D03*
X1344664Y1393993D03*
Y1399079D03*
Y1386793D03*
X1351948Y1410991D03*
Y1405999D03*
X1339708Y1410991D03*
Y1405999D03*
X1344664Y1410991D03*
Y1405999D03*
X1337512Y1461182D03*
X1346173Y1465513D03*
Y1460782D03*
X1337512Y1465913D03*
Y1456451D03*
X1346173Y1476136D03*
Y1470244D03*
X1337512Y1481267D03*
X1346173Y1480867D03*
X1337512Y1471805D03*
Y1476536D03*
X1346173Y1485598D03*
Y1491490D03*
X1337512Y1487159D03*
Y1491890D03*
Y1496621D03*
X1346173Y1496221D03*
X1337512Y1507245D03*
Y1502514D03*
X1346173Y1506845D03*
Y1500952D03*
Y1511576D03*
X1337512Y1511976D03*
X1346173Y1516307D03*
X1337512Y1558813D03*
Y1563544D03*
X1346173Y1563144D03*
X1337512Y1574167D03*
Y1578898D03*
X1346173Y1578498D03*
Y1572606D03*
X1337512Y1568275D03*
X1346173Y1567875D03*
X1337512Y1583629D03*
X1346173Y1583229D03*
X1337512Y1589522D03*
Y1594253D03*
X1346173Y1593853D03*
Y1587960D03*
X1337512Y1609607D03*
Y1604876D03*
Y1598984D03*
X1346173Y1609207D03*
Y1598584D03*
Y1603315D03*
X1337512Y1614338D03*
X1346173Y1613938D03*
Y1618669D03*
X1352000Y1644980D03*
X1355900Y146461D03*
X1354802Y152367D03*
X1355255Y561032D03*
Y607532D03*
Y652032D03*
X1364148Y836170D03*
X1354699Y855068D03*
X1357849Y861367D03*
X1354699D03*
X1357849Y858218D03*
X1357850Y855067D03*
X1360999Y851918D03*
Y877114D03*
X1357850Y873965D03*
X1354699Y873964D03*
X1357849Y870814D03*
Y867665D03*
X1354699D03*
X1363173Y994483D03*
X1363905Y1000855D03*
X1366493Y1000828D03*
X1367884Y1018825D03*
X1357265Y1022766D03*
X1364237Y1043140D03*
X1357265Y1030266D03*
X1363941Y1047047D03*
X1366289Y1098518D03*
X1361037Y1098428D03*
X1355533Y1123101D03*
X1363533D03*
X1366033D03*
X1366433Y1129301D03*
X1355533Y1125801D03*
X1363933D03*
X1366433D03*
X1353933Y1129301D03*
X1356433D03*
X1358933D03*
X1361433D03*
X1363933D03*
X1357397Y1155213D03*
Y1152713D03*
X1366797D03*
Y1155213D03*
X1361723Y1204617D03*
X1364038Y1198321D03*
Y1200821D03*
X1361723Y1212117D03*
Y1209617D03*
Y1207117D03*
X1357070Y1297498D03*
X1356904Y1345691D03*
Y1350683D03*
Y1357603D03*
Y1362595D03*
Y1381801D03*
Y1369889D03*
Y1374881D03*
Y1386793D03*
Y1394087D03*
Y1399079D03*
Y1410991D03*
Y1405999D03*
X1354834Y1465913D03*
Y1456451D03*
Y1461182D03*
X1363496Y1465513D03*
Y1460782D03*
X1354834Y1481267D03*
X1363496Y1476136D03*
Y1470244D03*
Y1480867D03*
X1354834Y1471805D03*
Y1476536D03*
Y1487159D03*
Y1496621D03*
X1363496Y1485598D03*
Y1491490D03*
Y1496221D03*
X1354834Y1491890D03*
Y1502514D03*
Y1511976D03*
X1363496Y1511576D03*
Y1506845D03*
Y1500952D03*
X1354834Y1507245D03*
X1363496Y1516307D03*
X1354834Y1558813D03*
Y1563544D03*
X1363496Y1563144D03*
Y1572606D03*
X1354834Y1568275D03*
Y1574167D03*
Y1578898D03*
X1363496Y1567875D03*
Y1578498D03*
X1354834Y1583629D03*
Y1589522D03*
Y1594253D03*
X1363496Y1583229D03*
Y1593853D03*
Y1587960D03*
X1354834Y1609607D03*
Y1604876D03*
Y1598984D03*
X1363496Y1609207D03*
Y1598584D03*
Y1603315D03*
X1354834Y1614338D03*
X1363496Y1613938D03*
Y1618669D03*
X1376262Y113394D03*
X1378911Y110784D03*
X1378505Y133298D03*
X1380652Y134579D03*
X1378227Y252371D03*
X1383556Y558338D03*
X1383184Y587653D03*
X1383425Y593575D03*
X1383556Y604838D03*
X1381118Y634033D03*
X1383425Y640075D03*
X1381244Y673623D03*
X1383425Y684140D03*
X1381932Y722547D03*
X1383425Y731575D03*
X1383046Y829871D03*
X1379896Y842470D03*
Y858218D03*
X1370447Y867665D03*
Y886562D03*
X1371379Y986717D03*
X1370384Y1004680D03*
X1376601Y1030218D03*
X1374451Y1090568D03*
Y1093068D03*
X1371477Y1098767D03*
X1375633Y1136935D03*
Y1134435D03*
Y1139435D03*
Y1131935D03*
X1383366D03*
Y1134435D03*
Y1136935D03*
Y1139435D03*
X1368933Y1125801D03*
X1371433D03*
X1368933Y1129301D03*
X1371433D03*
X1383024Y1152684D03*
X1376861D03*
X1375633Y1146935D03*
Y1144435D03*
Y1141935D03*
X1383366D03*
Y1146935D03*
Y1144435D03*
X1377390Y1244055D03*
Y1250760D03*
Y1254164D03*
X1372300Y1422900D03*
X1372157Y1461183D03*
Y1456452D03*
Y1465914D03*
Y1471806D03*
Y1476537D03*
Y1481268D03*
Y1487160D03*
Y1491891D03*
Y1496622D03*
Y1502515D03*
Y1507246D03*
Y1511977D03*
Y1558813D03*
Y1563544D03*
Y1568275D03*
Y1574167D03*
Y1578898D03*
Y1583629D03*
Y1589522D03*
Y1594253D03*
Y1604876D03*
Y1598984D03*
Y1609607D03*
Y1614338D03*
X1372000Y1644980D03*
X1391497Y109172D03*
X1394497D03*
X1393504Y106495D03*
X1397248Y116497D03*
X1386505Y133298D03*
X1397248Y130670D03*
Y123584D03*
X1393238Y146012D03*
X1395144Y141228D03*
X1397248Y137757D03*
X1398032Y150847D03*
X1400000Y247292D03*
X1392709Y253198D03*
X1391086Y577192D03*
X1400912Y581222D03*
Y591215D03*
X1391587Y627817D03*
X1388414Y675000D03*
X1388241Y722000D03*
X1396916Y862829D03*
X1395561Y876204D03*
X1396163Y868597D03*
X1398247Y926261D03*
X1390322Y1057998D03*
Y1055498D03*
X1392822D03*
Y1057998D03*
X1390322Y1060498D03*
Y1062998D03*
X1392822D03*
Y1060498D03*
X1399748Y1098518D03*
X1394496Y1098428D03*
X1388992Y1123101D03*
X1396992D03*
X1399492D03*
X1385866Y1131935D03*
Y1134435D03*
Y1136935D03*
Y1139435D03*
X1388992Y1125801D03*
X1397392D03*
X1399892D03*
X1387392Y1129301D03*
X1389892D03*
X1392392D03*
X1394892D03*
X1397392D03*
X1399892D03*
X1391856Y1155213D03*
Y1152713D03*
X1385866Y1141935D03*
Y1146935D03*
Y1144435D03*
X1393695Y1204405D03*
Y1206905D03*
Y1211905D03*
Y1209405D03*
X1385992Y1285466D03*
X1390492D03*
X1392000Y1644980D03*
X1409248Y109410D03*
Y102323D03*
X1404548Y116497D03*
X1402048D03*
X1404548Y109410D03*
X1409248Y116496D03*
X1402048Y130670D03*
Y123584D03*
X1404548Y123583D03*
X1409248Y130670D03*
Y123583D03*
X1404548Y130670D03*
X1409248Y137756D03*
X1402048Y137757D03*
X1408666Y324733D03*
X1411950Y448466D03*
X1408103Y555194D03*
X1410903D03*
X1408103Y563194D03*
X1410903D03*
X1408103Y571194D03*
X1410903D03*
X1406512Y581222D03*
X1403712D03*
Y591215D03*
X1406512D03*
X1405514Y611091D03*
X1405000Y656000D03*
Y699000D03*
X1404689Y910897D03*
X1413575Y915186D03*
X1413322Y958908D03*
X1404317Y989436D03*
X1411038Y985379D03*
X1404936Y1098767D03*
X1415494Y1139435D03*
Y1136935D03*
Y1134435D03*
Y1131935D03*
X1409092Y1136935D03*
Y1134435D03*
Y1139435D03*
Y1131935D03*
X1402392Y1125801D03*
X1404892D03*
X1402392Y1129301D03*
X1404892D03*
X1409092Y1141935D03*
X1416736Y1152713D03*
Y1155213D03*
X1402256D03*
Y1152713D03*
X1415494Y1144435D03*
Y1146935D03*
Y1141935D03*
X1409092Y1146935D03*
Y1144435D03*
X1407995Y1204617D03*
X1410310Y1200821D03*
Y1198321D03*
X1407995Y1207117D03*
Y1209617D03*
Y1212117D03*
X1415903Y1282590D03*
X1404019Y1285290D03*
X1414346Y1303020D03*
X1412000Y1644980D03*
X1417710Y82984D03*
Y75184D03*
Y77784D03*
Y80384D03*
X1420264Y92849D03*
X1417710Y85584D03*
X1427224Y103037D03*
X1427358Y116496D03*
Y109410D03*
Y130670D03*
Y123583D03*
X1423515Y137756D03*
X1429539Y293796D03*
X1432039D03*
X1431019Y434508D03*
X1427019D03*
X1424196Y446352D03*
X1428782Y445874D03*
X1417856Y455466D03*
X1433310Y504699D03*
X1430810D03*
X1433012Y516979D03*
X1430512D03*
X1427233Y628183D03*
X1424389Y627948D03*
X1426000Y709000D03*
Y713000D03*
Y757000D03*
Y753000D03*
X1422813Y910065D03*
X1424126Y900295D03*
X1427553Y939200D03*
X1427473Y965621D03*
X1420740Y1004766D03*
Y1000766D03*
Y1016266D03*
Y1030766D03*
X1420107Y1052514D03*
X1431876Y1098518D03*
X1426624Y1098428D03*
X1421120Y1123101D03*
X1429120D03*
X1431620D03*
X1422020Y1129301D03*
X1424520D03*
X1427020D03*
X1429520D03*
X1432020D03*
X1417994Y1139435D03*
Y1136935D03*
Y1134435D03*
Y1131935D03*
X1421120Y1125801D03*
X1429520D03*
X1432020D03*
X1419520Y1129301D03*
X1432384Y1155213D03*
Y1152713D03*
X1422984D03*
Y1155213D03*
X1417994Y1144435D03*
Y1146935D03*
Y1141935D03*
X1420625Y1204405D03*
Y1206905D03*
Y1209405D03*
X1425652Y1297411D03*
X1433386Y1343309D03*
X1428840Y1407740D03*
X1423065Y1508327D03*
X1432499Y1512175D03*
X1424245Y1543338D03*
X1425558Y1537432D03*
X1425260Y1558072D03*
X1433558Y1555366D03*
X1423701Y1563978D03*
X1432000Y1644980D03*
X1444641Y94017D03*
X1448641D03*
X1440641D03*
X1449761Y115401D03*
Y110445D03*
X1444769D03*
Y115401D03*
X1449761Y124618D03*
X1444769D03*
Y129574D03*
X1449761D03*
X1442682Y151540D03*
X1446332Y191941D03*
X1446199Y188727D03*
X1442956Y226141D03*
X1440156D03*
X1448026Y256535D03*
X1440053Y285690D03*
X1437553D03*
X1440053Y288190D03*
X1442853D03*
Y285690D03*
X1447079Y290755D03*
X1437553Y288190D03*
X1437758Y362584D03*
X1435019Y434508D03*
X1437757Y447201D03*
X1437879Y444269D03*
X1435810Y504699D03*
X1447036Y519518D03*
X1435512Y516979D03*
X1444536Y519518D03*
X1439536D03*
X1442036D03*
X1435241Y593796D03*
X1440930Y636005D03*
Y633205D03*
Y638805D03*
X1437784Y683532D03*
X1436567Y727532D03*
X1443000Y798500D03*
Y794500D03*
Y842500D03*
Y838500D03*
X1438188Y867633D03*
X1437703Y880067D03*
X1449072Y892581D03*
X1435288Y897500D03*
X1444453Y938806D03*
X1439449Y979009D03*
X1440610Y1021567D03*
X1435266Y1031522D03*
X1437064Y1098767D03*
X1441220Y1131935D03*
Y1139435D03*
Y1134435D03*
Y1136935D03*
X1434520Y1125801D03*
X1437020D03*
X1434520Y1129301D03*
X1437020D03*
X1441220Y1141935D03*
Y1144435D03*
Y1146935D03*
X1442448Y1152684D03*
X1434925Y1204617D03*
X1437240Y1200821D03*
Y1198321D03*
X1434925Y1207117D03*
Y1209617D03*
Y1212117D03*
X1436408Y1303462D03*
X1444438Y1308312D03*
X1439482D03*
X1441286Y1335776D03*
X1457718Y84140D03*
Y76140D03*
Y80140D03*
X1452650Y94017D03*
X1460163Y117557D03*
X1455171D03*
Y122513D03*
X1460163Y131731D03*
Y122513D03*
X1455171Y131731D03*
X1458262Y146461D03*
X1460163Y136687D03*
X1455171D03*
X1457164Y152367D03*
X1463547Y180527D03*
X1458864Y180572D03*
Y185165D03*
X1463502Y185121D03*
X1452832Y184619D03*
X1454812Y206760D03*
X1456026Y256535D03*
X1457056Y279208D03*
X1461160Y281307D03*
X1455079Y290755D03*
X1451079D03*
X1458982Y356861D03*
X1453000Y633450D03*
Y636250D03*
Y639050D03*
X1453032Y769032D03*
X1453775Y813032D03*
X1461241Y867475D03*
X1462694Y874859D03*
Y877859D03*
X1460472Y885985D03*
X1459420Y899226D03*
X1451005Y931848D03*
X1462819Y949996D03*
X1462000Y960378D03*
X1460655Y964253D03*
X1466076Y979746D03*
X1462388Y1006560D03*
X1455939Y1018368D03*
X1465503Y1030233D03*
X1460592Y1345691D03*
Y1350683D03*
X1465548Y1345691D03*
Y1350683D03*
X1460592Y1357603D03*
Y1362595D03*
X1465548Y1357603D03*
Y1362595D03*
X1460592Y1381801D03*
Y1374881D03*
Y1369889D03*
X1465548Y1381801D03*
Y1374881D03*
Y1369889D03*
X1460592Y1386793D03*
X1465548D03*
X1452000Y1644980D03*
X1480460Y60922D03*
X1475296Y55513D03*
X1471093Y117261D03*
X1478624Y113394D03*
X1481273Y110784D03*
X1481368Y130898D03*
X1478800Y180665D03*
Y172665D03*
X1467270Y192421D03*
X1478832Y200864D03*
Y212864D03*
Y216864D03*
Y221864D03*
X1480589Y252371D03*
X1473900Y433100D03*
X1478710Y685630D03*
X1473525Y710052D03*
X1474425Y716075D03*
X1479962Y727500D03*
X1471415Y748629D03*
X1474425Y760075D03*
X1473634Y864337D03*
X1481454Y911570D03*
X1474075Y920575D03*
X1474349Y949394D03*
X1468500Y974181D03*
X1479096Y997860D03*
X1471096D03*
X1475096D03*
X1467096D03*
X1471854Y1035088D03*
X1479624Y1035102D03*
X1468371Y1030701D03*
X1480193Y1102091D03*
X1474384D03*
X1480193Y1114691D03*
X1474384D03*
X1480193Y1127291D03*
X1474384D03*
X1480193Y1139891D03*
X1474384D03*
X1480193Y1152491D03*
X1474384D03*
X1480193Y1165091D03*
X1474384D03*
X1480193Y1177691D03*
X1474384D03*
X1480675Y1202103D03*
X1477788Y1350683D03*
Y1345691D03*
X1472832Y1350683D03*
Y1345691D03*
X1477788Y1357603D03*
Y1362595D03*
X1472832Y1357603D03*
Y1362595D03*
X1477788Y1381801D03*
Y1369795D03*
Y1374881D03*
X1472832Y1381801D03*
Y1369795D03*
Y1374881D03*
X1477788Y1386793D03*
Y1399079D03*
Y1393993D03*
X1472832Y1386793D03*
Y1393993D03*
Y1399079D03*
X1477788Y1405999D03*
Y1410991D03*
X1472832Y1405999D03*
Y1410991D03*
X1476094Y1465913D03*
Y1461182D03*
Y1456451D03*
Y1471805D03*
Y1481267D03*
Y1476536D03*
Y1491890D03*
Y1487159D03*
Y1496621D03*
Y1502514D03*
Y1511976D03*
Y1507245D03*
Y1563544D03*
Y1558813D03*
Y1568275D03*
Y1578898D03*
Y1574167D03*
Y1583629D03*
Y1594253D03*
Y1589522D03*
Y1609607D03*
Y1598984D03*
Y1604876D03*
Y1614338D03*
X1472000Y1644980D03*
X1493859Y109172D03*
X1496859D03*
X1495866Y106495D03*
X1488867Y133298D03*
X1495600Y146012D03*
X1497506Y141228D03*
X1483014Y134579D03*
X1495071Y253198D03*
X1486360Y358700D03*
Y354200D03*
X1496473Y769000D03*
X1491062Y793003D03*
X1491425Y801575D03*
X1496845Y813000D03*
X1491425Y845575D03*
X1489650Y836985D03*
X1489805Y866386D03*
X1497488Y873839D03*
X1491414Y875383D03*
X1494000Y884000D03*
X1498084Y894825D03*
X1492101Y894860D03*
X1496383Y898023D03*
X1496500Y919000D03*
X1496000Y922000D03*
X1487075Y920925D03*
X1485100Y943900D03*
X1496425Y943075D03*
X1496072Y950044D03*
X1482591Y961909D03*
X1486500Y947000D03*
X1485226Y973886D03*
X1492560Y974654D03*
X1495339Y1009354D03*
X1491839D03*
X1486030D03*
X1491096Y997860D03*
X1483096D03*
X1495096D03*
X1487096D03*
X1495339Y1021954D03*
X1491839D03*
X1486030D03*
X1483693Y1102091D03*
Y1114691D03*
Y1127291D03*
Y1139891D03*
Y1152491D03*
Y1165091D03*
Y1177691D03*
X1498197Y1209607D03*
X1492471Y1215195D03*
X1484055Y1223749D03*
X1497312Y1350683D03*
Y1345691D03*
X1485072D03*
Y1350683D03*
X1490028Y1345691D03*
Y1350683D03*
X1497312Y1357603D03*
Y1362595D03*
X1485072D03*
Y1357603D03*
X1490028D03*
Y1362595D03*
X1485072Y1369889D03*
Y1374881D03*
Y1381801D03*
X1490028Y1369889D03*
Y1374881D03*
Y1381801D03*
X1497312D03*
Y1374881D03*
Y1369889D03*
Y1386793D03*
Y1394087D03*
Y1399079D03*
X1485072Y1394087D03*
Y1399079D03*
Y1386793D03*
X1490028Y1399079D03*
Y1394087D03*
Y1386793D03*
X1497312Y1405999D03*
Y1410991D03*
X1485072Y1405999D03*
Y1410991D03*
X1490028Y1405999D03*
Y1410991D03*
X1484755Y1465513D03*
Y1460782D03*
X1493417Y1465913D03*
Y1456451D03*
Y1461182D03*
Y1471805D03*
Y1476536D03*
Y1481267D03*
X1484755Y1476136D03*
Y1470244D03*
Y1480867D03*
Y1496221D03*
X1493417Y1487159D03*
Y1491890D03*
Y1496621D03*
X1484755Y1491490D03*
Y1485598D03*
Y1506845D03*
Y1500952D03*
Y1511576D03*
X1493417Y1507245D03*
Y1502514D03*
Y1511976D03*
X1484755Y1516307D03*
Y1563144D03*
X1493417Y1558813D03*
Y1563544D03*
Y1578898D03*
X1484755Y1567875D03*
Y1578498D03*
Y1572606D03*
X1493417Y1568275D03*
Y1574167D03*
X1484755Y1583229D03*
Y1593853D03*
Y1587960D03*
X1493417Y1583629D03*
Y1589522D03*
Y1594253D03*
X1484755Y1609207D03*
Y1598584D03*
Y1603315D03*
X1493417Y1609607D03*
Y1604876D03*
Y1598984D03*
X1484755Y1613938D03*
Y1618669D03*
X1493417Y1614338D03*
X1492000Y1644980D03*
X1511610Y116496D03*
Y109410D03*
Y102323D03*
X1499610Y116497D03*
X1506910D03*
X1504410D03*
X1506910Y109410D03*
X1511610Y123583D03*
X1499610Y130670D03*
Y123584D03*
X1506910Y130670D03*
X1504410D03*
Y123584D03*
X1506910Y123583D03*
X1511610Y130670D03*
Y137756D03*
X1499610Y137757D03*
X1504410D03*
X1500394Y150847D03*
X1502362Y247292D03*
X1501807Y323766D03*
X1507864Y450750D03*
X1511963Y536382D03*
X1510280Y899732D03*
X1514354Y938811D03*
X1510500Y931500D03*
X1513955Y950396D03*
X1505888Y965964D03*
X1514000Y968739D03*
X1510740Y973740D03*
X1507096Y997860D03*
X1503096D03*
X1511096D03*
X1499096D03*
X1505130Y1105091D03*
Y1117691D03*
Y1130291D03*
Y1142891D03*
Y1155491D03*
Y1168091D03*
Y1180691D03*
X1509552Y1350683D03*
Y1345691D03*
X1514508Y1350683D03*
Y1345691D03*
X1502268Y1350683D03*
Y1345691D03*
X1509552Y1362595D03*
Y1357603D03*
X1514508D03*
Y1362595D03*
X1502268Y1357603D03*
Y1362595D03*
X1509552Y1374881D03*
Y1369889D03*
Y1381801D03*
X1514508Y1374881D03*
Y1369889D03*
Y1381801D03*
X1502268D03*
Y1374881D03*
Y1369889D03*
X1509552Y1394087D03*
Y1399079D03*
Y1386793D03*
X1514508Y1394087D03*
Y1399079D03*
Y1386793D03*
X1502268D03*
Y1399079D03*
Y1394087D03*
X1509552Y1405999D03*
Y1410991D03*
X1514508Y1405999D03*
Y1410991D03*
X1502268Y1405999D03*
Y1410991D03*
X1502078Y1465513D03*
Y1460782D03*
X1510740Y1465913D03*
Y1456451D03*
Y1461182D03*
X1502078Y1470244D03*
Y1480867D03*
X1510740Y1471805D03*
Y1476536D03*
Y1481267D03*
X1502078Y1476136D03*
Y1491490D03*
Y1485598D03*
Y1496221D03*
X1510740Y1487159D03*
Y1491890D03*
Y1496621D03*
Y1507245D03*
Y1502514D03*
Y1511976D03*
X1502078Y1506845D03*
Y1500952D03*
Y1511576D03*
Y1516307D03*
X1510740Y1563544D03*
X1502078Y1563144D03*
X1510740Y1558813D03*
Y1578898D03*
X1502078Y1567875D03*
Y1578498D03*
Y1572606D03*
X1510740Y1568275D03*
Y1574167D03*
X1502078Y1583229D03*
Y1593853D03*
Y1587960D03*
X1510740Y1583629D03*
Y1589522D03*
Y1594253D03*
X1502078Y1609207D03*
Y1598584D03*
Y1603315D03*
X1510740Y1609607D03*
Y1604876D03*
Y1598984D03*
X1502078Y1613938D03*
Y1618669D03*
X1510740Y1614338D03*
X1512000Y1644980D03*
X1520072Y82984D03*
Y75184D03*
Y77784D03*
Y80384D03*
X1522626Y92849D03*
X1520072Y85584D03*
X1529586Y103037D03*
X1529720Y116496D03*
Y109410D03*
Y130670D03*
Y123583D03*
X1526311Y137756D03*
X1528635Y555234D03*
X1528350Y562003D03*
X1519156Y596095D03*
X1516869Y594668D03*
X1518354Y592354D03*
X1518415Y589556D03*
X1519153Y599588D03*
X1516930Y597580D03*
X1519185Y615600D03*
X1519153Y607588D03*
X1523646Y634946D03*
X1519063Y876339D03*
X1517344Y896999D03*
X1515743Y888133D03*
X1517344Y903179D03*
X1517153Y908367D03*
X1523000Y923740D03*
X1526611Y921442D03*
X1525740Y928740D03*
X1528087Y936394D03*
X1524500Y949500D03*
X1530174Y956986D03*
X1525522Y971075D03*
X1523966Y980281D03*
X1515096Y997860D03*
X1531096D03*
X1519096D03*
X1523096D03*
X1516776Y1024954D03*
Y1012354D03*
X1526748Y1345691D03*
Y1350683D03*
X1521792Y1345691D03*
Y1350683D03*
X1526748Y1357603D03*
Y1362595D03*
X1521792Y1357603D03*
Y1362595D03*
X1526748Y1369889D03*
Y1374881D03*
Y1381801D03*
X1521792Y1374881D03*
Y1381801D03*
Y1369889D03*
X1526748Y1386793D03*
Y1399079D03*
Y1394087D03*
X1521792Y1386793D03*
Y1394087D03*
Y1399079D03*
X1526748Y1405999D03*
Y1410991D03*
X1521792Y1405999D03*
Y1410991D03*
X1519401Y1465513D03*
Y1460782D03*
X1528062Y1465913D03*
Y1456451D03*
Y1461182D03*
Y1481267D03*
X1519401Y1476136D03*
Y1470244D03*
Y1480867D03*
X1528062Y1471805D03*
Y1476536D03*
X1519401Y1491490D03*
Y1485598D03*
Y1496221D03*
X1528062Y1487159D03*
Y1491890D03*
Y1496621D03*
X1519401Y1506845D03*
Y1500952D03*
Y1511576D03*
X1528062Y1507245D03*
Y1502514D03*
Y1511976D03*
X1519401Y1516307D03*
Y1563144D03*
X1528062Y1558813D03*
Y1563544D03*
Y1578898D03*
X1519401Y1567875D03*
Y1578498D03*
Y1572606D03*
X1528062Y1568275D03*
Y1574167D03*
X1519401Y1587960D03*
X1528062Y1583629D03*
Y1589522D03*
Y1594253D03*
X1519401Y1583229D03*
Y1593853D03*
Y1609207D03*
Y1598584D03*
Y1603315D03*
X1528062Y1609607D03*
Y1604876D03*
Y1598984D03*
X1519401Y1613938D03*
Y1618669D03*
X1528062Y1614338D03*
X1547003Y94017D03*
X1543003D03*
X1547131Y110445D03*
Y115401D03*
Y129574D03*
Y124618D03*
X1545044Y151540D03*
X1548561Y188727D03*
X1542518Y226141D03*
X1545318D03*
X1531901Y293796D03*
X1539915Y288190D03*
X1542415Y285690D03*
X1539915D03*
X1542415Y288190D03*
X1545215D03*
Y285690D03*
X1534401Y293796D03*
X1541283Y354553D03*
X1546272Y1350683D03*
Y1345691D03*
X1534032Y1350683D03*
Y1345691D03*
X1538988D03*
Y1350683D03*
X1546272Y1357603D03*
Y1362595D03*
X1534032Y1357603D03*
Y1362595D03*
X1538988D03*
Y1357603D03*
X1546272Y1374881D03*
Y1369889D03*
Y1381801D03*
X1534032Y1369889D03*
Y1381801D03*
Y1374881D03*
X1538988Y1369889D03*
Y1381801D03*
Y1374881D03*
X1546272Y1386793D03*
Y1394087D03*
Y1399079D03*
X1534032Y1394087D03*
Y1399079D03*
Y1386793D03*
X1538988Y1394087D03*
Y1399079D03*
Y1386793D03*
X1546272Y1405999D03*
Y1410991D03*
X1534032Y1405999D03*
Y1410991D03*
X1538988Y1405999D03*
Y1410991D03*
X1545385Y1461183D03*
X1536724Y1465513D03*
Y1460782D03*
X1545385Y1465914D03*
Y1456452D03*
X1536724Y1476136D03*
Y1470244D03*
Y1480867D03*
X1545385Y1476537D03*
Y1471806D03*
Y1481268D03*
X1536724Y1491490D03*
Y1485598D03*
Y1496221D03*
X1545385Y1491891D03*
Y1487160D03*
Y1496622D03*
X1536724Y1506845D03*
Y1500952D03*
Y1511576D03*
X1545385Y1507246D03*
Y1502515D03*
Y1511977D03*
X1536724Y1516307D03*
X1545385Y1563544D03*
Y1558813D03*
X1536724Y1563144D03*
Y1567875D03*
X1545385Y1568275D03*
X1536724Y1578498D03*
Y1572606D03*
X1545385Y1578898D03*
Y1574167D03*
Y1594253D03*
Y1589522D03*
X1536724Y1583229D03*
X1545385Y1583629D03*
X1536724Y1593853D03*
Y1587960D03*
Y1609207D03*
Y1598584D03*
Y1603315D03*
X1545385Y1609607D03*
Y1598984D03*
Y1604876D03*
Y1614338D03*
X1536724Y1613938D03*
Y1618669D03*
X1532000Y1644980D03*
X1560080Y84140D03*
Y76140D03*
Y80140D03*
X1555012Y94017D03*
X1551003D03*
X1562525Y117557D03*
X1557533D03*
X1552123Y115401D03*
Y110445D03*
X1562525Y122513D03*
X1552123Y129574D03*
Y124618D03*
X1557533Y131731D03*
Y122513D03*
X1562525Y131731D03*
X1560624Y146461D03*
X1557533Y136687D03*
X1562525D03*
X1559526Y152367D03*
X1561226Y180572D03*
X1548694Y191941D03*
X1555194Y184619D03*
X1561226Y185165D03*
X1557174Y206760D03*
X1550388Y256535D03*
X1558388D03*
X1559418Y279208D03*
X1563522Y281307D03*
X1549441Y290755D03*
X1553441D03*
X1557441D03*
X1554403Y352363D03*
X1563248Y389154D03*
X1548629D03*
Y403327D03*
Y410413D03*
X1561778Y396240D03*
X1548629D03*
Y417500D03*
Y424587D03*
Y438760D03*
Y431673D03*
Y445847D03*
Y467539D03*
Y474626D03*
Y488799D03*
Y481713D03*
Y495886D03*
Y511673D03*
Y518760D03*
X1562089Y516841D03*
X1548629Y540020D03*
Y525847D03*
Y532933D03*
Y547106D03*
X1556914Y552872D03*
X1557036Y550123D03*
X1556359Y562443D03*
X1558668Y572334D03*
X1558127Y560675D03*
X1556900Y574102D03*
X1547910Y602197D03*
X1548374Y595108D03*
X1561535Y653161D03*
X1565132Y677843D03*
X1547813Y906581D03*
X1551099Y959096D03*
X1558512Y1345691D03*
Y1350683D03*
X1563468D03*
Y1345691D03*
X1551228Y1350683D03*
Y1345691D03*
X1563468Y1362595D03*
X1551228Y1357603D03*
Y1362595D03*
X1558512D03*
Y1357603D03*
X1563468D03*
X1558512Y1374881D03*
Y1369889D03*
Y1381801D03*
X1563468Y1374881D03*
Y1369889D03*
Y1381801D03*
X1551228Y1369889D03*
Y1381801D03*
Y1374881D03*
X1558512Y1399079D03*
Y1394087D03*
Y1386793D03*
X1563468Y1399079D03*
Y1394087D03*
Y1386793D03*
X1551228D03*
Y1394087D03*
Y1399079D03*
X1558512Y1405999D03*
Y1410991D03*
X1563468Y1405999D03*
Y1410991D03*
X1551228Y1405999D03*
Y1410991D03*
X1552000Y1644980D03*
X1576256Y-25273D03*
X1573003Y-25287D03*
X1576241Y-27788D03*
X1572988Y-27802D03*
X1579281Y-26693D03*
X1573455Y117261D03*
X1565909Y180527D03*
X1569632Y192421D03*
X1565864Y185121D03*
X1571625Y333549D03*
X1579340Y396240D03*
Y403327D03*
Y410413D03*
X1566555Y414823D03*
X1565863Y422864D03*
X1579340Y417500D03*
Y424586D03*
X1565933Y429832D03*
X1565538Y436447D03*
X1579340Y431673D03*
Y438760D03*
X1567573Y447953D03*
X1579340Y445847D03*
X1566740Y467539D03*
X1565482Y472772D03*
X1579340Y474626D03*
Y488799D03*
X1566216Y487711D03*
X1566329Y479104D03*
X1579340Y481712D03*
Y495886D03*
X1566740D03*
X1579340Y518760D03*
X1565050Y511673D03*
X1579340Y540020D03*
Y532933D03*
Y525846D03*
X1574222Y629872D03*
X1569926Y668885D03*
X1575950Y662981D03*
X1570331Y691851D03*
X1575942Y705043D03*
X1575708Y1345597D03*
X1570752Y1350683D03*
Y1345597D03*
X1575708Y1350683D03*
X1570752Y1357603D03*
Y1362595D03*
X1575708D03*
Y1357603D03*
Y1381801D03*
Y1374881D03*
Y1369889D03*
X1570752D03*
Y1381801D03*
Y1374881D03*
X1575708Y1386793D03*
Y1399079D03*
Y1393993D03*
X1570752Y1386793D03*
Y1393993D03*
Y1399079D03*
X1575708Y1405999D03*
Y1410991D03*
X1570752Y1405999D03*
Y1410991D03*
X1572000Y1644980D03*
X1586256Y-64207D03*
X1583003D03*
X1586241Y-66722D03*
X1582988D03*
X1589281Y-65613D03*
X1582822Y60922D03*
X1580327Y57448D03*
X1580986Y113394D03*
X1583635Y110784D03*
X1591229Y133298D03*
X1583229D03*
X1585376Y134579D03*
X1581162Y180665D03*
Y172665D03*
X1581194Y212864D03*
Y200864D03*
Y221864D03*
Y216864D03*
X1582951Y252371D03*
X1586640Y389153D03*
X1581840D03*
Y403326D03*
Y410413D03*
X1586640D03*
X1581840Y396240D03*
X1586640D03*
Y403326D03*
Y417499D03*
X1581840D03*
Y424586D03*
X1586640D03*
X1581840Y438760D03*
X1586640D03*
Y431673D03*
X1581840D03*
X1586640Y467539D03*
X1581840D03*
Y474626D03*
X1586640D03*
X1581840Y488799D03*
X1586640D03*
X1581840Y481712D03*
X1586640D03*
X1581840Y518760D03*
Y511673D03*
X1586640D03*
Y518760D03*
Y525846D03*
Y532933D03*
X1581840D03*
Y525846D03*
X1595185Y543925D03*
X1595760Y555000D03*
X1583720Y560500D03*
X1587948Y1350683D03*
Y1345691D03*
X1582992D03*
Y1350683D03*
X1587948Y1362595D03*
Y1357603D03*
X1582992Y1362595D03*
Y1357603D03*
Y1369889D03*
Y1381801D03*
Y1374881D03*
X1587948Y1369889D03*
Y1381801D03*
Y1374881D03*
X1582992Y1399079D03*
Y1394087D03*
Y1386793D03*
X1587948Y1399079D03*
Y1394087D03*
Y1386793D03*
X1582992Y1405999D03*
Y1410991D03*
X1587948Y1405999D03*
Y1410991D03*
X1592020Y1433061D03*
X1591610Y1469940D03*
X1591586Y1505130D03*
X1609272Y109410D03*
X1601972Y116497D03*
X1609272D03*
X1606772D03*
X1596221Y109172D03*
X1599221D03*
X1598228Y106495D03*
X1601972Y123584D03*
Y130670D03*
X1606772Y123584D03*
X1609272Y123583D03*
Y130670D03*
X1606772D03*
Y137757D03*
X1597962Y146012D03*
X1599868Y141228D03*
X1601972Y137757D03*
X1602756Y150847D03*
X1604724Y247292D03*
X1597433Y253198D03*
X1608240Y329000D03*
X1603664Y342596D03*
X1598223Y351003D03*
X1599127Y375587D03*
X1596714Y383003D03*
X1614338Y636842D03*
X1610620Y1345691D03*
Y1350683D03*
Y1357603D03*
Y1362595D03*
Y1381801D03*
Y1374881D03*
Y1369889D03*
Y1386793D03*
X1597225Y1437014D03*
X1603363Y1460570D03*
X1597457Y1452556D03*
X1598500Y1472500D03*
X1606745Y1474242D03*
X1602580Y1483108D03*
X1598000Y1486000D03*
X1604000Y1516000D03*
X1600700Y1534300D03*
X1622434Y82984D03*
Y80384D03*
Y75184D03*
Y77784D03*
X1624988Y92849D03*
X1622434Y85584D03*
X1613972Y116496D03*
Y102323D03*
Y109410D03*
Y130670D03*
Y123583D03*
Y137756D03*
X1625952Y431029D03*
X1626260Y427017D03*
X1625018Y435029D03*
X1625938Y449873D03*
X1625565Y472579D03*
Y479666D03*
Y486752D03*
Y493839D03*
Y523800D03*
Y516713D03*
Y537973D03*
Y530886D03*
Y566752D03*
Y588013D03*
Y573839D03*
Y580926D03*
Y602186D03*
Y595099D03*
Y609272D03*
Y616359D03*
X1620244Y638125D03*
X1617843Y665140D03*
X1613110Y678462D03*
X1624148Y708258D03*
X1627455Y759489D03*
X1619612Y783152D03*
X1620359Y774830D03*
X1619569Y796035D03*
X1620755Y787530D03*
X1613235Y808466D03*
X1620479Y815730D03*
X1620072Y801630D03*
X1616255Y824405D03*
X1619859Y839519D03*
X1615576Y1345691D03*
Y1350683D03*
X1622860D03*
Y1345691D03*
X1627816Y1350683D03*
Y1345691D03*
X1615576Y1357603D03*
Y1362595D03*
X1622860Y1357603D03*
Y1362595D03*
X1627816Y1357603D03*
Y1362595D03*
X1622860Y1381801D03*
Y1369795D03*
Y1374881D03*
X1627816Y1381801D03*
Y1369795D03*
Y1374881D03*
X1615576Y1381801D03*
Y1374881D03*
Y1369889D03*
Y1386793D03*
X1622860D03*
Y1393993D03*
Y1399079D03*
X1627816Y1386793D03*
Y1399079D03*
Y1393993D03*
X1622860Y1405999D03*
Y1410991D03*
X1627816Y1405999D03*
Y1410991D03*
X1618800Y1528558D03*
X1614200Y1519500D03*
X1614360Y1542860D03*
X1618600Y1532000D03*
X1631948Y103037D03*
X1632082Y116496D03*
Y109410D03*
Y130670D03*
Y123583D03*
X1628673Y137756D03*
X1644880Y226141D03*
X1644777Y288190D03*
X1642277Y285690D03*
X1644777D03*
X1642277Y288190D03*
X1636763Y293796D03*
X1634263D03*
X1635987Y335616D03*
X1630703Y350655D03*
X1636468Y345595D03*
X1636271Y410394D03*
Y403307D03*
X1637665Y458406D03*
Y451319D03*
X1637489Y462264D03*
X1632865Y465492D03*
X1637665D03*
Y472579D03*
X1632865D03*
X1630365D03*
Y479666D03*
X1632865D03*
X1637665Y479665D03*
Y486752D03*
X1630365D03*
X1632865D03*
X1630365Y493839D03*
X1637665D03*
X1632865Y509626D03*
Y516713D03*
X1630365D03*
Y523800D03*
X1632865D03*
X1637665Y523799D03*
Y516713D03*
Y509626D03*
X1630365Y530886D03*
X1637665D03*
X1632865D03*
X1637665Y537973D03*
X1630365D03*
X1637665Y559665D03*
Y566752D03*
X1630365D03*
X1632865D03*
Y559665D03*
Y573839D03*
X1630365Y580926D03*
X1632865D03*
X1637665D03*
Y588012D03*
X1630365Y588013D03*
X1632865Y588012D03*
X1637665Y573839D03*
X1630365D03*
X1632865Y602185D03*
X1630365Y602186D03*
X1637665Y602185D03*
Y595099D03*
X1632865D03*
X1630365D03*
Y616359D03*
X1632865Y609272D03*
X1630365D03*
X1637665Y616358D03*
Y609272D03*
X1637526Y699930D03*
X1637472Y717830D03*
X1631031Y732430D03*
X1628813Y727045D03*
X1631187Y750630D03*
X1629969Y740826D03*
X1644304Y891353D03*
X1640056Y1345691D03*
Y1350683D03*
X1635100Y1345691D03*
Y1350683D03*
X1640056Y1357603D03*
Y1362595D03*
X1635100D03*
Y1357603D03*
X1640056Y1369889D03*
Y1374881D03*
Y1381801D03*
X1635100Y1369889D03*
Y1374881D03*
Y1381801D03*
X1640056Y1399079D03*
Y1394087D03*
Y1386793D03*
X1635100Y1394087D03*
Y1399079D03*
Y1386793D03*
Y1405999D03*
Y1410991D03*
X1640056Y1405999D03*
Y1410991D03*
X1649365Y94017D03*
X1657374D03*
X1653365D03*
X1645365D03*
X1659895Y117557D03*
X1654485Y110445D03*
Y115401D03*
X1649493Y110445D03*
Y115401D03*
X1659895Y122513D03*
Y131731D03*
X1654485Y124618D03*
Y129574D03*
X1649493Y124618D03*
Y129574D03*
X1659895Y136687D03*
X1647406Y151540D03*
X1651056Y191941D03*
X1657556Y184619D03*
X1650923Y188727D03*
X1659536Y206760D03*
X1647680Y226141D03*
X1660750Y256535D03*
X1652750D03*
X1647577Y285690D03*
Y288190D03*
X1655803Y290755D03*
X1651803D03*
X1659803D03*
X1645685Y390500D03*
X1655335Y381500D03*
X1653507Y470136D03*
X1655776Y465492D03*
X1655742Y460250D03*
X1655776Y472579D03*
Y486752D03*
Y479665D03*
Y493839D03*
Y509626D03*
Y516713D03*
X1652236Y537973D03*
X1654716Y525483D03*
X1654637Y532756D03*
X1655776Y559665D03*
Y566752D03*
X1655626Y579978D03*
X1655776Y573839D03*
X1655840Y608117D03*
X1654572Y771702D03*
X1645128Y929263D03*
X1645342Y962120D03*
X1657091Y990823D03*
X1649571Y983857D03*
X1647340Y1350683D03*
Y1345691D03*
X1652296Y1350683D03*
Y1345691D03*
X1659580Y1350683D03*
Y1345691D03*
X1647340Y1357603D03*
Y1362595D03*
X1652296Y1357603D03*
Y1362595D03*
X1659580D03*
Y1357603D03*
X1647340Y1381801D03*
Y1374881D03*
Y1369889D03*
X1652296Y1381801D03*
Y1374881D03*
Y1369889D03*
X1659580Y1374881D03*
Y1369889D03*
Y1381801D03*
X1647340Y1386793D03*
Y1394087D03*
Y1399079D03*
X1652296Y1386793D03*
Y1399079D03*
Y1394087D03*
X1659580D03*
Y1399079D03*
Y1386793D03*
X1647340Y1405999D03*
Y1410991D03*
X1652296Y1405999D03*
Y1410991D03*
X1659580Y1405999D03*
Y1410991D03*
X1657983Y1460782D03*
X1649322Y1456451D03*
Y1465913D03*
X1657983Y1465513D03*
X1649322Y1461182D03*
Y1476536D03*
X1657983Y1476136D03*
Y1470244D03*
X1649322Y1471805D03*
Y1481267D03*
X1657983Y1480867D03*
X1649322Y1487159D03*
Y1496621D03*
X1657983Y1496221D03*
X1649322Y1491890D03*
X1657983Y1491490D03*
Y1485598D03*
Y1500952D03*
X1649322Y1502514D03*
X1657983Y1511576D03*
X1649322Y1511976D03*
Y1507245D03*
X1657983Y1506845D03*
Y1516307D03*
X1649322Y1558813D03*
Y1563544D03*
X1657983Y1563144D03*
Y1572606D03*
X1649322Y1574167D03*
Y1568275D03*
X1657983Y1567875D03*
X1649322Y1578898D03*
X1657983Y1578498D03*
X1649322Y1583629D03*
X1657983Y1583229D03*
X1649322Y1594253D03*
X1657983Y1593853D03*
Y1587960D03*
X1649322Y1589522D03*
Y1609607D03*
X1657983Y1609207D03*
X1649322Y1598984D03*
X1657983Y1598584D03*
Y1603315D03*
X1649322Y1604876D03*
Y1614338D03*
X1657983Y1613938D03*
Y1618669D03*
X1652000Y1644980D03*
X1662442Y84140D03*
Y76140D03*
Y80140D03*
X1675817Y117261D03*
X1664887Y117557D03*
Y122513D03*
Y131731D03*
X1662986Y146461D03*
X1664887Y136687D03*
X1661888Y152367D03*
X1663588Y180572D03*
X1668271Y180527D03*
X1671994Y192421D03*
X1663588Y185165D03*
X1668226Y185121D03*
X1661780Y279208D03*
X1665884Y281307D03*
X1669767Y445908D03*
X1673717Y445787D03*
X1664536Y1350683D03*
Y1345691D03*
X1671820D03*
Y1350683D03*
X1676776Y1345691D03*
Y1350683D03*
X1664536Y1357603D03*
Y1362595D03*
X1671820Y1357603D03*
Y1362595D03*
X1676776Y1357603D03*
Y1362595D03*
X1664536Y1374881D03*
Y1369889D03*
Y1381801D03*
X1671820Y1374881D03*
Y1381801D03*
Y1369889D03*
X1676776D03*
Y1374881D03*
Y1381801D03*
X1664536Y1394087D03*
Y1399079D03*
Y1386793D03*
X1671820D03*
Y1394087D03*
Y1399079D03*
X1676776Y1386793D03*
Y1399079D03*
Y1394087D03*
X1664536Y1405999D03*
Y1410991D03*
X1671820Y1405999D03*
Y1410991D03*
X1676776Y1405999D03*
Y1410991D03*
X1666645Y1465913D03*
Y1456451D03*
Y1461182D03*
X1675306Y1465513D03*
Y1460782D03*
X1666645Y1471805D03*
Y1476536D03*
Y1481267D03*
X1675306Y1476136D03*
Y1470244D03*
Y1480867D03*
X1666645Y1487159D03*
Y1491890D03*
Y1496621D03*
X1675306Y1491490D03*
Y1485598D03*
Y1496221D03*
Y1511576D03*
X1666645Y1511976D03*
Y1507245D03*
Y1502514D03*
X1675306Y1506845D03*
Y1500952D03*
Y1516307D03*
X1666645Y1558813D03*
Y1563544D03*
X1675306Y1563144D03*
Y1578498D03*
Y1572606D03*
X1666645Y1568275D03*
X1675306Y1567875D03*
X1666645Y1574167D03*
Y1578898D03*
Y1583629D03*
X1675306Y1583229D03*
X1666645Y1589522D03*
Y1594253D03*
X1675306Y1593853D03*
Y1587960D03*
X1666645Y1604876D03*
Y1598984D03*
X1675306Y1609207D03*
Y1598584D03*
Y1603315D03*
X1666645Y1609607D03*
Y1614338D03*
X1675306Y1613938D03*
Y1618669D03*
X1672000Y1644980D03*
X1685184Y60922D03*
X1680020Y55513D03*
X1683348Y113394D03*
X1685997Y110784D03*
X1686171Y130898D03*
X1693591Y133298D03*
X1687738Y134579D03*
X1683524Y172665D03*
Y180665D03*
X1683556Y200864D03*
Y212864D03*
Y221864D03*
Y216864D03*
X1685313Y252371D03*
X1687164Y336324D03*
X1678072Y342319D03*
X1691743Y353506D03*
X1680518Y385912D03*
Y393924D03*
Y389912D03*
Y409924D03*
Y405924D03*
Y401924D03*
X1677933Y418838D03*
X1689016Y1345691D03*
Y1350683D03*
X1684060D03*
Y1345691D03*
X1689016Y1362595D03*
Y1357603D03*
X1684060D03*
Y1362595D03*
X1689016Y1369889D03*
Y1381801D03*
Y1374881D03*
X1684060Y1369889D03*
Y1381801D03*
Y1374881D03*
X1689016Y1394087D03*
Y1399079D03*
Y1386793D03*
X1684060Y1394087D03*
Y1399079D03*
Y1386793D03*
X1689016Y1405999D03*
Y1410991D03*
X1684060Y1405999D03*
Y1410991D03*
X1683968Y1465913D03*
Y1456451D03*
Y1461182D03*
X1692629Y1465513D03*
Y1460782D03*
X1683968Y1471805D03*
Y1476536D03*
Y1481267D03*
X1692629Y1476136D03*
Y1470244D03*
Y1480867D03*
X1683968Y1487159D03*
Y1491890D03*
Y1496621D03*
X1692629Y1491490D03*
Y1485598D03*
Y1496221D03*
X1683968Y1502514D03*
Y1511976D03*
X1692629Y1506845D03*
Y1500952D03*
Y1511576D03*
X1683968Y1507245D03*
X1692629Y1516307D03*
X1683968Y1558813D03*
Y1563544D03*
X1692629Y1563144D03*
Y1572606D03*
X1683968Y1568275D03*
Y1574167D03*
Y1578898D03*
X1692629Y1567875D03*
Y1578498D03*
X1683968Y1583629D03*
Y1589522D03*
Y1594253D03*
X1692629Y1583229D03*
Y1593853D03*
Y1587960D03*
X1683968Y1598984D03*
X1692629Y1609207D03*
Y1598584D03*
Y1603315D03*
X1683968Y1609607D03*
Y1604876D03*
Y1614338D03*
X1692629Y1613938D03*
Y1618669D03*
X1692000Y1644980D03*
X1698583Y109172D03*
X1701583D03*
X1700590Y106495D03*
X1709134Y116497D03*
X1704334D03*
X1709134Y123584D03*
Y130670D03*
X1704334Y123584D03*
Y130670D03*
X1700324Y146012D03*
X1702230Y141228D03*
X1709134Y137757D03*
X1704334D03*
X1705118Y150847D03*
X1707086Y247292D03*
X1699795Y253198D03*
X1701495Y289735D03*
X1695142Y303839D03*
X1708889Y1189221D03*
X1696300Y1350683D03*
Y1345691D03*
X1701256Y1350683D03*
Y1345691D03*
X1708540D03*
Y1350683D03*
X1696300Y1357603D03*
Y1362595D03*
X1701256Y1357603D03*
Y1362595D03*
X1708540D03*
Y1357603D03*
X1696300Y1374881D03*
Y1369889D03*
Y1381801D03*
X1701256Y1369889D03*
Y1381801D03*
Y1374881D03*
X1708540D03*
Y1369889D03*
Y1381801D03*
X1696300Y1386793D03*
Y1394087D03*
Y1399079D03*
X1701256Y1386793D03*
Y1394087D03*
Y1399079D03*
X1708540D03*
Y1394087D03*
Y1386793D03*
X1696300Y1405999D03*
Y1410991D03*
X1701256Y1405999D03*
Y1410991D03*
X1708540Y1405999D03*
Y1410991D03*
X1701290Y1465913D03*
Y1456451D03*
Y1461182D03*
Y1471805D03*
Y1476536D03*
Y1481267D03*
Y1487159D03*
Y1491890D03*
Y1496621D03*
Y1507245D03*
Y1502514D03*
Y1511976D03*
Y1558813D03*
Y1563544D03*
Y1568275D03*
Y1574167D03*
Y1578898D03*
Y1583629D03*
Y1589522D03*
Y1594253D03*
Y1609607D03*
Y1604876D03*
Y1598984D03*
Y1614338D03*
X1724796Y82984D03*
Y77784D03*
Y80384D03*
Y75184D03*
Y85584D03*
X1716334Y116496D03*
Y109410D03*
Y102323D03*
X1711634Y116497D03*
Y109410D03*
X1716334Y130670D03*
Y123583D03*
X1711634D03*
Y130670D03*
X1716334Y137756D03*
X1720960Y1148000D03*
X1723796Y1160168D03*
X1725660Y1193019D03*
X1721660D03*
X1711783Y1193848D03*
X1713496Y1350683D03*
Y1345691D03*
X1720780Y1350683D03*
Y1345597D03*
X1725736Y1350683D03*
Y1345597D03*
X1713496Y1357603D03*
Y1362595D03*
X1720780Y1357603D03*
Y1362595D03*
X1725736Y1357603D03*
Y1362595D03*
X1713496Y1374881D03*
Y1369889D03*
Y1381801D03*
X1720780Y1369889D03*
Y1381801D03*
Y1374881D03*
X1725736Y1381801D03*
Y1374881D03*
Y1369889D03*
X1713496Y1399079D03*
Y1394087D03*
Y1386793D03*
X1720780D03*
Y1393993D03*
Y1399079D03*
X1725736Y1386793D03*
Y1399079D03*
Y1393993D03*
X1713496Y1405999D03*
Y1410991D03*
X1720780Y1405999D03*
Y1410991D03*
X1725736Y1405999D03*
Y1410991D03*
X1709952Y1465513D03*
Y1460782D03*
X1718613Y1465914D03*
Y1456452D03*
Y1461183D03*
Y1476537D03*
Y1471806D03*
Y1481268D03*
X1709952Y1476136D03*
Y1470244D03*
Y1480867D03*
Y1491490D03*
Y1485598D03*
Y1496221D03*
X1718613Y1491891D03*
Y1487160D03*
Y1496622D03*
Y1502515D03*
Y1511977D03*
X1709952Y1506845D03*
Y1500952D03*
Y1511576D03*
X1718613Y1507246D03*
X1709952Y1516307D03*
Y1563144D03*
X1718613Y1563544D03*
Y1558813D03*
X1709952Y1567875D03*
X1718613Y1568275D03*
X1709952Y1578498D03*
Y1572606D03*
X1718613Y1578898D03*
Y1574167D03*
Y1589522D03*
X1709952Y1583229D03*
X1718613Y1583629D03*
X1709952Y1593853D03*
Y1587960D03*
X1718613Y1594253D03*
Y1609607D03*
Y1598984D03*
Y1604876D03*
X1709952Y1609207D03*
Y1598584D03*
Y1603315D03*
Y1618669D03*
X1718613Y1614338D03*
X1709952Y1613938D03*
X1712000Y1644980D03*
X1727350Y92849D03*
X1734310Y103037D03*
X1734444Y116496D03*
Y109410D03*
Y130670D03*
Y123583D03*
X1730647Y137756D03*
X1739125Y293796D03*
X1736625D03*
X1737703Y472189D03*
X1728038Y491870D03*
X1730538D03*
X1730675Y1132361D03*
X1726963Y1132319D03*
X1739917Y1146937D03*
X1729207Y1159455D03*
X1737393Y1162817D03*
X1733660Y1193019D03*
X1729660D03*
X1737660D03*
X1733695Y1212164D03*
X1735989Y1214458D03*
X1731619Y1210089D03*
X1740785Y1219254D03*
X1737976Y1350683D03*
Y1345691D03*
X1733020D03*
Y1350683D03*
X1737976Y1362595D03*
Y1357603D03*
X1733020Y1362595D03*
Y1357603D03*
X1737976Y1369889D03*
Y1374881D03*
X1733020Y1369889D03*
Y1381801D03*
Y1374881D03*
X1737976Y1381801D03*
Y1399079D03*
Y1394087D03*
Y1386793D03*
X1733020Y1399079D03*
Y1394087D03*
Y1386793D03*
X1737976Y1405999D03*
Y1410991D03*
X1733020Y1405999D03*
Y1410991D03*
X1732000Y1644980D03*
X1755727Y94017D03*
X1747727D03*
X1751727D03*
X1751855Y110445D03*
Y115401D03*
X1756847D03*
Y110445D03*
X1751855Y129574D03*
Y124618D03*
X1756847D03*
Y129574D03*
X1753418Y191941D03*
X1753285Y188727D03*
X1747242Y226141D03*
X1750042D03*
X1755112Y256535D03*
X1749939Y288190D03*
X1747139D03*
X1744639D03*
X1749939Y285690D03*
X1744639D03*
X1747139D03*
X1758165Y290755D03*
X1754165D03*
X1744524Y370010D03*
X1753474Y542699D03*
X1757402Y825111D03*
Y820155D03*
X1744937Y912517D03*
X1747937D03*
X1750751Y910785D03*
X1748081Y984379D03*
X1756192Y996132D03*
X1743224Y1119055D03*
X1752000Y1644980D03*
X1764804Y84140D03*
Y76140D03*
Y80140D03*
X1759736Y94017D03*
X1767249Y117557D03*
X1762257D03*
Y122513D03*
Y131731D03*
X1767249Y122513D03*
Y131731D03*
X1762257Y136687D03*
X1767249D03*
X1765950Y180572D03*
X1770633Y180527D03*
X1774356Y192421D03*
X1759918Y184619D03*
X1770588Y185121D03*
X1765950Y185165D03*
X1761898Y206760D03*
X1763112Y256535D03*
X1764142Y279208D03*
X1768246Y281307D03*
X1762165Y290755D03*
X1765497Y370899D03*
X1766204Y398949D03*
X1770778Y402642D03*
X1773278D03*
X1763704Y401949D03*
X1767953Y413611D03*
X1770453D03*
X1772953D03*
X1772893Y423944D03*
X1770393D03*
X1767893D03*
X1765093D03*
X1765153Y413611D03*
X1764912Y482382D03*
X1765006Y478382D03*
X1761953Y706827D03*
Y865160D03*
X1772599Y993053D03*
X1762898Y992883D03*
X1764744Y1101930D03*
Y1097879D03*
X1766899Y1121122D03*
X1769499D03*
X1772099D03*
X1774799D03*
X1766999Y1130822D03*
X1772199D03*
X1769599D03*
X1774339Y1437975D03*
X1774216Y1470165D03*
X1772000Y1644980D03*
X1788884Y59871D03*
X1782382Y55513D03*
X1778179Y117261D03*
X1785886Y172665D03*
Y180665D03*
X1785918Y200864D03*
Y212864D03*
Y216864D03*
Y221864D03*
X1790014Y468607D03*
X1784602Y564092D03*
X1782600Y874500D03*
X1774899Y1130822D03*
Y1139822D03*
X1777399D03*
Y1147822D03*
X1774899D03*
X1785961Y1224892D03*
X1791099Y1260421D03*
X1779868Y1446668D03*
X1786564Y1478858D03*
X1777131Y1604357D03*
X1791570Y74535D03*
X1793149Y662810D03*
X1798705Y718793D03*
X1805013Y1091877D03*
X1792847Y1099210D03*
X1799012Y1095893D03*
X1805013Y1096470D03*
X1792863Y1103246D03*
X1801147Y1208555D03*
X1802844Y1227695D03*
X1793976Y1440762D03*
X1807270Y1468535D03*
X1793879Y1472952D03*
X1792000Y1644980D03*
X1816322Y977215D03*
X1823074Y992833D03*
X1812296Y1075688D03*
X1809696Y1091832D03*
X1809651Y1096426D03*
X1823028Y1124289D03*
X1817728D03*
X1815128D03*
X1820328D03*
X1822928Y1114589D03*
X1820228D03*
X1815028D03*
X1817628D03*
X1815865Y1133356D03*
X1809897Y1237285D03*
Y1230385D03*
Y1232885D03*
Y1239785D03*
Y1244185D03*
Y1246685D03*
X1807393Y1436345D03*
X1812000Y1644980D03*
X1831511Y978888D03*
X1831914Y992877D03*
X1824706Y1081145D03*
Y1089145D03*
X1837933Y1636171D03*
X1832000Y1644980D03*
G54D35*
X141337Y1228542D03*
X141336Y1247242D03*
Y1239762D03*
X161909Y1129429D03*
X160039Y1228543D03*
X169389Y1121948D03*
X167519Y1198621D03*
Y1213582D03*
X174999Y1228543D03*
X182480D03*
X167519D03*
X189960D03*
X197440D03*
X210531Y1211712D03*
X212401Y1228543D03*
X204921D03*
X213969Y1453293D03*
Y1464293D03*
X218011Y1211712D03*
X227362Y1228543D03*
X219881D03*
X227249Y1464293D03*
Y1453293D03*
X294685Y1127558D03*
Y1135039D03*
Y1194881D03*
Y1202362D03*
X290944Y1191141D03*
X294685Y1209842D03*
X302165Y1108858D03*
X298425Y1112598D03*
X309645D03*
Y1120078D03*
X305905Y1116338D03*
X298425Y1120078D03*
X305905Y1123818D03*
X309645Y1135039D03*
Y1127558D03*
X311515Y1136909D03*
X304035Y1140649D03*
X305905Y1131299D03*
X296555Y1151869D03*
X304035Y1155610D03*
Y1148129D03*
X296555Y1144389D03*
X311515D03*
Y1151869D03*
X296555Y1159350D03*
Y1166830D03*
X304035Y1170570D03*
X300295D03*
X311515Y1159350D03*
X300295Y1185531D03*
Y1178051D03*
X296555Y1174310D03*
X298425Y1187401D03*
X304035Y1185531D03*
Y1178051D03*
Y1193011D03*
X302165Y1198621D03*
X305905Y1206102D03*
X302165Y1213582D03*
Y1206102D03*
X298425Y1221062D03*
Y1217322D03*
X317125Y1116338D03*
Y1123818D03*
X313385D03*
Y1116338D03*
X315255Y1136909D03*
X313384Y1131299D03*
X315255Y1144389D03*
Y1151869D03*
Y1159350D03*
Y1166830D03*
Y1181791D03*
Y1189271D03*
Y1174310D03*
X313385Y1198621D03*
Y1206102D03*
X320866Y1217322D03*
X317125Y1221062D03*
X313385Y1213582D03*
X324606Y1209842D03*
Y1217322D03*
X320866Y1236023D03*
Y1224803D03*
X324606Y1232283D03*
Y1236023D03*
Y1224803D03*
Y1243503D03*
X598424Y1228542D03*
X598423Y1239762D03*
Y1247242D03*
X618996Y1129429D03*
X617126Y1228543D03*
X626476Y1121948D03*
X624606Y1198621D03*
Y1213582D03*
X632086Y1228543D03*
X624606D03*
X639567D03*
X647047D03*
X667618Y1211712D03*
X654527Y1228543D03*
X662008D03*
X669488D03*
X675098Y1211712D03*
X676968Y1228543D03*
X684449D03*
X748031Y1194881D03*
X762992Y1116338D03*
X766732Y1120078D03*
X762992Y1123818D03*
X766732Y1112598D03*
X759252Y1108858D03*
X755512Y1120078D03*
X761122Y1140649D03*
X762992Y1131299D03*
X766732Y1135039D03*
Y1127558D03*
X751772D03*
Y1135039D03*
X753642Y1144389D03*
X761122Y1148129D03*
Y1155610D03*
X753642Y1151869D03*
X757382Y1170570D03*
X761122D03*
X753642Y1166830D03*
Y1159350D03*
Y1181791D03*
Y1174310D03*
X757382Y1178051D03*
Y1185531D03*
X761122Y1178051D03*
Y1185531D03*
X753642Y1189271D03*
X759252Y1191141D03*
X762992D03*
X755512Y1194881D03*
X759252Y1198621D03*
X751772Y1202362D03*
X755512Y1221062D03*
Y1217322D03*
X759252Y1213582D03*
X762992Y1206102D03*
X759252D03*
X751772Y1209842D03*
X770472Y1123818D03*
X774212D03*
X770472Y1116338D03*
X774212D03*
X770471Y1131299D03*
X770472Y1138779D03*
X772342Y1151869D03*
Y1144389D03*
X768602Y1151869D03*
Y1144389D03*
X772342Y1166830D03*
X768602Y1159350D03*
X772342D03*
Y1174310D03*
Y1181791D03*
Y1196751D03*
X770472Y1198621D03*
X781693Y1217322D03*
X777953D03*
X774212Y1221062D03*
X781693Y1209842D03*
X770472Y1213582D03*
Y1206102D03*
X781693Y1224803D03*
X777953D03*
X781693Y1232283D03*
X777953Y1236023D03*
X781693D03*
Y1243503D03*
X1055510Y1228542D03*
X1055509Y1239762D03*
Y1247242D03*
X1074212Y1228543D03*
X1083562Y1121948D03*
X1076082Y1129429D03*
X1081692Y1198621D03*
Y1213582D03*
Y1228543D03*
X1089172D03*
X1104133D03*
X1096653D03*
X1124704Y1211712D03*
X1119094Y1228543D03*
X1111613D03*
X1132184Y1211712D03*
X1126574Y1228543D03*
X1134054D03*
X1141535D03*
X1203247Y1193011D03*
X1216338Y1108858D03*
X1212598Y1120078D03*
X1220078Y1116338D03*
Y1123818D03*
X1218208Y1140649D03*
X1208858Y1127558D03*
X1220078Y1131299D03*
X1208858Y1135039D03*
X1210728Y1151869D03*
X1218208Y1155610D03*
Y1148129D03*
X1210728Y1144389D03*
Y1159350D03*
Y1166830D03*
X1218208Y1170570D03*
X1214468D03*
X1210728Y1181791D03*
Y1189271D03*
X1218208Y1185531D03*
Y1178051D03*
X1214468Y1185531D03*
Y1178051D03*
X1210728Y1174310D03*
X1212598Y1194881D03*
X1218208Y1193011D03*
X1214468D03*
X1216338Y1198621D03*
X1208858Y1202362D03*
X1220078Y1206102D03*
X1216338D03*
X1212598Y1221062D03*
Y1217322D03*
X1216338Y1213582D03*
X1208858Y1209842D03*
X1223818Y1112598D03*
Y1120078D03*
X1227558Y1116338D03*
X1231298D03*
X1227558Y1123818D03*
X1231298D03*
X1229428Y1136909D03*
X1223818Y1127558D03*
X1227557Y1131299D03*
X1223818Y1135039D03*
X1225688Y1144389D03*
Y1151869D03*
X1229428Y1144389D03*
Y1151869D03*
Y1159350D03*
X1225688D03*
X1229428Y1166830D03*
Y1181791D03*
Y1189271D03*
Y1174310D03*
Y1196751D03*
X1227558Y1198621D03*
Y1206102D03*
X1235039Y1217322D03*
X1231298Y1221062D03*
X1227558Y1213582D03*
X1235039Y1224803D03*
Y1236023D03*
X1238779Y1217322D03*
Y1209842D03*
Y1224803D03*
Y1232283D03*
Y1236023D03*
Y1243503D03*
X1514468Y1166829D03*
Y1174309D03*
Y1181790D03*
X1512597Y1228542D03*
X1512596Y1239762D03*
Y1247242D03*
X1540649Y1121948D03*
X1533169Y1129429D03*
X1538779Y1198621D03*
Y1213582D03*
X1531299Y1228543D03*
X1538779D03*
X1546259D03*
X1561220D03*
X1553740D03*
X1576181D03*
X1568700D03*
X1589271Y1211712D03*
X1581791D03*
X1583661Y1228543D03*
X1591141D03*
X1598622D03*
X1660334Y1204232D03*
Y1200491D03*
Y1193011D03*
Y1196751D03*
Y1207972D03*
X1673425Y1108858D03*
X1669685Y1112598D03*
Y1120078D03*
X1675295Y1140649D03*
X1665945Y1127558D03*
Y1135039D03*
X1667815Y1151869D03*
X1675295Y1155610D03*
Y1148129D03*
X1667815Y1144389D03*
Y1159350D03*
Y1166830D03*
X1675295Y1170570D03*
X1671555D03*
Y1185531D03*
Y1178051D03*
X1667815Y1174310D03*
Y1181791D03*
Y1189271D03*
X1675295Y1185531D03*
Y1178051D03*
X1669685Y1194881D03*
X1675295Y1193011D03*
X1671555D03*
X1665945Y1202362D03*
X1673425Y1198621D03*
X1669685Y1221062D03*
Y1217322D03*
X1673425Y1213582D03*
X1665945Y1209842D03*
X1673425Y1206102D03*
X1677165Y1116338D03*
X1680905Y1112598D03*
X1677165Y1123818D03*
X1680905Y1120078D03*
X1684645Y1116338D03*
X1688385D03*
X1684645Y1123818D03*
X1688385D03*
X1686515Y1136909D03*
X1682775D03*
X1680905Y1127558D03*
X1677165Y1131299D03*
X1684644D03*
X1680905Y1135039D03*
X1682775Y1144389D03*
Y1151869D03*
X1686515Y1144389D03*
Y1151869D03*
Y1159350D03*
X1682775D03*
X1686515Y1166830D03*
Y1174310D03*
Y1181791D03*
Y1189271D03*
X1684645Y1198621D03*
X1692126Y1217322D03*
X1688385Y1221062D03*
X1684645Y1213582D03*
Y1206102D03*
X1677165D03*
X1692126Y1224803D03*
Y1236023D03*
X1695866Y1217322D03*
Y1209842D03*
Y1232283D03*
Y1236023D03*
Y1224803D03*
Y1243503D03*
G54D27*
X73872Y1348187D03*
X81752D03*
X73872Y1360099D03*
X81752D03*
X73872Y1384297D03*
Y1372385D03*
X81752Y1384297D03*
Y1372385D03*
X86112Y1348187D03*
X98352D03*
X93992D03*
X86112Y1360099D03*
X98352D03*
X93992D03*
X86112Y1384297D03*
Y1372385D03*
X98352Y1384297D03*
Y1372385D03*
X93992D03*
Y1384297D03*
X86112Y1396583D03*
X93992D03*
X98352D03*
X86112Y1408495D03*
X93992D03*
X98352D03*
X110592Y1348187D03*
X106232D03*
X110592Y1360099D03*
X106232D03*
X110592Y1384297D03*
X106232D03*
Y1372385D03*
X110592D03*
Y1396583D03*
X106232D03*
X110592Y1408495D03*
X106232D03*
X118472Y1348187D03*
X122832D03*
X130712D03*
X118472Y1360099D03*
X122832D03*
X130712D03*
X118472Y1384297D03*
Y1372385D03*
X122832Y1384297D03*
Y1372385D03*
X130712Y1384297D03*
Y1372385D03*
X118472Y1396583D03*
X122832D03*
X130712D03*
X118472Y1408495D03*
X122832D03*
X130712D03*
X146948Y1080806D03*
Y1103247D03*
X143208D03*
X146948Y1133169D03*
Y1140649D03*
X139468Y1136909D03*
X143208Y1125688D03*
Y1133169D03*
Y1140649D03*
X146948Y1125688D03*
X143208Y1144389D03*
Y1151870D03*
X146948Y1144389D03*
Y1151870D03*
X140707Y1170569D03*
X143208Y1159350D03*
X146948D03*
X148818Y1183661D03*
X140707Y1178050D03*
X145078Y1187401D03*
Y1183661D03*
X148818Y1187401D03*
X146947Y1174310D03*
X141337Y1191142D03*
X145078Y1194881D03*
Y1202362D03*
X148818Y1194881D03*
Y1202362D03*
X141337Y1198622D03*
Y1206103D03*
X145078Y1209842D03*
Y1217322D03*
X148818Y1209842D03*
Y1217322D03*
X141337Y1213583D03*
Y1221063D03*
X148818Y1224803D03*
X145078Y1232283D03*
Y1236023D03*
X148818Y1232283D03*
Y1236023D03*
X145078Y1224803D03*
X148818Y1254724D03*
X135072Y1348187D03*
X142952D03*
X147312D03*
X135072Y1360099D03*
X147312D03*
X142952D03*
X135072Y1384297D03*
Y1372385D03*
X147312Y1384297D03*
Y1372385D03*
X142952Y1384297D03*
Y1372385D03*
X135072Y1396583D03*
X147312D03*
X142952D03*
X135072Y1408495D03*
X147312D03*
X142952D03*
X150688Y1077066D03*
X158169Y1106988D03*
X165649D03*
X161909D03*
X158169Y1118208D03*
Y1121948D03*
X154429D03*
X150689D03*
X165649Y1114468D03*
X161909D03*
X158169Y1133169D03*
X161909Y1140649D03*
X158169Y1125688D03*
X154429Y1129429D03*
X150689D03*
Y1136909D03*
X154429Y1140649D03*
X150689D03*
X165649D03*
Y1129429D03*
Y1136909D03*
X158169Y1140649D03*
X150689Y1151870D03*
X158169Y1155610D03*
X154429D03*
X150689D03*
X161909Y1144389D03*
Y1148129D03*
Y1151870D03*
Y1155610D03*
X150689Y1144389D03*
Y1148129D03*
Y1159350D03*
X158169Y1166830D03*
X150688D03*
X154429Y1170570D03*
X150688D03*
X161909Y1159350D03*
X160039Y1187401D03*
X156299Y1183661D03*
X152559D03*
X161909Y1174310D03*
Y1178051D03*
X165649Y1181791D03*
X161909D03*
X158169Y1174310D03*
X154429D03*
X150688Y1178051D03*
Y1174310D03*
X156299Y1179921D03*
X160039Y1183661D03*
X163779D03*
X156299Y1198621D03*
X152559D03*
X163779D03*
X160039D03*
X152559Y1191141D03*
X156299D03*
X160039D03*
X163779D03*
X160039Y1206102D03*
X156299D03*
X152559D03*
X163779D03*
X156299Y1213582D03*
X152559D03*
X160039Y1221062D03*
X156299D03*
X152559D03*
X163779D03*
X152559Y1228543D03*
X160039Y1224803D03*
X152559D03*
X156299Y1232283D03*
Y1236023D03*
X163779D03*
Y1232283D03*
X160039Y1239763D03*
X152559D03*
Y1243503D03*
X160039D03*
X163779Y1239763D03*
X152559Y1258465D03*
X160039D03*
X159552Y1348187D03*
X155192D03*
X159552Y1360099D03*
X155192D03*
X159552Y1372385D03*
Y1384297D03*
X155192D03*
Y1372385D03*
X159552Y1396583D03*
X155192D03*
X159552Y1408495D03*
X155192D03*
X174998Y1071455D03*
X182479D03*
X178740Y1090157D03*
X174999D03*
X171259D03*
X182480D03*
X178740Y1093897D03*
Y1097637D03*
X174999Y1101377D03*
X169389Y1106988D03*
X171259Y1093897D03*
X174999Y1105117D03*
X182480Y1101377D03*
Y1105117D03*
X174999Y1108858D03*
X178740D03*
X176870Y1114468D03*
Y1118208D03*
Y1121948D03*
X178740Y1112598D03*
X173129Y1110728D03*
X169389D03*
X180610Y1114468D03*
Y1118208D03*
Y1121948D03*
X182480Y1112598D03*
Y1108858D03*
X180610Y1136909D03*
X173129Y1133169D03*
X169389D03*
X176870Y1140649D03*
Y1125688D03*
Y1129429D03*
Y1133169D03*
Y1136909D03*
X173129Y1140649D03*
X169389D03*
X180610D03*
Y1125688D03*
Y1129429D03*
Y1133169D03*
Y1148129D03*
X173129Y1144389D03*
X169389D03*
X173129Y1148129D03*
Y1155610D03*
Y1151870D03*
X180610Y1155610D03*
Y1151870D03*
Y1144389D03*
X176870Y1170570D03*
X173129Y1159350D03*
Y1166830D03*
Y1170570D03*
X180610Y1166830D03*
Y1159350D03*
Y1174310D03*
Y1181791D03*
X173129Y1174310D03*
Y1178051D03*
Y1181791D03*
X171259Y1187401D03*
X174999D03*
X180610Y1178051D03*
X167519Y1183661D03*
X178740Y1187401D03*
X182480D03*
X176870Y1185531D03*
X173129D03*
X171259Y1202362D03*
Y1194881D03*
X174999Y1202362D03*
Y1194881D03*
X167519Y1191141D03*
X178740D03*
Y1194881D03*
Y1198621D03*
Y1202362D03*
X182480Y1191141D03*
Y1198621D03*
Y1202362D03*
X171259Y1209842D03*
X174999Y1217322D03*
X171259Y1221062D03*
X174999D03*
X171259Y1217322D03*
X167519Y1206102D03*
X178740D03*
Y1209842D03*
Y1213582D03*
Y1221062D03*
X182480D03*
X178740Y1217322D03*
X182480Y1206102D03*
Y1209842D03*
Y1213582D03*
Y1217322D03*
X178740Y1232283D03*
Y1236023D03*
X171259Y1232283D03*
X174999Y1224803D03*
X171259Y1236023D03*
X182480Y1224803D03*
X167519D03*
X182480Y1243503D03*
X171259Y1250984D03*
X174999Y1247243D03*
Y1239763D03*
X171259D03*
X167519D03*
Y1243503D03*
X175000Y1258465D03*
X182480D03*
X167519D03*
X167432Y1348187D03*
X171792D03*
X179672D03*
X167432Y1360099D03*
X171792D03*
X179672D03*
X167432Y1384297D03*
Y1372385D03*
X171792Y1384297D03*
Y1372385D03*
X179672Y1384297D03*
Y1372385D03*
X171792Y1396583D03*
X179672D03*
X167432D03*
Y1408495D03*
X171792D03*
X179672D03*
X197439Y1071455D03*
X189959D03*
X193700Y1090157D03*
X189960D03*
X186220D03*
X197440D03*
X193700Y1093897D03*
X189960Y1101377D03*
X186220Y1097637D03*
X189960Y1105117D03*
X186220Y1093897D03*
X193700Y1097637D03*
X197440Y1101377D03*
Y1105117D03*
X195570Y1121948D03*
X191830Y1118208D03*
X188090D03*
X184350D03*
X191830Y1121948D03*
X188090D03*
X184350D03*
X195570Y1118208D03*
X186220Y1108858D03*
X189960D03*
X193700D03*
X197440D03*
X191830Y1125688D03*
X188090D03*
X184350D03*
X188090Y1129429D03*
X184350D03*
X188090Y1133169D03*
X184350D03*
X188090Y1136909D03*
Y1140649D03*
X184350D03*
X195570Y1133169D03*
Y1129429D03*
Y1125688D03*
Y1136909D03*
X188090Y1144389D03*
Y1151870D03*
X191830Y1155610D03*
Y1148129D03*
X195570Y1151869D03*
Y1144389D03*
X188090Y1159350D03*
Y1170570D03*
X191830Y1166830D03*
X195570Y1159350D03*
Y1170570D03*
X188090Y1185531D03*
X195570Y1189271D03*
X191830Y1181791D03*
Y1174310D03*
X195570Y1185531D03*
Y1178051D03*
X188090Y1196751D03*
Y1200491D03*
Y1204232D03*
X191830D03*
Y1196751D03*
Y1200491D03*
X184350Y1193011D03*
Y1196751D03*
X195570Y1200491D03*
Y1196751D03*
Y1193011D03*
Y1204232D03*
X186220Y1198621D03*
X193700Y1209842D03*
X191830Y1207972D03*
X189960Y1209842D03*
X195570Y1207972D03*
X193700Y1213582D03*
X191830Y1219192D03*
X186220Y1221062D03*
X189960D03*
X193700D03*
X197440D03*
X186220Y1206102D03*
Y1209842D03*
Y1213582D03*
X197440Y1209842D03*
Y1224803D03*
X193700Y1232283D03*
X186220D03*
X189960Y1224803D03*
X193700Y1236023D03*
X186220D03*
X197440Y1239763D03*
Y1243503D03*
X193700Y1239763D03*
X186220D03*
X189960Y1243503D03*
Y1258465D03*
X197441D03*
X184032Y1348187D03*
X191912D03*
X196272D03*
X184032Y1360099D03*
X196272D03*
X191912D03*
X184032Y1384297D03*
Y1372385D03*
X196272Y1384297D03*
Y1372385D03*
X191912Y1384297D03*
Y1372385D03*
X184032Y1396583D03*
X191912D03*
X196272D03*
X184032Y1408495D03*
X191912D03*
X196272D03*
X204920Y1071455D03*
X212400D03*
X204921Y1090157D03*
X212401D03*
X208661D03*
X201181D03*
X204921Y1101377D03*
X208661Y1097637D03*
X201181D03*
X204921Y1105117D03*
X212401Y1101377D03*
Y1105117D03*
X201181Y1093897D03*
X208661D03*
X199311Y1118208D03*
Y1121948D03*
X206791Y1118208D03*
X203051D03*
Y1121948D03*
X206791D03*
X210531Y1118208D03*
X214271Y1110728D03*
X210531Y1121948D03*
X214271Y1118208D03*
Y1121948D03*
X201181Y1108858D03*
X204921D03*
X208661D03*
X212401D03*
X199311Y1140649D03*
X203051D03*
X206791D03*
X199311Y1125688D03*
X203051D03*
X206791D03*
Y1133169D03*
X203051D03*
X199311D03*
X210531D03*
Y1140649D03*
X214271D03*
Y1125688D03*
X210531D03*
X214271Y1133169D03*
X203051Y1148129D03*
X199311D03*
X206791D03*
X214271D03*
X210531D03*
X199311Y1155610D03*
X206791D03*
X214271D03*
X206791Y1166830D03*
X203051Y1159350D03*
X199311Y1166830D03*
X203051Y1170570D03*
X214271Y1166830D03*
X210531Y1159350D03*
Y1170570D03*
X206791Y1181791D03*
X203051D03*
X199311D03*
X206791Y1189271D03*
X203051D03*
X199311D03*
X214271Y1181791D03*
X210531D03*
X214271Y1189271D03*
X210531D03*
X199311Y1174310D03*
X206791D03*
X214271D03*
X206791Y1196751D03*
X203051D03*
X199311D03*
Y1204232D03*
X203051D03*
X206791D03*
X214271Y1196751D03*
X210531D03*
Y1204232D03*
X214271D03*
X206791Y1207972D03*
X203051D03*
X199311D03*
X210531D03*
X214271D03*
X212401Y1221062D03*
X208661D03*
X204921D03*
X201181D03*
X212401Y1224803D03*
X208661Y1232283D03*
X201181D03*
X204921Y1224803D03*
X201181Y1236023D03*
X208661D03*
X212401Y1243503D03*
X208661Y1239763D03*
X204921Y1243503D03*
X212401Y1258465D03*
X204921D03*
X204152Y1348187D03*
Y1360099D03*
Y1384297D03*
Y1372385D03*
Y1396583D03*
Y1408495D03*
X219880Y1071455D03*
X227361D03*
X227362Y1090157D03*
X223622D03*
X219881D03*
X231102D03*
X216141D03*
X223622Y1093897D03*
X231102D03*
Y1097637D03*
X227362Y1101377D03*
Y1105117D03*
X219881Y1101377D03*
Y1105117D03*
X223622Y1097637D03*
X216141D03*
Y1093897D03*
X225492Y1118208D03*
Y1121948D03*
X218011Y1118208D03*
X221751D03*
X218011Y1121948D03*
X221751D03*
X229232D03*
Y1118208D03*
Y1114468D03*
X216141Y1108858D03*
X219881D03*
X223622D03*
X227362D03*
X231102D03*
X225492Y1133169D03*
Y1140649D03*
Y1125688D03*
X218011Y1140649D03*
X221751D03*
X218011Y1125688D03*
X221751D03*
Y1133169D03*
X218011D03*
X229330Y1132677D03*
X229232Y1140649D03*
Y1125688D03*
X225492Y1148129D03*
X221751D03*
X218011D03*
X229232D03*
X221751Y1155610D03*
X229232D03*
X225492Y1170570D03*
Y1159350D03*
X218011Y1170570D03*
X221752Y1166830D03*
X218011Y1159350D03*
X229232Y1166830D03*
X225492Y1181791D03*
Y1189271D03*
X221751Y1181791D03*
X218011D03*
X221751Y1189271D03*
X218011D03*
X229232Y1181791D03*
Y1189271D03*
X221751Y1174310D03*
X229232D03*
X218011Y1204232D03*
X229232Y1196751D03*
Y1204232D03*
X225492Y1196751D03*
Y1204232D03*
X221751D03*
Y1196751D03*
X218011D03*
X225492Y1207972D03*
X221751D03*
X218011D03*
X229232D03*
X231102Y1221062D03*
X227362D03*
X219881Y1217322D03*
X223622Y1221062D03*
X219881D03*
X216141D03*
X227362Y1224803D03*
X223622Y1232283D03*
X219881Y1224803D03*
X223622Y1236023D03*
X231102Y1232283D03*
Y1236023D03*
X216141Y1232283D03*
Y1236023D03*
X223622Y1239763D03*
X231102D03*
X227362Y1243503D03*
X219881D03*
X216141Y1239763D03*
X219882Y1258465D03*
X227363D03*
X246062Y1075196D03*
X234841Y1071454D03*
X242321Y1071455D03*
X238582Y1075196D03*
X234842Y1090157D03*
X246062D03*
Y1078936D03*
X238582Y1090157D03*
X242322Y1086417D03*
X234842Y1082677D03*
Y1086417D03*
X242322Y1090157D03*
X246062Y1097637D03*
Y1093897D03*
X242322Y1105117D03*
X234842Y1101377D03*
X238582Y1093897D03*
X242322Y1101377D03*
X234842Y1105117D03*
X236712Y1121948D03*
X240452D03*
X244192D03*
X234842Y1108858D03*
X238582D03*
X242322D03*
X246062D03*
X236712Y1133464D03*
X240452Y1133169D03*
X236712Y1140649D03*
X240452D03*
X236712Y1125688D03*
X240452D03*
X244192Y1133169D03*
Y1140649D03*
Y1125688D03*
X236712Y1148129D03*
X240452D03*
X244192D03*
X240452Y1155610D03*
Y1166830D03*
X236712Y1170570D03*
Y1159350D03*
X244192Y1170570D03*
Y1159350D03*
X240452Y1181791D03*
X236712D03*
Y1189271D03*
X240452D03*
X244192Y1181791D03*
Y1189271D03*
X240452Y1174310D03*
Y1204232D03*
X236712D03*
Y1196751D03*
X240452D03*
X244192Y1204232D03*
Y1196751D03*
X240452Y1207972D03*
Y1211712D03*
X242322Y1221062D03*
X244192Y1211712D03*
Y1207972D03*
X236712D03*
X234842Y1221062D03*
X238582D03*
X246062Y1232283D03*
Y1236023D03*
X238582Y1232283D03*
X234842Y1228543D03*
Y1224803D03*
X238582Y1236023D03*
X242322Y1228543D03*
Y1224803D03*
X246062Y1239763D03*
X238582D03*
X234842Y1258465D03*
X242322D03*
X239383Y1348187D03*
X247263D03*
Y1360099D03*
X239383D03*
X247263Y1384297D03*
Y1372385D03*
X239383Y1384297D03*
Y1372385D03*
X253543Y1075196D03*
X261023D03*
X249802Y1071455D03*
X257282D03*
X253543Y1090157D03*
X249803D03*
Y1086417D03*
X253543Y1078936D03*
X257283Y1090157D03*
Y1086417D03*
X261023Y1090157D03*
Y1078936D03*
X249803Y1105117D03*
X253543Y1093897D03*
Y1097637D03*
X257283Y1105117D03*
X261023Y1093897D03*
Y1097637D03*
X255413Y1121948D03*
X251673D03*
X247933D03*
X262893D03*
X259153D03*
X249803Y1108858D03*
X253543D03*
X257283D03*
X261023D03*
X247933Y1133169D03*
X251673D03*
X255413D03*
X247933Y1140649D03*
X251673D03*
X255413D03*
X247933Y1125688D03*
X251673D03*
X255413D03*
X259153Y1133169D03*
X262893D03*
Y1140649D03*
X259153Y1125688D03*
X262893D03*
X259153Y1140649D03*
Y1148129D03*
X262893D03*
Y1155610D03*
X247933Y1148129D03*
X251673D03*
X255413D03*
X247933Y1155610D03*
X255413D03*
X262893Y1166830D03*
X251673Y1170570D03*
X255413Y1166830D03*
X247933D03*
X251673Y1159350D03*
X259153D03*
Y1170570D03*
X247933Y1181791D03*
X251673D03*
X255413D03*
X247933Y1189271D03*
X251673D03*
X255413D03*
X262893D03*
Y1174310D03*
X259153Y1181791D03*
X262893D03*
X259153Y1189271D03*
X255413Y1174310D03*
X247933D03*
Y1204232D03*
X255413D03*
X251673D03*
X247933Y1196751D03*
X251673D03*
X255413D03*
X259153Y1204232D03*
X262893D03*
X259153Y1196751D03*
X262893D03*
X247933Y1207972D03*
X251673D03*
X255413Y1211712D03*
Y1207972D03*
X262893D03*
X259153D03*
X262893Y1211712D03*
X259153D03*
X249803Y1228543D03*
X257283D03*
X249803Y1224803D03*
X253543Y1236023D03*
X257283Y1224803D03*
X261023Y1236023D03*
X253543Y1232283D03*
X261023D03*
X257283Y1239763D03*
X249803Y1258465D03*
X257283D03*
X263863Y1348187D03*
X259503D03*
X251623D03*
X263863Y1360099D03*
X259503D03*
X251623D03*
X263863Y1384297D03*
Y1372385D03*
X259503Y1384297D03*
Y1372385D03*
X251623D03*
Y1384297D03*
X263863Y1396583D03*
X259503D03*
X251623D03*
X263863Y1408495D03*
X259503D03*
X251623D03*
X279723Y1071455D03*
X264762D03*
X272243D03*
X268503Y1075196D03*
X275984D03*
X279724Y1090157D03*
X272244Y1082677D03*
X275984Y1090157D03*
X272244Y1086417D03*
X268503Y1078936D03*
Y1090157D03*
X264763Y1086417D03*
X272244Y1090157D03*
X264763D03*
X268503Y1093897D03*
Y1097637D03*
X272244Y1105117D03*
X279724D03*
X275984Y1093897D03*
X264763Y1105117D03*
X274114Y1118208D03*
X270373D03*
X266633Y1121948D03*
X270373D03*
X277854Y1118208D03*
X264763Y1108858D03*
X268503D03*
X272244D03*
X275984D03*
X279724D03*
X274114Y1125688D03*
X270373Y1136909D03*
X266633Y1133169D03*
X270373D03*
X266633Y1140649D03*
X270373Y1125688D03*
Y1129429D03*
X266633Y1125688D03*
X270373Y1140649D03*
X277854Y1136909D03*
Y1140649D03*
X274114Y1155610D03*
Y1151869D03*
Y1148129D03*
X266633D03*
X270373Y1144389D03*
Y1148129D03*
Y1151869D03*
X277854Y1144389D03*
Y1148129D03*
Y1151870D03*
X270373Y1155610D03*
X274114Y1166830D03*
Y1159350D03*
Y1170570D03*
X266633Y1181791D03*
X270373Y1189271D03*
X277854Y1178051D03*
Y1189271D03*
Y1185531D03*
X270373Y1174310D03*
X277854Y1181791D03*
X274114D03*
Y1174310D03*
X266633Y1189271D03*
X270373Y1178051D03*
Y1185531D03*
X274114Y1196751D03*
X270393Y1196732D03*
X270373Y1204232D03*
X266633D03*
X270373Y1200491D03*
X266633Y1196751D03*
X270373Y1193011D03*
X277854D03*
X274114Y1207972D03*
X270373Y1211712D03*
X266633Y1207972D03*
Y1211712D03*
X270373Y1207972D03*
X277854Y1211712D03*
X279724Y1221062D03*
X275984D03*
X272244D03*
X268503D03*
X279724Y1224803D03*
X272244D03*
X268503Y1236023D03*
Y1232283D03*
X272244Y1228543D03*
X264763Y1224803D03*
X275984Y1232283D03*
Y1236023D03*
X264763Y1228543D03*
X279724D03*
X268503Y1239763D03*
X279724Y1258465D03*
X264763D03*
X272244D03*
X276103Y1348187D03*
X271743D03*
X276103Y1360099D03*
X271743D03*
X276103Y1384297D03*
Y1372385D03*
X271743Y1384297D03*
Y1372385D03*
X276103Y1396583D03*
X271743D03*
Y1408495D03*
X276103D03*
X294684Y1071455D03*
X290944Y1075196D03*
X287203Y1071455D03*
X283464Y1075196D03*
X287204Y1090157D03*
X283464Y1078936D03*
Y1090157D03*
X290943D03*
X290944Y1093897D03*
X287204Y1101377D03*
Y1105117D03*
X294685D03*
X294684Y1120078D03*
Y1112598D03*
X283464Y1108858D03*
X287204D03*
X290944D03*
X294685D03*
X290944Y1112598D03*
Y1116338D03*
Y1120078D03*
Y1123818D03*
X281594Y1140649D03*
Y1136909D03*
X290944Y1127558D03*
Y1131299D03*
Y1135039D03*
Y1138779D03*
X281594Y1148129D03*
Y1155610D03*
Y1151869D03*
X285334D03*
X289074D03*
Y1155610D03*
X292814Y1151869D03*
Y1144389D03*
X281594Y1159350D03*
X289074Y1166830D03*
Y1170570D03*
Y1159350D03*
X281594Y1170570D03*
Y1166830D03*
X292814Y1159350D03*
Y1166830D03*
Y1181791D03*
X285334Y1185531D03*
X289074Y1174310D03*
Y1178051D03*
Y1185531D03*
X281594Y1189271D03*
Y1185531D03*
X285334Y1181791D03*
X281594Y1178051D03*
Y1174310D03*
X292814D03*
Y1189271D03*
X281594Y1196751D03*
Y1204232D03*
Y1193011D03*
X285334D03*
X290944Y1194881D03*
Y1198621D03*
Y1202362D03*
X294685Y1221062D03*
Y1217322D03*
X290944Y1221062D03*
X287204D03*
X283464D03*
X290944Y1206102D03*
Y1209842D03*
Y1213582D03*
Y1217322D03*
X294685Y1228543D03*
Y1224803D03*
X290944Y1232283D03*
Y1236023D03*
X283464Y1232283D03*
X287204Y1228543D03*
X283464Y1236023D03*
X287204Y1224803D03*
X283464Y1239763D03*
X290944D03*
X294685Y1258465D03*
X287204D03*
X288343Y1348187D03*
X296223D03*
X283983D03*
X288343Y1360099D03*
X296223D03*
X283983D03*
X288343Y1384297D03*
Y1372385D03*
X296223Y1384297D03*
Y1372385D03*
X283983D03*
Y1384297D03*
X288343Y1396583D03*
X296223D03*
X283983D03*
X288343Y1408495D03*
X296223D03*
X283983D03*
X309645Y1071455D03*
X302165D03*
X298425Y1075196D03*
X305906D03*
X298424Y1090157D03*
X298426Y1078936D03*
X305906D03*
X302165Y1105117D03*
X309645D03*
X298425Y1093897D03*
X305905D03*
X302165Y1123818D03*
X305904Y1108857D03*
X302165Y1116338D03*
X298425Y1108858D03*
X300295Y1140649D03*
X302165Y1131299D03*
X300295Y1148129D03*
Y1159350D03*
Y1166830D03*
X311515D03*
X307775Y1170570D03*
X300295Y1181791D03*
Y1174310D03*
Y1189271D03*
X311515Y1174310D03*
X307775Y1178051D03*
X311515Y1181791D03*
X307775Y1185531D03*
X311515Y1189271D03*
X298425Y1202362D03*
Y1194881D03*
X309645Y1198621D03*
X307775Y1193011D03*
X311515Y1196751D03*
X305905Y1198621D03*
X309645Y1202362D03*
X298425Y1209842D03*
X302165Y1221062D03*
X309645Y1217322D03*
Y1209842D03*
X305905Y1213582D03*
X309645D03*
Y1206102D03*
Y1221062D03*
X305905D03*
X298425Y1236023D03*
Y1232283D03*
X302165Y1228543D03*
Y1224803D03*
X305905Y1232283D03*
X309645Y1228543D03*
Y1224803D03*
X305905Y1236023D03*
X298425Y1239763D03*
X309645D03*
Y1258465D03*
X302165D03*
X308463Y1348187D03*
X300583D03*
X308463Y1360099D03*
X300583D03*
X308463Y1372385D03*
X300583D03*
Y1384297D03*
X308463D03*
Y1396583D03*
X300583D03*
X308463Y1408495D03*
X300583D03*
X317125Y1071455D03*
X320866Y1075196D03*
X313386D03*
X320866Y1078936D03*
X313384Y1090157D03*
X313386Y1078936D03*
X328347Y1082677D03*
Y1090158D03*
X324606Y1078936D03*
X313385Y1093897D03*
X328347Y1101378D03*
Y1116339D03*
Y1123819D03*
Y1108859D03*
X313385Y1108858D03*
X328347Y1131300D03*
X318996Y1140649D03*
Y1155610D03*
Y1148129D03*
X322736Y1170570D03*
X318996D03*
Y1185531D03*
Y1178051D03*
X322736D03*
Y1185531D03*
X328347Y1198621D03*
X322736Y1193011D03*
X320866Y1202362D03*
X318996Y1193011D03*
X326416D03*
X324606Y1202362D03*
X328347Y1206102D03*
Y1221062D03*
Y1213582D03*
X320866Y1209842D03*
X313385Y1221062D03*
X320866Y1232283D03*
X313385D03*
X317125Y1228543D03*
Y1224803D03*
X313385Y1236023D03*
X328347Y1228543D03*
Y1239762D03*
Y1247243D03*
X324606Y1250984D03*
X317125Y1258465D03*
X320703Y1348187D03*
X312823D03*
X325063D03*
X320703Y1360099D03*
X312823D03*
X325063D03*
X320703Y1372385D03*
Y1384297D03*
X312823Y1372385D03*
Y1384297D03*
X325063Y1372385D03*
Y1384297D03*
Y1396583D03*
X320703D03*
X312823D03*
X320703Y1408495D03*
X312823D03*
X325063D03*
X318448Y1750941D03*
Y1760941D03*
X318348Y1796941D03*
Y1806941D03*
X337303Y1348187D03*
X332943D03*
Y1360099D03*
X337303D03*
X332943Y1384297D03*
Y1372385D03*
X337303D03*
Y1384297D03*
X332943Y1396583D03*
X337303D03*
X332943Y1408495D03*
X337303D03*
X349543Y1348187D03*
X357423D03*
X345183D03*
X349543Y1360099D03*
X357423D03*
X345183D03*
Y1372385D03*
Y1384297D03*
X349543D03*
Y1372385D03*
X357423D03*
Y1384297D03*
X345183Y1396583D03*
X349543D03*
X357423D03*
X345183Y1408495D03*
X349543D03*
X357423D03*
X369663Y1348187D03*
X361783D03*
X369663Y1360099D03*
X361783D03*
X369663Y1372385D03*
Y1384297D03*
X361783D03*
Y1372385D03*
X369663Y1396583D03*
X361783D03*
X369663Y1408495D03*
X361783D03*
X458282Y1348187D03*
X446042D03*
X458282Y1360099D03*
X446042D03*
X458282Y1372385D03*
X446042D03*
X458282Y1384297D03*
X446042D03*
X458282Y1396583D03*
Y1408495D03*
X470522Y1348187D03*
Y1360099D03*
Y1384297D03*
Y1372385D03*
Y1396583D03*
Y1408495D03*
X482762Y1348187D03*
Y1360099D03*
Y1384297D03*
Y1372385D03*
Y1396583D03*
Y1408495D03*
X507242Y1348187D03*
X495002D03*
X507242Y1360099D03*
X495002D03*
Y1384297D03*
X507242D03*
X495002Y1372385D03*
X507242D03*
Y1396583D03*
X495002D03*
X507242Y1408495D03*
X495002D03*
X519482Y1348187D03*
Y1360099D03*
Y1384297D03*
Y1372385D03*
Y1396583D03*
Y1408495D03*
X531722Y1348187D03*
Y1360099D03*
Y1384297D03*
Y1372385D03*
Y1396583D03*
Y1408495D03*
X556202Y1348187D03*
X543962D03*
X556202Y1360099D03*
X543962D03*
Y1372385D03*
Y1384297D03*
X556202D03*
Y1372385D03*
Y1396583D03*
X543962D03*
X556202Y1408495D03*
X543962D03*
X568442Y1348187D03*
Y1360099D03*
Y1384297D03*
Y1372385D03*
Y1396583D03*
Y1408495D03*
X604035Y1080806D03*
Y1103247D03*
X600295D03*
Y1125688D03*
Y1133169D03*
Y1140649D03*
X604035Y1125688D03*
Y1133169D03*
Y1140649D03*
X600295Y1144389D03*
Y1151870D03*
X604035Y1144389D03*
Y1151870D03*
X600295Y1159350D03*
X604035D03*
X597795Y1170570D03*
X604034Y1174310D03*
X597795Y1178050D03*
X602165Y1183661D03*
Y1187401D03*
Y1202362D03*
Y1194881D03*
X598424Y1198622D03*
Y1191142D03*
X602165Y1217322D03*
Y1209842D03*
X598424Y1221063D03*
Y1213583D03*
Y1206103D03*
X602165Y1224803D03*
Y1236023D03*
Y1232283D03*
X605386Y1728583D03*
Y1738583D03*
X605312Y1774624D03*
Y1784624D03*
X607775Y1077066D03*
X615256Y1106988D03*
X618996D03*
X615256Y1118208D03*
Y1121948D03*
X611516D03*
X607776D03*
X618996Y1114468D03*
X615256Y1125688D03*
X611516Y1129429D03*
X607776D03*
Y1136909D03*
X615256Y1140649D03*
X611516D03*
X607776D03*
X618996D03*
Y1144389D03*
Y1148129D03*
Y1151870D03*
Y1155610D03*
X607776Y1144389D03*
Y1148129D03*
Y1151870D03*
X615256Y1155610D03*
X611516D03*
X607776D03*
Y1159350D03*
X615256Y1166830D03*
X607775D03*
X611516Y1170570D03*
X607775D03*
X618996Y1159350D03*
Y1174310D03*
Y1178051D03*
X607775Y1174310D03*
Y1178051D03*
X611516Y1174310D03*
X615256D03*
X613386Y1183661D03*
X617126Y1187401D03*
Y1183661D03*
X613386Y1179921D03*
X620866Y1183661D03*
X609646D03*
X605905D03*
Y1187401D03*
X613386Y1198621D03*
X609646Y1191141D03*
X613386D03*
X617126Y1198621D03*
X620866D03*
X617126Y1191141D03*
X620866D03*
X605905Y1202362D03*
Y1194881D03*
X609646Y1198621D03*
X613386Y1221062D03*
X609646D03*
Y1213582D03*
X613386D03*
X620866Y1206102D03*
X617126D03*
X620866Y1221062D03*
X617126D03*
X613386Y1206102D03*
X605905Y1217322D03*
Y1209842D03*
X609646Y1206102D03*
X605905Y1224803D03*
Y1232283D03*
Y1236023D03*
X620866D03*
Y1232283D03*
X617126Y1224803D03*
X609646D03*
Y1228543D03*
X613386Y1232283D03*
Y1236023D03*
X617126Y1243503D03*
Y1239763D03*
X620866D03*
X609646Y1243503D03*
Y1239763D03*
X617126Y1258465D03*
X609646D03*
X632085Y1071455D03*
X626476Y1092027D03*
X635827Y1090157D03*
X628346D03*
X632086D03*
X630216Y1099507D03*
X626476Y1106988D03*
X622736D03*
X626476Y1095767D03*
X630216Y1103247D03*
X635827Y1093897D03*
X632086Y1101377D03*
Y1105117D03*
X628346Y1093897D03*
X635827Y1097637D03*
X633957Y1110728D03*
X630216D03*
X626476D03*
X622736Y1114468D03*
X630216Y1118208D03*
X626476D03*
X633957Y1114468D03*
Y1118208D03*
Y1121948D03*
X635827Y1108858D03*
X632086D03*
X633957Y1140649D03*
Y1125688D03*
Y1129429D03*
Y1133169D03*
Y1136909D03*
X630216Y1140649D03*
X626476D03*
X622736D03*
Y1129429D03*
X630216Y1144389D03*
X626476D03*
X630216Y1148129D03*
Y1155610D03*
Y1151870D03*
Y1159350D03*
Y1166830D03*
Y1170570D03*
X633957D03*
Y1185531D03*
X628346Y1183661D03*
X630216Y1174310D03*
Y1178051D03*
Y1181791D03*
X632086Y1187401D03*
X628346D03*
X624606Y1183661D03*
X635827Y1187401D03*
X624606Y1191141D03*
X632086Y1202362D03*
X628346D03*
X632086Y1194881D03*
X628346D03*
X635827Y1191141D03*
Y1194881D03*
Y1198621D03*
Y1202362D03*
X624606Y1206102D03*
X628346Y1209842D03*
Y1217322D03*
Y1221062D03*
X632086D03*
Y1217322D03*
X635827Y1221062D03*
Y1206102D03*
Y1209842D03*
Y1213582D03*
Y1217322D03*
X632086Y1224803D03*
X624606D03*
X628346Y1236023D03*
Y1232283D03*
X635827Y1236023D03*
Y1232283D03*
X632086Y1247243D03*
Y1239763D03*
X628346D03*
Y1250984D03*
X624606Y1243503D03*
Y1239763D03*
X632087Y1258465D03*
X624606D03*
X631928Y1396583D03*
Y1408495D03*
X647046Y1071455D03*
X639566D03*
X643307Y1090157D03*
X639567D03*
X650787D03*
X647047D03*
X639567Y1101377D03*
Y1105117D03*
X647047D03*
Y1101377D03*
X650787Y1097637D03*
X643307D03*
Y1093897D03*
X650787D03*
X637697Y1114468D03*
X648917Y1118208D03*
X645177D03*
X641437D03*
X637697D03*
X648917Y1121948D03*
X645177D03*
X641437D03*
X637697D03*
Y1110728D03*
X652657Y1118208D03*
Y1121948D03*
X650787Y1108858D03*
X647047D03*
X643307D03*
X639567D03*
X641437Y1133169D03*
X637697D03*
X645177Y1136909D03*
X637697D03*
X645177Y1140649D03*
X641437D03*
X652657Y1133169D03*
Y1129429D03*
Y1125688D03*
Y1136909D03*
X637697Y1140649D03*
X648917Y1125688D03*
X645177D03*
X641437D03*
X637697D03*
X645177Y1129429D03*
X641437D03*
X637697D03*
X645177Y1133169D03*
X637697Y1155610D03*
Y1151870D03*
X645177Y1144389D03*
X637697D03*
Y1148129D03*
X645177Y1151870D03*
X648917Y1155610D03*
Y1148129D03*
X652657Y1151869D03*
Y1144389D03*
X645177Y1170570D03*
X637697Y1166830D03*
X645177Y1159350D03*
X637697D03*
X648917Y1166830D03*
X652657Y1159350D03*
Y1170570D03*
X637697Y1189271D03*
X645177Y1185531D03*
X637697D03*
Y1178051D03*
Y1174310D03*
Y1181791D03*
X652657Y1189271D03*
X648917Y1181791D03*
Y1174310D03*
X652657Y1185531D03*
Y1178051D03*
Y1193011D03*
Y1204232D03*
X637697Y1193011D03*
X645177Y1196751D03*
Y1200491D03*
X641437D03*
Y1204232D03*
X645177D03*
X648917D03*
Y1196751D03*
Y1200491D03*
X641437Y1193011D03*
Y1196751D03*
X652657Y1200491D03*
Y1196751D03*
Y1211712D03*
X648917Y1219192D03*
X641437D03*
Y1211712D03*
X645177D03*
X648917D03*
Y1207972D03*
X645177D03*
X641437D03*
X652657D03*
X639567Y1221062D03*
X647047D03*
X643307D03*
X650787D03*
X639567Y1224803D03*
X643307Y1236023D03*
Y1232283D03*
X650787Y1236023D03*
X647047Y1224803D03*
X650787Y1232283D03*
X639567Y1243503D03*
X647047D03*
X650787Y1239763D03*
X643307D03*
X647047Y1258465D03*
X639567D03*
X644168Y1384297D03*
Y1372385D03*
Y1396583D03*
Y1408495D03*
X669487Y1071455D03*
X662007D03*
X654526D03*
X669488Y1090157D03*
X665748D03*
X654527D03*
X658268D03*
X662008D03*
Y1101377D03*
X665748Y1093897D03*
X658268D03*
X654527Y1105117D03*
Y1101377D03*
X662008Y1105117D03*
X658268Y1097637D03*
X669488Y1101377D03*
Y1105117D03*
X665748Y1097637D03*
X656398Y1118208D03*
Y1121948D03*
X663878Y1118208D03*
X660138D03*
Y1121948D03*
X663878D03*
X667618Y1118208D03*
Y1121948D03*
X669488Y1108858D03*
X665748D03*
X662008D03*
X658268D03*
X654527D03*
X656398Y1140649D03*
X660138D03*
X663878D03*
X656398Y1125688D03*
X660138D03*
X663878D03*
Y1133169D03*
X660138D03*
X656398D03*
X667618D03*
Y1140649D03*
Y1125688D03*
Y1148129D03*
X660138D03*
X656398D03*
X663878D03*
X656398Y1155610D03*
X663878D03*
Y1166830D03*
X660138Y1159350D03*
X656398Y1166830D03*
X660138Y1170570D03*
X667618Y1159350D03*
Y1170570D03*
X663878Y1181791D03*
X660138D03*
X656398D03*
X663878Y1189271D03*
X660138D03*
X656398D03*
X667618Y1181791D03*
Y1189271D03*
X656398Y1174310D03*
X663878D03*
Y1196751D03*
X660138D03*
X656398D03*
Y1204232D03*
X660138D03*
X663878D03*
X667618Y1196751D03*
Y1204232D03*
X663878Y1207972D03*
X660138D03*
X656398D03*
X667618D03*
X654527Y1221062D03*
X658268D03*
X662008D03*
X665748D03*
X669488D03*
X654527Y1224803D03*
X658268Y1236023D03*
Y1232283D03*
X662008Y1224803D03*
X665748Y1236023D03*
Y1232283D03*
X669488Y1224803D03*
X654527Y1239763D03*
Y1243503D03*
X665748Y1239763D03*
X669488Y1243503D03*
X662008D03*
Y1258465D03*
X669488D03*
X654528D03*
X668648Y1348187D03*
X656408D03*
X668648Y1360099D03*
X656408D03*
Y1384297D03*
Y1372385D03*
X668648D03*
Y1384297D03*
Y1396583D03*
X656408D03*
X668648Y1408495D03*
X656408D03*
X684448Y1071455D03*
X676967D03*
X680709Y1090157D03*
X676968D03*
X684449D03*
X673228D03*
X676968Y1105117D03*
X684449Y1101377D03*
Y1105117D03*
X680709Y1093897D03*
X676968Y1101377D03*
X680709Y1097637D03*
X673228D03*
Y1093897D03*
X682579Y1118208D03*
Y1121948D03*
X671358Y1118208D03*
X675098D03*
X678838D03*
X675098Y1121948D03*
X678838D03*
X671358D03*
X684449Y1108858D03*
X680709D03*
X676968D03*
X673228D03*
X682579Y1133169D03*
Y1140649D03*
Y1125688D03*
X671358Y1140649D03*
X675098D03*
X678838D03*
X675098Y1125688D03*
X671358D03*
X678838D03*
Y1133169D03*
X675098D03*
X671358D03*
X682579Y1148129D03*
X678838D03*
X675098D03*
X671358D03*
Y1155610D03*
X678838D03*
X682579Y1170570D03*
Y1159350D03*
X675098Y1170570D03*
X678839Y1166830D03*
X671358D03*
X675098Y1159350D03*
Y1181791D03*
X671358D03*
X678838Y1189271D03*
X675098D03*
X671358D03*
X682579Y1181791D03*
Y1189271D03*
X678838Y1181791D03*
X671358Y1174310D03*
X678838D03*
X682579Y1196751D03*
Y1204232D03*
X678838D03*
Y1196751D03*
X675098D03*
X671358D03*
Y1204232D03*
X675098D03*
X682579Y1207972D03*
X678838Y1219192D03*
Y1207972D03*
X675098D03*
X671358D03*
X673228Y1221062D03*
X676968D03*
X680709D03*
X684449D03*
X673228Y1236023D03*
Y1232283D03*
X676968Y1224803D03*
X680709Y1236023D03*
Y1232283D03*
X684449Y1224803D03*
X673228Y1239763D03*
X680709D03*
X676968Y1243503D03*
X684449D03*
X684450Y1258465D03*
X676969D03*
X680888Y1348187D03*
Y1360099D03*
Y1372385D03*
Y1384297D03*
Y1396583D03*
Y1408495D03*
X695669Y1075196D03*
X699408Y1071455D03*
X691928Y1071454D03*
X688189Y1090157D03*
X691929Y1082677D03*
Y1086417D03*
X695669Y1090157D03*
X699409D03*
Y1086417D03*
X691929Y1090157D03*
X688189Y1097637D03*
X695669Y1093897D03*
X688189D03*
X699409Y1105117D03*
X691929Y1101377D03*
X699409D03*
X691929Y1105117D03*
X693799Y1121948D03*
X697539D03*
X701279D03*
X686319D03*
Y1118208D03*
Y1114468D03*
X699409Y1108858D03*
X695669D03*
X691929D03*
X688189D03*
X693799Y1133464D03*
X697539Y1133169D03*
X686417Y1132677D03*
X693799Y1140649D03*
X697539D03*
X693799Y1125688D03*
X697539D03*
X701279D03*
Y1140649D03*
Y1133169D03*
X686319Y1140649D03*
Y1125688D03*
X697539Y1148129D03*
X701279D03*
X693799D03*
X697539Y1155610D03*
X686319Y1148129D03*
Y1155610D03*
X697539Y1166830D03*
X693799Y1170570D03*
Y1159350D03*
X701279D03*
Y1170570D03*
X686319Y1166830D03*
X693799Y1181791D03*
Y1189271D03*
X697539D03*
X701279D03*
Y1181791D03*
X697539D03*
Y1174310D03*
X686319Y1181791D03*
Y1189271D03*
Y1174310D03*
X697539Y1204232D03*
X693799D03*
Y1196751D03*
X697539D03*
X701279D03*
Y1204232D03*
X686319Y1196751D03*
Y1204232D03*
X693799Y1207972D03*
X697539D03*
Y1211712D03*
X701279Y1207972D03*
Y1211712D03*
X686319Y1207972D03*
X695669Y1221062D03*
X699409D03*
X691929D03*
X688189D03*
Y1236023D03*
Y1232283D03*
X691929Y1224803D03*
Y1228543D03*
X699409Y1224803D03*
Y1228543D03*
X695669Y1236023D03*
Y1232283D03*
X688189Y1239763D03*
X695669D03*
X699409Y1258465D03*
X691929D03*
X693128Y1348187D03*
Y1360099D03*
Y1372385D03*
Y1384297D03*
Y1396583D03*
Y1408495D03*
X703149Y1075196D03*
X718110D03*
X710630D03*
X714369Y1071455D03*
X706889D03*
X710630Y1078936D03*
X706890Y1086417D03*
Y1090157D03*
X718110Y1078936D03*
X714370Y1086417D03*
Y1090157D03*
X710630D03*
X718110D03*
X703149Y1078936D03*
Y1090157D03*
X706890Y1105117D03*
X714370D03*
X710630Y1097637D03*
Y1093897D03*
X718110Y1097637D03*
Y1093897D03*
X703149D03*
Y1097637D03*
X716240Y1121948D03*
X705020D03*
X708760D03*
X712500D03*
X718110Y1108858D03*
X714370D03*
X710630D03*
X706890D03*
X703149D03*
X716240Y1140649D03*
Y1125688D03*
Y1133169D03*
X712500Y1125688D03*
X708760D03*
X705020D03*
X712500Y1140649D03*
X708760D03*
X705020D03*
X712500Y1133169D03*
X708760D03*
X705020D03*
X716240Y1148129D03*
X712500D03*
X708760D03*
X705020D03*
X712500Y1155610D03*
X705020D03*
X716240Y1170570D03*
Y1159350D03*
X708760D03*
X705020Y1166830D03*
X712500D03*
X708760Y1170570D03*
X716240Y1189271D03*
Y1181791D03*
X712500Y1189271D03*
X708760D03*
X705020D03*
X712500Y1181791D03*
X708760D03*
X705020D03*
Y1174310D03*
X712500D03*
X716240Y1196751D03*
Y1204232D03*
X712500Y1196751D03*
X708760D03*
X705020D03*
X708760Y1204232D03*
X712500D03*
X705020D03*
X716240Y1211712D03*
Y1207972D03*
X712500D03*
Y1211712D03*
X708760Y1207972D03*
X705020D03*
X703149Y1221062D03*
X706890D03*
X710630D03*
X714370D03*
X718110D03*
X703149Y1236023D03*
Y1232283D03*
X710630Y1236023D03*
X718110D03*
Y1232283D03*
X710630D03*
X714370Y1224803D03*
Y1228543D03*
X706890Y1224803D03*
Y1228543D03*
X703149Y1239763D03*
X714370D03*
Y1258465D03*
X706890D03*
X705368Y1348187D03*
X717608D03*
X705368Y1360099D03*
X717608D03*
X705368Y1372385D03*
Y1384297D03*
X717608Y1372385D03*
Y1384297D03*
Y1396583D03*
X705368D03*
X717608Y1408495D03*
X705368D03*
X725590Y1075196D03*
X733071D03*
X729330Y1071455D03*
X721849D03*
X729331Y1086417D03*
Y1082677D03*
X733071Y1090157D03*
X729331D03*
X725590D03*
X721850D03*
X725590Y1078936D03*
X721850Y1086417D03*
X725590Y1097637D03*
X721850Y1105117D03*
X725590Y1093897D03*
X729331Y1105117D03*
X733071Y1093897D03*
X734941Y1118208D03*
X727460Y1121948D03*
X719980D03*
X723720D03*
X727460Y1118208D03*
X731201D03*
X733071Y1108858D03*
X729331D03*
X725590D03*
X721850D03*
X734941Y1140649D03*
Y1136909D03*
X727460Y1140649D03*
X723720Y1125688D03*
X719980D03*
X727460Y1129429D03*
Y1125688D03*
X723720Y1140649D03*
X719980D03*
X727460Y1133169D03*
X723720D03*
X719980D03*
X727460Y1136909D03*
X731201Y1125688D03*
X727460Y1151869D03*
Y1148129D03*
Y1144389D03*
X723720Y1148129D03*
X719980D03*
X731201D03*
Y1151869D03*
Y1155610D03*
X734941Y1151870D03*
Y1148129D03*
Y1144389D03*
X719980Y1155610D03*
X727460D03*
X731201Y1170570D03*
X719980Y1166830D03*
X731201Y1159350D03*
Y1166830D03*
X727460Y1185531D03*
X734941Y1181791D03*
Y1185531D03*
Y1189271D03*
Y1178051D03*
X727460Y1189271D03*
X723720Y1181791D03*
X719980D03*
Y1174310D03*
X727460Y1178051D03*
X723720Y1189271D03*
X719980D03*
X731201Y1174310D03*
Y1181791D03*
X727460Y1174310D03*
X719980Y1204232D03*
X727460D03*
X727480Y1196732D03*
X731201Y1196751D03*
X734941Y1193011D03*
X727460D03*
X723720Y1196751D03*
X719980D03*
X727460Y1200491D03*
X723720Y1204232D03*
X734941Y1211712D03*
X727460Y1207972D03*
X723720Y1211712D03*
Y1207972D03*
X719980Y1211712D03*
Y1207972D03*
X727460Y1211712D03*
X731201Y1207972D03*
X733071Y1221062D03*
X721850D03*
X725590D03*
X729331D03*
Y1224803D03*
Y1228543D03*
X733071Y1236023D03*
Y1232283D03*
X725590Y1236023D03*
Y1232283D03*
X721850Y1224803D03*
Y1228543D03*
X725590Y1239763D03*
X729331Y1258465D03*
X721850D03*
X729848Y1348187D03*
Y1360099D03*
Y1372385D03*
Y1384297D03*
Y1396489D03*
Y1408401D03*
X740551Y1075196D03*
X748031D03*
X744290Y1071455D03*
X736810D03*
X748030Y1090157D03*
X744291D03*
X740551Y1078936D03*
Y1090157D03*
X736811D03*
X744291Y1101377D03*
X748031Y1093897D03*
X744291Y1105117D03*
X736811D03*
X748031Y1123818D03*
Y1120078D03*
Y1116338D03*
Y1112598D03*
Y1108858D03*
X744291D03*
X740551D03*
X736811D03*
X738681Y1136909D03*
Y1140649D03*
X748031Y1138779D03*
Y1135039D03*
Y1131299D03*
Y1127558D03*
X738681Y1155610D03*
Y1148129D03*
X749901Y1144389D03*
Y1151869D03*
X746161Y1155610D03*
Y1151869D03*
X742421D03*
X738681D03*
Y1166830D03*
X746161Y1170570D03*
Y1166830D03*
X738681Y1159350D03*
X749901Y1166830D03*
Y1159350D03*
X738681Y1170570D03*
X746161Y1159350D03*
X749901Y1181791D03*
Y1174310D03*
X738681D03*
Y1178051D03*
X742421Y1181791D03*
X738681Y1185531D03*
Y1189271D03*
X746161Y1185531D03*
Y1178051D03*
Y1174310D03*
X742421Y1185531D03*
X748031Y1191141D03*
X738681Y1204232D03*
Y1193011D03*
Y1196751D03*
X742421Y1193011D03*
X748031Y1202362D03*
Y1198621D03*
X736811Y1221062D03*
X740551D03*
X748031D03*
X744291D03*
X748031Y1217322D03*
Y1213582D03*
Y1209842D03*
Y1206102D03*
X736811Y1224803D03*
Y1228543D03*
X748031Y1236023D03*
Y1232283D03*
X740551Y1236023D03*
X744291Y1228543D03*
X740551Y1232283D03*
X744291Y1224803D03*
X748031Y1239763D03*
X740551D03*
X744291Y1258465D03*
X736811D03*
X742088Y1348187D03*
Y1360099D03*
Y1384297D03*
Y1372385D03*
Y1396489D03*
Y1408401D03*
X755512Y1075196D03*
X762993D03*
X766732Y1071455D03*
X759252D03*
X751771D03*
X755511Y1090157D03*
X762993Y1078936D03*
X755513D03*
X751772Y1105117D03*
X762992Y1093897D03*
X759252Y1105117D03*
X766732D03*
X755512Y1093897D03*
X762991Y1108857D03*
X755512Y1108858D03*
X751772D03*
X759252Y1116338D03*
Y1123818D03*
X751771Y1112598D03*
Y1120078D03*
X757382Y1140649D03*
X759252Y1131299D03*
X757382Y1148129D03*
X764862Y1170570D03*
X757382Y1166830D03*
Y1159350D03*
Y1174310D03*
Y1181791D03*
X764862Y1185531D03*
Y1178051D03*
X755512Y1187401D03*
X764862Y1189271D03*
X766732Y1194881D03*
X751772D03*
X755512Y1202362D03*
X766732D03*
Y1198621D03*
X762992D03*
X766732Y1221062D03*
Y1217322D03*
X762992Y1221062D03*
X759252D03*
X762992Y1213582D03*
X766732D03*
Y1209842D03*
X755512D03*
X766732Y1206102D03*
X751772Y1221062D03*
Y1217322D03*
X759252Y1224803D03*
Y1228543D03*
X755512Y1232283D03*
Y1236023D03*
X766732Y1224803D03*
Y1228543D03*
X762992Y1232283D03*
Y1236023D03*
X751772Y1224803D03*
Y1228543D03*
X755512Y1239763D03*
X766732D03*
Y1258465D03*
X759252D03*
X751772D03*
X766568Y1348187D03*
X754328D03*
X766568Y1360099D03*
X754328D03*
Y1372385D03*
Y1384297D03*
X766568Y1372385D03*
Y1384297D03*
X777953Y1075196D03*
X770473D03*
X774212Y1071455D03*
X777953Y1078936D03*
X781693D03*
X770473D03*
X770471Y1090157D03*
X770472Y1093897D03*
Y1108858D03*
X776083Y1140649D03*
Y1148129D03*
Y1155610D03*
Y1170570D03*
X768602Y1166830D03*
X779823Y1170570D03*
X776083Y1178051D03*
Y1185531D03*
X779823D03*
Y1178051D03*
X768602Y1181791D03*
Y1174310D03*
X772342Y1189271D03*
X783503Y1193011D03*
X776083D03*
X779823D03*
X781693Y1202362D03*
X777953D03*
X770472Y1221062D03*
X777953Y1209842D03*
X774212Y1224803D03*
Y1228543D03*
X770472Y1236023D03*
Y1232283D03*
X777953D03*
X781693Y1250984D03*
X774212Y1258465D03*
X778808Y1348187D03*
Y1360099D03*
X785434Y1090158D03*
Y1082677D03*
Y1101378D03*
Y1123819D03*
Y1116339D03*
Y1108859D03*
Y1131300D03*
Y1198621D03*
Y1221062D03*
Y1213582D03*
Y1206102D03*
Y1228543D03*
Y1247243D03*
Y1239762D03*
X892183Y1728286D03*
Y1738286D03*
X891761Y1775438D03*
Y1785438D03*
X1057381Y1103247D03*
Y1140649D03*
Y1133169D03*
Y1125688D03*
Y1151870D03*
Y1144389D03*
X1054881Y1170570D03*
X1057381Y1159350D03*
X1054881Y1178050D03*
X1059251Y1187401D03*
Y1183661D03*
Y1194881D03*
Y1202362D03*
X1055510Y1198622D03*
Y1191142D03*
X1059251Y1209842D03*
Y1217322D03*
X1055510Y1221063D03*
Y1213583D03*
Y1206103D03*
X1059251Y1232283D03*
Y1236023D03*
Y1224803D03*
X1052473Y1348187D03*
Y1360099D03*
Y1384297D03*
Y1372385D03*
X1064861Y1077066D03*
X1061121Y1080806D03*
X1072342Y1106988D03*
X1061121Y1103247D03*
X1072342Y1121948D03*
Y1118208D03*
X1064862Y1121948D03*
X1068602D03*
X1072342Y1140649D03*
Y1125688D03*
X1061121D03*
Y1140649D03*
X1064862D03*
X1068602D03*
X1064862Y1136909D03*
X1061121Y1133169D03*
X1064862Y1129429D03*
X1068602D03*
X1072342Y1155610D03*
X1064862D03*
X1068602D03*
X1061121Y1151870D03*
X1064862D03*
Y1148129D03*
X1061121Y1144389D03*
X1064862D03*
X1072342Y1166830D03*
X1064861Y1170570D03*
X1068602D03*
X1064861Y1166830D03*
X1061121Y1159350D03*
X1064862D03*
X1072342Y1181791D03*
Y1174310D03*
X1061120Y1181791D03*
X1064861D03*
X1068602D03*
Y1174310D03*
X1064861Y1178051D03*
X1061120Y1174310D03*
X1064861D03*
X1074212Y1187401D03*
X1062991D03*
Y1183661D03*
X1066732D03*
X1070472D03*
X1074212D03*
Y1191141D03*
Y1198621D03*
X1070472Y1191141D03*
X1066732D03*
X1070472Y1198621D03*
X1066732D03*
X1062991Y1194881D03*
Y1202362D03*
X1074212Y1206102D03*
X1066732D03*
X1070472D03*
Y1213582D03*
X1066732D03*
X1062991Y1209842D03*
Y1217322D03*
X1074212Y1221062D03*
X1066732D03*
X1070472D03*
Y1236023D03*
Y1232283D03*
X1066732Y1228543D03*
Y1224803D03*
X1074212D03*
X1062991Y1236023D03*
Y1232283D03*
Y1224803D03*
X1066732Y1239763D03*
Y1243503D03*
X1074212Y1239763D03*
Y1243503D03*
Y1258465D03*
X1066732D03*
X1072593Y1348187D03*
X1064713D03*
X1060353D03*
X1072593Y1360099D03*
X1064713D03*
X1060353D03*
X1072593Y1384297D03*
Y1372385D03*
X1064713D03*
Y1384297D03*
X1060353D03*
Y1372385D03*
X1072593Y1396583D03*
X1064713D03*
X1072593Y1408495D03*
X1064713D03*
X1089171Y1071455D03*
X1083562Y1092027D03*
X1089172Y1090157D03*
X1083562Y1095767D03*
X1087302Y1106988D03*
X1079822D03*
X1083562D03*
X1076082D03*
X1089172Y1101377D03*
Y1105117D03*
X1083562Y1118208D03*
X1087302D03*
X1079822Y1114468D03*
X1083562Y1110728D03*
X1087302D03*
X1091043D03*
Y1121948D03*
Y1118208D03*
Y1114468D03*
X1076082D03*
X1089172Y1108858D03*
X1091043Y1125688D03*
Y1140649D03*
X1079822Y1129429D03*
Y1140649D03*
X1083562D03*
X1087302D03*
X1091043Y1136909D03*
Y1133169D03*
Y1129429D03*
X1076082Y1140649D03*
X1087302Y1151870D03*
Y1155610D03*
Y1148129D03*
X1083562Y1144389D03*
X1087302D03*
X1076082Y1155610D03*
Y1151870D03*
Y1148129D03*
Y1144389D03*
X1087302Y1170570D03*
Y1166830D03*
Y1159350D03*
X1091043Y1170570D03*
X1076082Y1159350D03*
X1081692Y1179921D03*
X1083562Y1181791D03*
X1087302D03*
Y1178051D03*
Y1174310D03*
X1076082Y1181791D03*
Y1178051D03*
Y1174310D03*
X1077952Y1183661D03*
X1081692D03*
X1085432D03*
X1089172Y1187401D03*
X1085432D03*
X1091043Y1185531D03*
X1077952Y1191141D03*
Y1198621D03*
X1081692Y1191141D03*
X1085432Y1194881D03*
X1089172D03*
X1085432Y1202362D03*
X1089172D03*
X1077952Y1206102D03*
X1081692D03*
X1085432Y1209842D03*
X1077952Y1221062D03*
X1089172Y1217322D03*
Y1221062D03*
X1085432D03*
Y1217322D03*
X1077952Y1232283D03*
Y1236023D03*
X1085432Y1232283D03*
Y1236023D03*
X1081692Y1224803D03*
X1089172D03*
X1077952Y1239763D03*
X1081692D03*
Y1243503D03*
X1085432Y1250984D03*
Y1239763D03*
X1089172D03*
Y1247243D03*
X1089173Y1258465D03*
X1081692D03*
X1089193Y1348187D03*
X1084833D03*
X1076953D03*
X1089193Y1360099D03*
X1084833D03*
X1076953D03*
X1089193Y1384297D03*
Y1372385D03*
X1084833Y1384297D03*
Y1372385D03*
X1076953Y1384297D03*
Y1372385D03*
X1089193Y1396583D03*
X1084833D03*
X1076953D03*
X1089193Y1408495D03*
X1084833D03*
X1076953D03*
X1104132Y1071455D03*
X1096652D03*
X1092913Y1090157D03*
X1104133D03*
X1107873D03*
X1100393D03*
X1096653D03*
X1092913Y1093897D03*
Y1097637D03*
X1107873Y1093897D03*
Y1097637D03*
X1104133Y1101377D03*
X1100393Y1097637D03*
Y1093897D03*
X1096653Y1101377D03*
X1104133Y1105117D03*
X1096653D03*
X1094783Y1110728D03*
Y1121948D03*
X1098523D03*
X1102263D03*
X1106003D03*
X1094783Y1118208D03*
X1098523D03*
X1102263D03*
X1106003D03*
X1094783Y1114468D03*
X1107873Y1108858D03*
X1104133D03*
X1100393D03*
X1096653D03*
X1092913D03*
X1098523Y1140649D03*
X1102263D03*
X1094783Y1136909D03*
X1102263D03*
X1094783Y1133169D03*
X1098523D03*
X1102263D03*
X1094783Y1129429D03*
X1098523D03*
X1102263D03*
X1094783Y1125688D03*
X1098523D03*
X1102263D03*
X1106003D03*
X1094783Y1140649D03*
Y1151870D03*
Y1155610D03*
X1102263Y1151870D03*
X1094783Y1148129D03*
Y1144389D03*
X1102263D03*
X1106003Y1148129D03*
Y1155610D03*
X1102263Y1170570D03*
X1094783Y1159350D03*
X1102263D03*
X1094783Y1166830D03*
X1106003D03*
X1094783Y1181791D03*
X1102263Y1185531D03*
X1094783Y1174310D03*
Y1178051D03*
X1106003Y1181791D03*
Y1174310D03*
X1092913Y1187401D03*
X1098523Y1196751D03*
Y1193011D03*
X1106003Y1200491D03*
Y1196751D03*
Y1204232D03*
X1102263D03*
X1098523D03*
Y1200491D03*
X1102263D03*
Y1196751D03*
X1092913Y1191141D03*
Y1194881D03*
Y1198621D03*
Y1202362D03*
X1098523Y1207972D03*
X1102263D03*
X1106003D03*
Y1211712D03*
X1102263D03*
X1098523D03*
Y1219192D03*
X1106003D03*
X1092913Y1206102D03*
Y1209842D03*
Y1213582D03*
Y1217322D03*
X1107873Y1221062D03*
X1104133D03*
X1100393D03*
X1096653D03*
X1092913D03*
Y1232283D03*
Y1236023D03*
X1107873Y1232283D03*
X1104133Y1224803D03*
X1107873Y1236023D03*
X1100393Y1232283D03*
Y1236023D03*
X1096653Y1224803D03*
X1100393Y1239763D03*
X1107873D03*
X1104133Y1243503D03*
X1096653D03*
X1104133Y1258465D03*
X1096653D03*
X1101433Y1348187D03*
X1097073D03*
X1101433Y1360099D03*
X1097073D03*
X1101433Y1384297D03*
Y1372385D03*
X1097073D03*
Y1384297D03*
X1101433Y1396583D03*
X1097073D03*
X1101433Y1408495D03*
X1097073D03*
X1119093Y1071455D03*
X1111612D03*
X1115354Y1090157D03*
X1119094D03*
X1122834D03*
X1111613D03*
X1122834Y1093897D03*
X1115354D03*
X1122834Y1097637D03*
X1115354D03*
X1119094Y1101377D03*
X1111613D03*
X1119094Y1105117D03*
X1111613D03*
X1117224Y1121948D03*
Y1118208D03*
X1120964D03*
X1109743Y1121948D03*
X1113484D03*
X1109743Y1118208D03*
X1113484D03*
X1124704Y1121948D03*
Y1118208D03*
X1120964Y1121948D03*
X1122834Y1108858D03*
X1119094D03*
X1115354D03*
X1111613D03*
X1109743Y1136909D03*
X1124704Y1125688D03*
Y1140649D03*
Y1133169D03*
X1113484D03*
X1117224D03*
X1120964D03*
X1109743Y1125688D03*
X1120964D03*
X1117224D03*
X1113484D03*
X1120964Y1140649D03*
X1117224D03*
X1113484D03*
X1109743Y1129429D03*
Y1133169D03*
X1113484Y1155610D03*
X1109743Y1144389D03*
X1120964Y1155610D03*
X1109743Y1151869D03*
X1120964Y1148129D03*
X1113484D03*
X1117224D03*
X1124704D03*
X1117224Y1170570D03*
X1109743D03*
X1113484Y1166830D03*
X1117224Y1159350D03*
X1120964Y1166830D03*
X1109743Y1159350D03*
X1124704Y1170570D03*
Y1159350D03*
X1109743Y1189271D03*
X1113484D03*
X1117224D03*
X1120964D03*
X1113484Y1181791D03*
X1117224D03*
X1120964D03*
X1124704Y1189271D03*
Y1181791D03*
X1109743Y1178051D03*
X1120964Y1174310D03*
X1109743Y1185531D03*
X1113484Y1174310D03*
X1124704Y1204232D03*
Y1196751D03*
X1120964Y1204232D03*
X1117224D03*
X1113484D03*
X1109743D03*
Y1193011D03*
Y1196751D03*
Y1200491D03*
X1113484Y1196751D03*
X1117224D03*
X1120964D03*
X1113484Y1207972D03*
X1117224D03*
X1120964D03*
X1109743Y1211712D03*
Y1207972D03*
X1124704D03*
X1122834Y1221062D03*
X1119094D03*
X1115354D03*
X1111613D03*
X1122834Y1232283D03*
Y1236023D03*
X1119094Y1224803D03*
X1115354Y1232283D03*
Y1236023D03*
X1111613Y1224803D03*
X1119094Y1243503D03*
X1122834Y1239763D03*
X1111613Y1243503D03*
Y1239763D03*
X1119094Y1258465D03*
X1111614D03*
X1113673Y1348187D03*
X1121553D03*
X1109313D03*
X1113673Y1360099D03*
X1121553D03*
X1109313D03*
X1113673Y1372385D03*
Y1384297D03*
X1121553Y1372385D03*
Y1384297D03*
X1109313D03*
Y1372385D03*
X1113673Y1396583D03*
X1121553D03*
X1109313D03*
X1113673Y1408495D03*
X1121553D03*
X1109313D03*
X1134053Y1071455D03*
X1126573D03*
X1126574Y1090157D03*
X1130314D03*
X1134054D03*
X1137795D03*
X1126574Y1101377D03*
X1130314Y1097637D03*
Y1093897D03*
X1137795D03*
Y1097637D03*
X1134054Y1101377D03*
X1126574Y1105117D03*
X1134054D03*
X1139665Y1121948D03*
X1130314Y1112598D03*
X1128444Y1118208D03*
X1132184D03*
X1135924D03*
X1132184Y1121948D03*
X1135924D03*
X1128444D03*
X1139665Y1118208D03*
X1137795Y1108858D03*
X1134054D03*
X1130314D03*
X1126574D03*
X1139665Y1125688D03*
X1128444Y1140649D03*
X1132184D03*
X1135924D03*
X1132184Y1125688D03*
X1128444D03*
X1135924D03*
Y1133169D03*
X1132184D03*
X1128444D03*
X1139665D03*
Y1140649D03*
X1135924Y1148129D03*
X1132184D03*
X1128444D03*
X1139665D03*
X1128444Y1155610D03*
X1135924D03*
X1139665Y1170570D03*
Y1159350D03*
X1132184Y1170570D03*
X1135925Y1166830D03*
X1128444D03*
X1132184Y1159350D03*
X1135924Y1181791D03*
X1132184D03*
X1128444D03*
X1135924Y1189271D03*
X1132184D03*
X1128444D03*
Y1174310D03*
X1135924D03*
X1139665Y1181791D03*
Y1189271D03*
Y1196751D03*
Y1204232D03*
X1135924D03*
Y1196751D03*
X1132184D03*
X1128444D03*
Y1204232D03*
X1132184D03*
X1139665Y1207972D03*
X1134054Y1217322D03*
X1135924Y1207972D03*
X1132184D03*
X1128444D03*
X1137795Y1221062D03*
X1134054D03*
X1130314D03*
X1126574D03*
Y1224803D03*
X1137795Y1232283D03*
Y1236023D03*
X1134054Y1224803D03*
X1130314Y1232283D03*
Y1236023D03*
X1126574Y1243503D03*
X1134054D03*
X1137795Y1239763D03*
X1130314D03*
X1134055Y1258465D03*
X1126574D03*
X1138153Y1348187D03*
X1133793D03*
X1125913D03*
X1138153Y1360099D03*
X1133793D03*
X1125913D03*
X1138153Y1384297D03*
Y1372385D03*
X1133793Y1384297D03*
Y1372385D03*
X1125913Y1384297D03*
Y1372385D03*
X1138153Y1396583D03*
X1133793D03*
X1125913D03*
X1138153Y1408495D03*
X1133793D03*
X1125913D03*
X1152755Y1075196D03*
X1156494Y1071455D03*
X1149014Y1071454D03*
X1141534Y1071455D03*
X1141535Y1090157D03*
X1149015Y1082677D03*
Y1086417D03*
X1152755Y1090157D03*
X1156495D03*
Y1086417D03*
X1149015Y1090157D03*
X1145275D03*
X1141535Y1101377D03*
X1149015D03*
X1152755Y1093897D03*
X1156495Y1101377D03*
X1145275Y1093897D03*
Y1097637D03*
X1141535Y1105117D03*
X1149015D03*
X1156495D03*
X1150885Y1121948D03*
X1143405D03*
Y1118208D03*
Y1114468D03*
X1154625Y1121948D03*
X1156495Y1108858D03*
X1152755D03*
X1149015D03*
X1145275D03*
X1141535D03*
X1154625Y1125688D03*
X1150885Y1133464D03*
X1154625Y1133169D03*
X1143503Y1132677D03*
X1143405Y1140649D03*
Y1125688D03*
X1150885Y1140649D03*
X1154625D03*
X1150885Y1125688D03*
X1143405Y1148129D03*
X1150885D03*
X1154625D03*
X1143405Y1155610D03*
X1154625D03*
Y1166830D03*
X1150885Y1170570D03*
X1143405Y1166830D03*
X1150885Y1159350D03*
X1143405Y1181791D03*
X1154625D03*
X1150885D03*
Y1189271D03*
X1154625D03*
X1143405D03*
Y1174310D03*
X1154625D03*
X1150885Y1196751D03*
X1154625Y1204232D03*
X1150885D03*
X1154625Y1196751D03*
X1143405D03*
Y1204232D03*
X1150885Y1207972D03*
X1154625D03*
Y1211712D03*
X1143405Y1207972D03*
X1149015Y1221062D03*
X1156495D03*
X1152755D03*
X1145275D03*
X1141535D03*
Y1224803D03*
X1152755Y1232283D03*
Y1236023D03*
X1156495Y1228543D03*
Y1224803D03*
X1149015Y1228543D03*
Y1224803D03*
X1145275Y1232283D03*
Y1236023D03*
X1141535Y1243503D03*
X1152755Y1239763D03*
X1145275D03*
X1156495Y1258465D03*
X1149015D03*
X1141536D03*
X1150393Y1348187D03*
X1146033D03*
X1150393Y1360099D03*
X1146033D03*
X1150393Y1384297D03*
Y1372385D03*
X1146033D03*
Y1384297D03*
X1150393Y1396583D03*
X1146033D03*
X1150393Y1408495D03*
X1146033D03*
X1167716Y1075196D03*
X1160235D03*
X1171455Y1071455D03*
X1163975D03*
X1167716Y1078936D03*
X1163976Y1086417D03*
Y1090157D03*
X1171456Y1086417D03*
Y1090157D03*
X1167716D03*
X1160235Y1078936D03*
Y1090157D03*
X1167716Y1097637D03*
Y1093897D03*
X1160235D03*
Y1097637D03*
X1163976Y1105117D03*
X1171456D03*
X1169586Y1121948D03*
X1165846D03*
X1162106D03*
X1158365D03*
X1173326D03*
X1171456Y1108858D03*
X1167716D03*
X1163976D03*
X1160235D03*
X1162106Y1133169D03*
X1165846D03*
X1169586D03*
X1158365Y1140649D03*
X1162106D03*
X1165846D03*
X1169586D03*
X1158365Y1125688D03*
X1162106D03*
X1165846D03*
X1169586D03*
X1173326Y1133169D03*
Y1125688D03*
Y1140649D03*
X1158365Y1133169D03*
X1173326Y1148129D03*
X1158365D03*
X1162106D03*
X1165846D03*
X1169586D03*
X1162106Y1155610D03*
X1169586D03*
X1158365Y1170570D03*
X1165846D03*
X1169586Y1166830D03*
X1158365Y1159350D03*
X1162106Y1166830D03*
X1165846Y1159350D03*
X1173326D03*
Y1170570D03*
Y1189271D03*
X1158365Y1181791D03*
X1162106D03*
X1165846D03*
X1169586D03*
X1158365Y1189271D03*
X1162106D03*
X1165846D03*
X1169586D03*
X1173326Y1181791D03*
X1169586Y1174310D03*
X1162106D03*
Y1204232D03*
X1158365D03*
X1169586D03*
X1165846D03*
X1158365Y1196751D03*
X1162106D03*
X1165846D03*
X1169586D03*
X1173326Y1204232D03*
Y1196751D03*
X1158365Y1211712D03*
Y1207972D03*
X1173326D03*
Y1211712D03*
X1162106Y1207972D03*
X1165846D03*
X1169586Y1211712D03*
Y1207972D03*
X1171456Y1221062D03*
X1167716D03*
X1163976D03*
X1160235D03*
X1163976Y1228543D03*
Y1224803D03*
X1171456Y1228543D03*
Y1224803D03*
X1167716Y1232283D03*
Y1236023D03*
X1160235Y1232283D03*
Y1236023D03*
X1171456Y1239763D03*
X1160235D03*
X1171456Y1258465D03*
X1163976D03*
X1162633Y1348187D03*
X1170513D03*
X1158273D03*
X1162633Y1360099D03*
X1170513D03*
X1158273D03*
X1162633Y1372385D03*
Y1384297D03*
X1170513Y1372385D03*
Y1384297D03*
X1158273D03*
Y1372385D03*
X1162633Y1396583D03*
X1170513D03*
X1158273D03*
X1162633Y1408495D03*
X1170513D03*
X1158273D03*
X1175196Y1075196D03*
X1182676D03*
X1186416Y1071455D03*
X1178935D03*
X1175196Y1078936D03*
Y1090157D03*
X1178936D03*
X1182676Y1078936D03*
X1178936Y1086417D03*
X1182676Y1090157D03*
X1186417D03*
Y1086417D03*
Y1082677D03*
X1175196Y1097637D03*
Y1093897D03*
X1182676Y1097637D03*
Y1093897D03*
X1178936Y1105117D03*
X1186417D03*
X1188287Y1118208D03*
X1184546D03*
X1180806Y1121948D03*
X1177066D03*
X1184546D03*
X1186417Y1108858D03*
X1182676D03*
X1178936D03*
X1175196D03*
X1188287Y1125688D03*
X1184546Y1136909D03*
X1177066Y1133169D03*
X1180806D03*
X1184546D03*
X1177066Y1140649D03*
X1180806D03*
X1184546Y1125688D03*
Y1129429D03*
X1177066Y1125688D03*
X1180806D03*
X1184546Y1140649D03*
X1188287Y1155610D03*
Y1151869D03*
Y1148129D03*
X1177066D03*
X1180806D03*
X1184546Y1144389D03*
Y1148129D03*
Y1151869D03*
X1177066Y1155610D03*
X1184546D03*
X1177066Y1166830D03*
X1188287D03*
Y1159350D03*
Y1170570D03*
Y1181791D03*
Y1174310D03*
X1177066Y1189271D03*
X1180806D03*
X1184546Y1178051D03*
X1177066Y1174310D03*
X1184546Y1185531D03*
X1177066Y1181791D03*
X1180806D03*
X1184546Y1189271D03*
Y1174310D03*
Y1204232D03*
X1177066D03*
X1180806D03*
X1184546Y1200491D03*
X1177066Y1196751D03*
X1180806D03*
X1184546Y1193011D03*
X1188287Y1196751D03*
X1184566Y1196732D03*
X1188287Y1207972D03*
X1184546Y1211712D03*
X1177066Y1207972D03*
Y1211712D03*
X1180806Y1207972D03*
Y1211712D03*
X1184546Y1207972D03*
X1186417Y1221062D03*
X1182676D03*
X1178936D03*
X1175196D03*
Y1232283D03*
Y1236023D03*
X1178936Y1228543D03*
Y1224803D03*
X1182676Y1232283D03*
Y1236023D03*
X1186417Y1228543D03*
Y1224803D03*
X1182676Y1239763D03*
X1186417Y1258465D03*
X1178936D03*
X1182753Y1348187D03*
X1174873D03*
X1182753Y1360099D03*
X1174873D03*
X1182753Y1384297D03*
Y1372385D03*
X1174873Y1384297D03*
Y1372385D03*
X1182753Y1396583D03*
X1174873D03*
X1182753Y1408495D03*
X1174873D03*
X1179329Y1728990D03*
Y1738990D03*
X1179123Y1776014D03*
Y1786014D03*
X1190157Y1075196D03*
X1197637D03*
X1205117D03*
X1201376Y1071455D03*
X1193896D03*
X1190157Y1090157D03*
X1197637Y1078936D03*
Y1090157D03*
X1201377D03*
X1205116D03*
X1193897D03*
X1190157Y1093897D03*
X1201377Y1101377D03*
X1205117Y1093897D03*
X1201377Y1105117D03*
X1193897D03*
X1192027Y1118208D03*
X1205117Y1123818D03*
Y1120078D03*
Y1116338D03*
Y1108858D03*
X1201377D03*
X1197637D03*
X1193897D03*
X1190157D03*
X1192027Y1136909D03*
X1195767Y1140649D03*
X1192027D03*
X1195767Y1136909D03*
X1205117Y1135039D03*
Y1131299D03*
Y1127558D03*
X1195767Y1148129D03*
X1192027Y1144389D03*
X1195767Y1155610D03*
X1192027Y1148129D03*
X1195767Y1151869D03*
X1199507D03*
X1203247D03*
Y1155610D03*
X1192027Y1151870D03*
X1195767Y1170570D03*
Y1159350D03*
X1203247Y1166830D03*
Y1170570D03*
Y1159350D03*
X1195767Y1166830D03*
X1192027Y1181791D03*
X1199507Y1185531D03*
X1203247Y1174310D03*
Y1178051D03*
Y1185531D03*
X1192027Y1178051D03*
Y1189271D03*
X1195767D03*
X1192027Y1185531D03*
X1195767D03*
X1199507Y1181791D03*
X1195767Y1178051D03*
Y1174310D03*
Y1204232D03*
X1199507Y1193011D03*
X1195767Y1196751D03*
Y1193011D03*
X1192027D03*
X1205117Y1198621D03*
Y1202362D03*
X1192027Y1211712D03*
X1205117Y1206102D03*
Y1209842D03*
Y1213582D03*
Y1217322D03*
Y1221062D03*
X1201377D03*
X1197637D03*
X1193897D03*
X1190157D03*
Y1232283D03*
Y1236023D03*
X1197637Y1232283D03*
X1201377Y1228543D03*
X1197637Y1236023D03*
X1201377Y1224803D03*
X1205117Y1232283D03*
Y1236023D03*
X1193897Y1228543D03*
Y1224803D03*
X1197637Y1239763D03*
X1205117D03*
X1201377Y1258465D03*
X1193897D03*
X1212598Y1075196D03*
X1220079D03*
X1216338Y1071455D03*
X1208857D03*
X1220079Y1078936D03*
X1212599D03*
X1212597Y1090157D03*
X1212598Y1093897D03*
X1220078D03*
X1216338Y1105117D03*
X1208858D03*
X1212598Y1108858D03*
X1216338Y1116338D03*
Y1123818D03*
X1208857Y1112598D03*
Y1120078D03*
X1220077Y1108857D03*
X1208858Y1108858D03*
X1214468Y1140649D03*
X1206987Y1136909D03*
X1216338Y1131299D03*
X1206987Y1151869D03*
X1214468Y1148129D03*
X1206987Y1144389D03*
Y1159350D03*
X1214468D03*
X1206987Y1166830D03*
X1214468D03*
X1221948Y1170570D03*
X1206987Y1181791D03*
X1214468Y1189271D03*
X1221948Y1178051D03*
Y1185531D03*
X1206987Y1174310D03*
Y1189271D03*
X1214468Y1181791D03*
Y1174310D03*
X1208858Y1194881D03*
X1221948Y1193011D03*
X1212598Y1202362D03*
X1220078Y1198621D03*
Y1221062D03*
X1216338D03*
X1220078Y1213582D03*
X1212598Y1209842D03*
X1208858Y1221062D03*
Y1217322D03*
X1216338Y1224803D03*
Y1228543D03*
X1212598Y1232283D03*
Y1236023D03*
X1220078Y1232283D03*
Y1236023D03*
X1208858Y1224803D03*
Y1228543D03*
X1212598Y1239763D03*
X1216338Y1258465D03*
X1208858D03*
X1227559Y1075196D03*
X1235039D03*
X1231298Y1071455D03*
X1223818D03*
X1235039Y1078936D03*
X1227559D03*
X1227557Y1090157D03*
X1227558Y1093897D03*
X1223818Y1105117D03*
X1227558Y1108858D03*
X1233169Y1140649D03*
Y1155610D03*
Y1148129D03*
X1236909Y1170570D03*
X1225688Y1166830D03*
X1233169Y1170570D03*
X1236909Y1178051D03*
Y1185531D03*
X1233169D03*
Y1178051D03*
X1225688Y1174310D03*
Y1181791D03*
Y1189271D03*
X1233169Y1193011D03*
X1223818Y1194881D03*
X1236909Y1193011D03*
X1223818Y1202362D03*
Y1198621D03*
X1235039Y1202362D03*
X1223818Y1206102D03*
Y1221062D03*
Y1217322D03*
Y1213582D03*
Y1209842D03*
X1227558Y1221062D03*
X1235039Y1209842D03*
X1223818Y1224803D03*
Y1228543D03*
X1231298Y1224803D03*
Y1228543D03*
X1227558Y1236023D03*
Y1232283D03*
X1235039D03*
X1225688Y1222932D03*
X1223818Y1239763D03*
X1231298Y1258465D03*
X1223818D03*
X1235966Y1348187D03*
X1228086D03*
X1235966Y1360099D03*
X1228086D03*
X1235966Y1372385D03*
Y1384297D03*
X1228086Y1372385D03*
Y1384297D03*
X1238779Y1078936D03*
X1242520Y1090158D03*
Y1082677D03*
Y1101378D03*
Y1123819D03*
Y1116339D03*
Y1108859D03*
Y1131300D03*
X1240589Y1193011D03*
X1238779Y1202362D03*
X1242520Y1198621D03*
Y1221062D03*
Y1213582D03*
Y1206102D03*
Y1228543D03*
X1238779Y1250984D03*
X1242520Y1247243D03*
Y1239762D03*
X1252566Y1348187D03*
X1240326D03*
X1248206D03*
X1252566Y1360099D03*
X1240326D03*
X1248206D03*
X1252566Y1372385D03*
Y1384297D03*
X1240326D03*
Y1372385D03*
X1248206D03*
Y1384297D03*
X1252566Y1396583D03*
X1240326D03*
X1248206D03*
X1252566Y1408495D03*
X1240326D03*
X1248206D03*
X1264806Y1348187D03*
X1260446D03*
X1264806Y1360099D03*
X1260446D03*
X1264806Y1372385D03*
Y1384297D03*
X1260446Y1372385D03*
Y1384297D03*
X1264806Y1396583D03*
X1260446D03*
X1264806Y1408495D03*
X1260446D03*
X1284926Y1348187D03*
X1277046D03*
X1272686D03*
X1284926Y1360099D03*
X1277046D03*
X1272686D03*
X1284926Y1372385D03*
Y1384297D03*
X1277046Y1372385D03*
Y1384297D03*
X1272686D03*
Y1372385D03*
X1284926Y1396583D03*
X1277046D03*
X1272686D03*
X1284926Y1408495D03*
X1277046D03*
X1272686D03*
X1301526Y1348187D03*
X1289286D03*
X1297166D03*
X1301526Y1360099D03*
X1289286D03*
X1297166D03*
X1301526Y1372385D03*
Y1384297D03*
X1289286D03*
Y1372385D03*
X1297166Y1384297D03*
Y1372385D03*
X1301526Y1396583D03*
X1289286D03*
X1297166D03*
X1301526Y1408495D03*
X1289286D03*
X1297166D03*
X1313766Y1348187D03*
X1309406D03*
X1313766Y1360099D03*
X1309406D03*
X1313766Y1372385D03*
Y1384297D03*
X1309406Y1372385D03*
Y1384297D03*
X1313766Y1396583D03*
X1309406D03*
X1313766Y1408495D03*
X1309406D03*
X1333886Y1348187D03*
X1326006D03*
X1321646D03*
X1333886Y1360099D03*
X1326006D03*
X1321646D03*
X1333886Y1372385D03*
Y1384297D03*
X1326006Y1372385D03*
Y1384297D03*
X1321646D03*
Y1372385D03*
X1333886Y1396583D03*
X1326006D03*
X1321646D03*
X1333886Y1408495D03*
X1326006D03*
X1321646D03*
X1350486Y1348187D03*
X1338246D03*
X1346126D03*
X1350486Y1360099D03*
X1338246D03*
X1346126D03*
X1350486Y1372385D03*
Y1384297D03*
X1338246D03*
Y1372385D03*
X1346126Y1384297D03*
Y1372385D03*
X1350486Y1396583D03*
X1338246D03*
X1346126D03*
X1350486Y1408495D03*
X1338246D03*
X1346126D03*
X1358366Y1348187D03*
Y1360099D03*
Y1372385D03*
Y1384297D03*
Y1396583D03*
Y1408495D03*
X1459130Y1348187D03*
Y1360099D03*
Y1384297D03*
Y1372385D03*
X1479250Y1348187D03*
X1471370D03*
X1467010D03*
X1479250Y1360099D03*
X1471370D03*
X1467010D03*
X1479250Y1384297D03*
Y1372385D03*
X1471370D03*
Y1384297D03*
X1467010D03*
Y1372385D03*
X1479250Y1396583D03*
X1471370D03*
X1479250Y1408495D03*
X1471370D03*
X1495850Y1348187D03*
X1483610D03*
X1491490D03*
X1495850Y1360099D03*
X1483610D03*
X1491490D03*
X1483610Y1384297D03*
Y1372385D03*
X1491490Y1384297D03*
Y1372385D03*
X1495850Y1384297D03*
Y1372385D03*
Y1396583D03*
X1483610D03*
X1491490D03*
X1495850Y1408495D03*
X1483610D03*
X1491490D03*
X1514468Y1103247D03*
Y1125688D03*
Y1133169D03*
Y1140649D03*
Y1144389D03*
Y1151870D03*
Y1159350D03*
X1512597Y1198622D03*
Y1191142D03*
Y1221063D03*
Y1213583D03*
Y1206103D03*
X1508090Y1348187D03*
X1503730D03*
X1508090Y1360099D03*
X1503730D03*
X1508090Y1384297D03*
Y1372385D03*
X1503730D03*
Y1384297D03*
X1508090Y1396583D03*
X1503730D03*
X1508090Y1408495D03*
X1503730D03*
X1521948Y1077066D03*
X1518208Y1080806D03*
Y1103247D03*
X1529429Y1106988D03*
Y1118208D03*
Y1121948D03*
X1525689D03*
X1521949D03*
X1529429Y1125688D03*
X1518208D03*
X1525689Y1129429D03*
X1521949D03*
X1518208Y1133169D03*
X1521949Y1136909D03*
X1529429Y1140649D03*
X1525689D03*
X1521949D03*
X1518208D03*
X1521949Y1144389D03*
X1518208D03*
X1521949Y1148129D03*
Y1151870D03*
X1518208D03*
X1529429Y1155610D03*
X1525689D03*
X1521949D03*
Y1159350D03*
X1518208D03*
X1529429Y1166830D03*
X1521948D03*
X1525689Y1170570D03*
X1521948D03*
Y1174310D03*
X1518207D03*
X1521948Y1178051D03*
X1525689Y1174310D03*
X1529429D03*
X1527559Y1179921D03*
X1523819D03*
X1518207Y1181791D03*
X1516338Y1187401D03*
X1520078D03*
X1527559Y1183661D03*
X1523819D03*
X1520078D03*
X1516338D03*
Y1194881D03*
Y1202362D03*
X1527559Y1191141D03*
X1523819D03*
X1527559Y1198621D03*
X1523819D03*
X1520078Y1194881D03*
Y1202362D03*
X1516338Y1209842D03*
Y1217322D03*
X1523819Y1206102D03*
X1527559D03*
Y1213582D03*
X1523819D03*
X1520078Y1209842D03*
Y1217322D03*
X1523819Y1221062D03*
X1527559D03*
X1516338Y1232283D03*
Y1236023D03*
Y1224803D03*
X1527559Y1236023D03*
Y1232283D03*
X1523819Y1228543D03*
Y1224803D03*
X1520078Y1236023D03*
Y1232283D03*
Y1224803D03*
X1523819Y1239763D03*
Y1243503D03*
Y1258465D03*
X1528210Y1348187D03*
X1520330D03*
X1515970D03*
X1528210Y1360099D03*
X1520330D03*
X1515970D03*
X1528210Y1372385D03*
Y1384297D03*
X1520330Y1372385D03*
Y1384297D03*
X1515970D03*
Y1372385D03*
X1528210Y1396583D03*
X1520330D03*
X1515970D03*
X1528210Y1408495D03*
X1520330D03*
X1515970D03*
X1546258Y1071455D03*
X1540649Y1092027D03*
X1546259Y1090157D03*
X1544389Y1099507D03*
X1540649Y1106988D03*
X1536909D03*
X1533169D03*
X1544389D03*
X1540649Y1095767D03*
X1546259Y1101377D03*
Y1105117D03*
X1544389Y1118208D03*
X1540649D03*
X1544389Y1110728D03*
X1540649D03*
X1536909Y1114468D03*
X1533169D03*
X1544389Y1140649D03*
X1540649D03*
X1536909D03*
X1533169D03*
X1536909Y1129429D03*
X1544389Y1144389D03*
X1540649D03*
X1533169D03*
Y1148129D03*
Y1151870D03*
Y1155610D03*
X1544389Y1148129D03*
Y1155610D03*
Y1151870D03*
X1533169Y1159350D03*
X1544389D03*
Y1166830D03*
Y1170570D03*
X1533169Y1174310D03*
Y1178051D03*
X1544389Y1174310D03*
Y1178051D03*
Y1181791D03*
X1540649D03*
X1538779Y1179921D03*
X1531299D03*
Y1187401D03*
X1546259D03*
X1542519D03*
Y1183661D03*
X1538779D03*
X1535039D03*
X1531299D03*
X1535039Y1191141D03*
X1531299D03*
X1535039Y1198621D03*
X1531299D03*
X1538779Y1191141D03*
X1542519Y1194881D03*
X1546259D03*
X1542519Y1202362D03*
X1546259D03*
X1531299Y1206102D03*
X1535039D03*
X1538779D03*
X1542519Y1209842D03*
X1531299Y1221062D03*
X1535039D03*
X1546259Y1217322D03*
Y1221062D03*
X1542519D03*
Y1217322D03*
X1531299Y1224803D03*
X1535039Y1232283D03*
Y1236023D03*
X1542519Y1232283D03*
Y1236023D03*
X1538779Y1224803D03*
X1546259D03*
X1535039Y1239763D03*
X1531299D03*
Y1243503D03*
X1538779Y1239763D03*
Y1243503D03*
X1542519Y1250984D03*
Y1239763D03*
X1546259D03*
Y1247243D03*
X1546260Y1258465D03*
X1538779D03*
X1531299D03*
X1544810Y1348187D03*
X1532570D03*
X1540450D03*
X1544810Y1360099D03*
X1532570D03*
X1540450D03*
X1544810Y1384297D03*
Y1372385D03*
X1532570Y1384297D03*
Y1372385D03*
X1540450Y1384297D03*
Y1372385D03*
X1544810Y1396583D03*
X1532570D03*
X1540450D03*
X1544810Y1408495D03*
X1532570D03*
X1540450D03*
X1561219Y1071455D03*
X1553739D03*
X1561220Y1090157D03*
X1557480D03*
X1553740D03*
X1550000D03*
X1561220Y1105117D03*
X1553740D03*
X1561220Y1101377D03*
X1557480Y1097637D03*
Y1093897D03*
X1553740Y1101377D03*
X1550000Y1093897D03*
Y1097637D03*
X1551870Y1114468D03*
X1548130D03*
X1563090Y1118208D03*
X1559350D03*
X1555610D03*
X1551870D03*
X1548130D03*
X1563090Y1121948D03*
X1559350D03*
X1555610D03*
X1551870D03*
X1548130D03*
Y1110728D03*
X1561220Y1108858D03*
X1557480D03*
X1553740D03*
X1550000D03*
X1551870Y1110728D03*
X1548130Y1140649D03*
X1563090Y1125688D03*
X1559350D03*
X1555610D03*
X1551870D03*
X1548130D03*
X1559350Y1129429D03*
X1555610D03*
X1551870D03*
X1548130D03*
X1559350Y1133169D03*
X1555610D03*
X1551870D03*
X1548130D03*
X1559350Y1136909D03*
X1551870D03*
X1548130D03*
X1559350Y1140649D03*
X1555610D03*
X1551870D03*
Y1155610D03*
Y1151870D03*
X1559350Y1144389D03*
X1551870D03*
Y1148129D03*
X1559350Y1151870D03*
X1563090Y1155610D03*
Y1148129D03*
X1559350Y1170570D03*
X1551870Y1166830D03*
X1559350Y1159350D03*
X1551870D03*
X1548130Y1170570D03*
X1563090Y1166830D03*
X1551870Y1189271D03*
X1559350Y1185531D03*
X1551870D03*
Y1178051D03*
Y1174310D03*
Y1181791D03*
X1563090D03*
Y1174310D03*
X1550000Y1187401D03*
X1548130Y1185531D03*
X1551870Y1193011D03*
X1559350Y1196751D03*
Y1200491D03*
X1555610D03*
Y1204232D03*
X1559350D03*
X1563090D03*
Y1196751D03*
Y1200491D03*
X1555610Y1193011D03*
Y1196751D03*
X1550000Y1191141D03*
Y1194881D03*
Y1198621D03*
Y1202362D03*
X1555610Y1211712D03*
X1559350D03*
X1563090D03*
Y1207972D03*
X1559350D03*
X1555610D03*
X1563090Y1219192D03*
X1550000Y1221062D03*
X1553740D03*
X1557480D03*
X1561220D03*
X1550000Y1206102D03*
Y1209842D03*
Y1213582D03*
Y1217322D03*
X1553740D03*
X1550000Y1232283D03*
Y1236023D03*
X1561220Y1224803D03*
X1557480Y1232283D03*
Y1236023D03*
X1553740Y1224803D03*
X1557480Y1239763D03*
X1561220Y1243503D03*
X1553740D03*
X1561220Y1258465D03*
X1553740D03*
X1557050Y1348187D03*
X1552690D03*
Y1360099D03*
X1557050D03*
Y1384297D03*
Y1372385D03*
X1552690D03*
Y1384297D03*
X1557050Y1396583D03*
X1552690D03*
X1557050Y1408495D03*
X1552690D03*
X1576180Y1071455D03*
X1568699D03*
X1564960Y1090157D03*
X1572441D03*
X1576181D03*
X1568700D03*
X1576181Y1105117D03*
X1568700D03*
X1564960Y1093897D03*
Y1097637D03*
X1572441Y1093897D03*
Y1097637D03*
X1576181Y1101377D03*
X1568700D03*
X1566830Y1121948D03*
X1578051Y1118208D03*
X1574311D03*
Y1121948D03*
X1578051D03*
X1570571Y1118208D03*
X1566830D03*
X1570571Y1121948D03*
X1576181Y1108858D03*
X1572441D03*
X1568700D03*
X1564960D03*
X1566830Y1133169D03*
Y1129429D03*
X1570571Y1140649D03*
X1574311D03*
X1578051D03*
X1570571Y1125688D03*
X1574311D03*
X1578051D03*
X1566830D03*
X1578051Y1133169D03*
X1574311D03*
X1570571D03*
X1566830Y1136909D03*
X1574311Y1148129D03*
X1570571D03*
X1578051D03*
X1570571Y1155610D03*
X1566830Y1151869D03*
X1578051Y1155610D03*
X1566830Y1144389D03*
Y1159350D03*
X1578051Y1166830D03*
X1574311Y1159350D03*
X1570571Y1166830D03*
X1566830Y1170570D03*
X1574311D03*
X1578051Y1181791D03*
X1574311D03*
X1570571D03*
X1578051Y1189271D03*
X1574311D03*
X1570571D03*
X1566830D03*
Y1178051D03*
X1570571Y1174310D03*
X1566830Y1185531D03*
X1578051Y1174310D03*
X1574311Y1204232D03*
X1578051D03*
Y1196751D03*
X1574311D03*
X1570571D03*
X1566830Y1200491D03*
Y1196751D03*
Y1193011D03*
Y1204232D03*
X1570571D03*
X1566830Y1207972D03*
Y1211712D03*
X1578051Y1207972D03*
X1574311D03*
X1570571D03*
X1564960Y1221062D03*
X1568700D03*
X1572441D03*
X1576181D03*
X1564960Y1232283D03*
Y1236023D03*
X1576181Y1224803D03*
X1572441Y1232283D03*
Y1236023D03*
X1568700Y1224803D03*
X1564960Y1239763D03*
X1576181Y1243503D03*
X1568700D03*
Y1239763D03*
X1576181Y1258465D03*
X1568701D03*
X1564930Y1348187D03*
X1569290D03*
X1577170D03*
X1569290Y1360099D03*
X1577170D03*
X1564930D03*
X1577170Y1372385D03*
Y1384297D03*
X1569290Y1372385D03*
Y1384297D03*
X1564930D03*
Y1372385D03*
X1577170Y1396583D03*
X1569290D03*
X1564930D03*
X1577170Y1408495D03*
X1569290D03*
X1564930D03*
X1591140Y1071455D03*
X1583660D03*
X1579921Y1090157D03*
X1583661D03*
X1587401D03*
X1591141D03*
X1594882D03*
X1583661Y1105117D03*
X1591141D03*
X1579921Y1093897D03*
Y1097637D03*
X1583661Y1101377D03*
X1587401Y1097637D03*
Y1093897D03*
X1594882D03*
Y1097637D03*
X1591141Y1101377D03*
X1581791Y1121948D03*
X1585531Y1118208D03*
X1589271D03*
X1593011D03*
X1589271Y1121948D03*
X1593011D03*
X1585531D03*
X1581791Y1118208D03*
X1594882Y1108858D03*
X1591141D03*
X1587401D03*
X1583661D03*
X1579921D03*
X1587401Y1112598D03*
X1581791Y1133169D03*
Y1140649D03*
X1585531D03*
X1589271D03*
X1593011D03*
X1589271Y1125688D03*
X1585531D03*
X1581791D03*
X1593011D03*
Y1133169D03*
X1589271D03*
X1585531D03*
X1593011Y1148129D03*
X1589271D03*
X1585531D03*
X1581791D03*
X1593011Y1155610D03*
X1585531D03*
X1589271Y1170570D03*
X1593012Y1166830D03*
X1585531D03*
X1581791Y1159350D03*
X1589271D03*
X1581791Y1170570D03*
X1593011Y1181791D03*
X1589271D03*
X1585531D03*
X1581791D03*
X1593011Y1189271D03*
X1589271D03*
X1585531D03*
X1581791D03*
X1585531Y1174310D03*
X1593011D03*
Y1204232D03*
Y1196751D03*
X1589271D03*
X1585531D03*
X1581791D03*
Y1204232D03*
X1585531D03*
X1589271D03*
X1593011Y1219192D03*
X1591141Y1217322D03*
X1593011Y1207972D03*
X1589271D03*
X1585531D03*
X1581791D03*
X1591141Y1221062D03*
X1587401D03*
X1579921D03*
X1583661D03*
X1594882D03*
X1583661Y1224803D03*
X1579921Y1232283D03*
Y1236023D03*
X1594882Y1232283D03*
Y1236023D03*
X1591141Y1224803D03*
X1587401Y1232283D03*
Y1236023D03*
X1583661Y1243503D03*
X1579921Y1239763D03*
X1591141Y1243503D03*
X1594882Y1239763D03*
X1587401D03*
X1591142Y1258465D03*
X1583661D03*
X1589410Y1348187D03*
X1581530D03*
X1589410Y1360099D03*
X1581530D03*
Y1384297D03*
Y1372385D03*
X1589410Y1384297D03*
Y1372385D03*
X1581530Y1396583D03*
X1589410D03*
X1581530Y1408495D03*
X1589410D03*
X1609842Y1075196D03*
X1606101Y1071454D03*
X1598621Y1071455D03*
X1598622Y1090157D03*
X1606102Y1082677D03*
Y1086417D03*
X1609842Y1090157D03*
X1606102D03*
X1602362D03*
X1598622Y1105117D03*
X1606102D03*
X1598622Y1101377D03*
X1606102D03*
X1609842Y1093897D03*
X1602362D03*
Y1097637D03*
X1596752Y1121948D03*
X1600492Y1118208D03*
Y1114468D03*
X1611712Y1121948D03*
X1607972D03*
X1596752Y1118208D03*
X1600492Y1121948D03*
X1609842Y1108858D03*
X1606102D03*
X1602362D03*
X1598622D03*
X1607972Y1125688D03*
X1611712D03*
X1607972Y1133464D03*
X1611712Y1133169D03*
X1600590Y1132677D03*
X1596752Y1133169D03*
Y1140649D03*
X1600492D03*
Y1125688D03*
X1596752D03*
X1607972Y1140649D03*
X1611712D03*
X1600492Y1148129D03*
X1596752D03*
X1607972D03*
X1611712D03*
X1600492Y1155610D03*
X1611712D03*
X1596752Y1170570D03*
Y1159350D03*
X1611712Y1166830D03*
X1607972Y1170570D03*
X1600492Y1166830D03*
X1607972Y1159350D03*
X1600492Y1181791D03*
X1611712D03*
X1607972D03*
Y1189271D03*
X1611712D03*
X1596752Y1181791D03*
X1600492Y1189271D03*
X1596752D03*
X1600492Y1174310D03*
X1611712D03*
Y1204232D03*
X1607972D03*
Y1196751D03*
X1611712D03*
X1600492D03*
X1596752D03*
Y1204232D03*
X1600492D03*
X1606102Y1221062D03*
X1596752Y1207972D03*
X1607972D03*
X1611712D03*
Y1211712D03*
X1596752Y1219192D03*
X1600492Y1207972D03*
X1598622Y1221062D03*
X1609842D03*
X1602362D03*
X1598622Y1224803D03*
X1609842Y1232283D03*
Y1236023D03*
X1606102Y1228543D03*
Y1224803D03*
X1602362Y1232283D03*
Y1236023D03*
X1598622Y1243503D03*
X1609842Y1239763D03*
X1602362D03*
X1606102Y1258465D03*
X1598623D03*
X1609158Y1348187D03*
Y1360099D03*
Y1384297D03*
Y1372385D03*
X1624803Y1075196D03*
X1617322D03*
X1621062Y1071455D03*
X1613581D03*
X1617322Y1090157D03*
Y1078936D03*
X1613582Y1090157D03*
Y1086417D03*
X1624803Y1078936D03*
X1621063Y1086417D03*
Y1090157D03*
X1624803D03*
X1617322Y1093897D03*
Y1097637D03*
X1624803Y1093897D03*
Y1097637D03*
X1621063Y1105117D03*
X1613582D03*
Y1101377D03*
X1626673Y1121948D03*
X1622933D03*
X1619193D03*
X1615452D03*
X1624803Y1108858D03*
X1621063D03*
X1617322D03*
X1613582D03*
X1615452Y1133169D03*
X1619193D03*
X1622933D03*
X1626673D03*
X1615452Y1140649D03*
X1619193D03*
X1622933D03*
X1626673D03*
X1615452Y1125688D03*
X1619193D03*
X1622933D03*
X1626673D03*
X1615452Y1148129D03*
X1619193D03*
X1622933D03*
X1626673D03*
X1619193Y1155610D03*
X1626673D03*
X1615452Y1170570D03*
X1622933D03*
X1626673Y1166830D03*
X1615452Y1159350D03*
X1619193Y1166830D03*
X1622933Y1159350D03*
X1615452Y1181791D03*
X1619193D03*
X1622933D03*
X1626673D03*
X1615452Y1189271D03*
X1619193D03*
X1622933D03*
X1626673D03*
Y1174310D03*
X1619193D03*
Y1204232D03*
X1615452D03*
X1626673D03*
X1622933D03*
X1615452Y1196751D03*
X1619193D03*
X1622933D03*
X1626673D03*
X1617322Y1221062D03*
X1619193Y1207972D03*
X1622933D03*
X1626673Y1211712D03*
Y1207972D03*
X1615452Y1211712D03*
Y1207972D03*
X1621063Y1221062D03*
X1613582D03*
X1624803D03*
X1613582Y1228543D03*
Y1224803D03*
X1621063Y1228543D03*
Y1224803D03*
X1624803Y1232283D03*
Y1236023D03*
X1617322Y1232283D03*
Y1236023D03*
Y1239763D03*
X1621063Y1258465D03*
X1613582D03*
X1617038Y1348187D03*
X1621398D03*
X1617038Y1360099D03*
X1621398D03*
X1617038Y1384297D03*
Y1372385D03*
X1621398D03*
Y1384297D03*
Y1396583D03*
Y1408495D03*
X1639763Y1075196D03*
X1632283D03*
X1643503Y1071455D03*
X1636022D03*
X1628542D03*
X1636023Y1090157D03*
X1643504Y1082677D03*
X1636023Y1086417D03*
X1643504Y1090157D03*
Y1086417D03*
X1639763Y1090157D03*
Y1078936D03*
X1632283D03*
X1628543Y1086417D03*
Y1090157D03*
X1632283D03*
Y1093897D03*
Y1097637D03*
X1639763Y1093897D03*
Y1097637D03*
X1628543Y1105117D03*
X1636023D03*
X1643504D03*
X1641633Y1118208D03*
X1637893Y1121948D03*
X1634153D03*
X1630413D03*
X1641633D03*
X1643504Y1108858D03*
X1639763D03*
X1636023D03*
X1632283D03*
X1628543D03*
X1641633Y1136909D03*
X1630413Y1133169D03*
X1634153D03*
X1637893D03*
X1641633D03*
X1634153Y1140649D03*
X1637893D03*
X1641633Y1125688D03*
Y1129429D03*
X1630413Y1125688D03*
X1634153D03*
X1637893D03*
X1641633Y1140649D03*
X1630413D03*
Y1148129D03*
X1634153D03*
X1637893D03*
X1641633Y1144389D03*
Y1148129D03*
Y1151869D03*
X1634153Y1155610D03*
X1641633D03*
X1634153Y1166830D03*
X1630413Y1159350D03*
Y1170570D03*
X1634153Y1189271D03*
X1637893D03*
X1641633Y1178051D03*
X1634153Y1174310D03*
X1641633Y1185531D03*
X1630413Y1181791D03*
X1634153D03*
X1637893D03*
X1641633Y1189271D03*
X1630413D03*
X1641633Y1174310D03*
X1641653Y1196732D03*
X1641633Y1204232D03*
X1630413D03*
X1634153D03*
X1637893D03*
X1641633Y1200491D03*
X1630413Y1196751D03*
X1634153D03*
X1637893D03*
X1641633Y1193011D03*
Y1211712D03*
X1634153Y1207972D03*
X1630413D03*
X1634153Y1211712D03*
X1637893Y1207972D03*
Y1211712D03*
X1630413D03*
X1641633Y1207972D03*
X1628543Y1221062D03*
X1632283D03*
X1636023D03*
X1639763D03*
X1643504D03*
X1628543Y1228543D03*
Y1224803D03*
X1632283Y1232283D03*
Y1236023D03*
X1636023Y1228543D03*
Y1224803D03*
X1639763Y1232283D03*
Y1236023D03*
X1643504Y1228543D03*
Y1224803D03*
X1628543Y1239763D03*
X1639763D03*
X1643504Y1258465D03*
X1636023D03*
X1628543D03*
X1629278Y1348187D03*
X1641518D03*
X1633638D03*
X1629278Y1360099D03*
X1641518D03*
X1633638D03*
X1629278Y1384297D03*
Y1372385D03*
X1641518Y1384297D03*
Y1372385D03*
X1633638Y1384297D03*
Y1372385D03*
X1629278Y1396583D03*
X1641518D03*
X1633638D03*
Y1408495D03*
X1629278D03*
X1641518D03*
X1647244Y1075196D03*
X1654724D03*
X1658463Y1071455D03*
X1650983D03*
X1654724Y1078936D03*
Y1090157D03*
X1658464D03*
X1650984D03*
X1647244D03*
Y1093897D03*
X1658464Y1101377D03*
Y1105117D03*
X1650984D03*
X1645374Y1118208D03*
X1649114D03*
X1658464Y1108858D03*
X1654724D03*
X1650984D03*
X1647244D03*
X1649114Y1140649D03*
X1652854Y1136909D03*
X1645374Y1125688D03*
X1649114Y1136909D03*
X1652854Y1140649D03*
X1645374Y1155610D03*
Y1151869D03*
Y1148129D03*
X1652854D03*
X1649114Y1144389D03*
X1652854Y1155610D03*
X1649114Y1148129D03*
X1652854Y1151869D03*
X1656594D03*
X1660334D03*
Y1155610D03*
X1649114Y1151870D03*
X1645374Y1166830D03*
X1652854Y1159350D03*
X1660334Y1166830D03*
Y1170570D03*
X1645374Y1159350D03*
X1660334D03*
X1645374Y1170570D03*
X1652854D03*
Y1166830D03*
Y1185531D03*
X1656594Y1181791D03*
X1652854Y1178051D03*
Y1174310D03*
X1649114Y1181791D03*
X1656594Y1185531D03*
X1660334Y1174310D03*
Y1178051D03*
Y1185531D03*
X1645374Y1181791D03*
Y1174310D03*
X1649114Y1178051D03*
Y1189271D03*
X1652854D03*
X1649114Y1185531D03*
X1656594Y1193011D03*
X1652854Y1204232D03*
Y1196751D03*
Y1193011D03*
X1649114D03*
X1645374Y1196751D03*
X1649114Y1211712D03*
X1645374Y1207972D03*
X1660334Y1215452D03*
Y1211712D03*
X1654724Y1221062D03*
X1658464D03*
X1650984D03*
X1647244D03*
Y1232283D03*
Y1236023D03*
X1654724Y1232283D03*
X1658464Y1228543D03*
X1654724Y1236023D03*
X1658464Y1224803D03*
X1650984Y1228543D03*
Y1224803D03*
X1654724Y1239763D03*
X1658464Y1258465D03*
X1650984D03*
X1645878Y1348187D03*
X1653758D03*
X1658118D03*
X1645878Y1360099D03*
X1653758D03*
X1658118D03*
X1645878Y1384297D03*
Y1372385D03*
X1653758D03*
Y1384297D03*
X1658118D03*
Y1372385D03*
X1645878Y1396583D03*
X1653758D03*
X1658118D03*
X1645878Y1408495D03*
X1653758D03*
X1658118D03*
X1662204Y1075196D03*
X1669685D03*
X1673425Y1071455D03*
X1665944D03*
X1662203Y1090157D03*
X1669686Y1078936D03*
X1669684Y1090157D03*
X1662204Y1093897D03*
X1669685D03*
X1673425Y1105117D03*
X1665945D03*
X1669685Y1108858D03*
X1673425Y1116338D03*
Y1123818D03*
X1665944Y1112598D03*
Y1120078D03*
X1665945Y1108858D03*
X1662204Y1123818D03*
Y1120078D03*
Y1116338D03*
Y1108858D03*
X1671555Y1140649D03*
X1673425Y1131299D03*
X1662204Y1135039D03*
Y1131299D03*
Y1127558D03*
Y1138779D03*
X1664074Y1151869D03*
X1671555Y1148129D03*
X1664074Y1144389D03*
Y1159350D03*
X1671555D03*
X1664074Y1166830D03*
X1671555D03*
X1664074Y1189271D03*
Y1174310D03*
X1671555Y1181791D03*
Y1174310D03*
X1664074Y1181791D03*
X1671555Y1189271D03*
X1665945Y1194881D03*
X1664074Y1204232D03*
X1669685Y1202362D03*
X1673425Y1221062D03*
X1669685Y1209842D03*
X1665945Y1221062D03*
Y1217322D03*
X1662204Y1221062D03*
Y1232283D03*
Y1236023D03*
X1673425Y1224803D03*
Y1228543D03*
X1669685Y1232283D03*
Y1236023D03*
X1665945Y1224803D03*
Y1228543D03*
X1662204Y1239763D03*
X1669685D03*
X1673425Y1258465D03*
X1665945D03*
X1665998Y1348187D03*
X1670358D03*
X1665998Y1360099D03*
X1670358D03*
X1665998Y1384297D03*
Y1372385D03*
X1670358D03*
Y1384297D03*
X1665998Y1396583D03*
X1670358D03*
X1665998Y1408495D03*
X1670358D03*
X1677166Y1075196D03*
X1684646D03*
X1692126D03*
X1688385Y1071455D03*
X1680905D03*
X1677166Y1078936D03*
X1692126D03*
X1684646D03*
X1684644Y1090157D03*
X1677165Y1093897D03*
X1684645D03*
X1680905Y1105117D03*
X1677164Y1108857D03*
X1684645Y1108858D03*
X1690256Y1140649D03*
Y1155610D03*
Y1148129D03*
X1682775Y1166830D03*
X1679035Y1170570D03*
X1690256D03*
Y1178051D03*
X1682775Y1174310D03*
X1679035Y1178051D03*
X1682775Y1181791D03*
X1679035Y1185531D03*
X1682775Y1189271D03*
X1690256Y1185531D03*
X1680905Y1194881D03*
X1690256Y1193011D03*
X1679035D03*
X1692126Y1202362D03*
X1680905D03*
Y1198621D03*
X1677165D03*
X1684645Y1221062D03*
X1692126Y1209842D03*
X1680905Y1221062D03*
Y1217322D03*
X1677165Y1221062D03*
Y1213582D03*
X1680905D03*
Y1209842D03*
Y1206102D03*
X1688385Y1224803D03*
Y1228543D03*
X1684645Y1236023D03*
Y1232283D03*
X1692126D03*
X1680905Y1224803D03*
Y1228543D03*
X1677165Y1232283D03*
Y1236023D03*
X1680905Y1239763D03*
X1688385Y1258465D03*
X1680905D03*
X1678238Y1348187D03*
X1690478D03*
X1682598D03*
X1678238Y1360099D03*
X1690478D03*
X1682598D03*
X1678238Y1372385D03*
Y1384297D03*
X1690478D03*
Y1372385D03*
X1682598Y1384297D03*
Y1372385D03*
X1678238Y1396583D03*
X1690478D03*
X1682598D03*
X1678238Y1408495D03*
X1690478D03*
X1682598D03*
X1695866Y1078936D03*
X1699607Y1090158D03*
Y1082677D03*
Y1101378D03*
Y1123819D03*
Y1116339D03*
Y1108859D03*
Y1131300D03*
X1693996Y1170570D03*
Y1178051D03*
Y1185531D03*
Y1193011D03*
X1697676D03*
X1695866Y1202362D03*
X1699607Y1198621D03*
Y1221062D03*
Y1213582D03*
Y1206102D03*
Y1228543D03*
X1695866Y1250984D03*
X1699607Y1247243D03*
Y1239762D03*
X1694838Y1348187D03*
X1702718D03*
X1707078D03*
X1702718Y1360099D03*
X1707078D03*
X1694838D03*
Y1384297D03*
Y1372385D03*
X1702718D03*
Y1384297D03*
X1707078D03*
Y1372385D03*
X1694838Y1396583D03*
X1702718D03*
X1707078D03*
X1694838Y1408495D03*
X1702718D03*
X1707078D03*
X1714958Y1348187D03*
X1719318D03*
X1714958Y1360099D03*
X1719318D03*
X1714958Y1384297D03*
Y1372385D03*
X1719318D03*
Y1384297D03*
X1714958Y1396583D03*
X1719318D03*
X1714958Y1408495D03*
X1719318D03*
X1727198Y1348187D03*
X1739438D03*
X1731558D03*
X1727198Y1360099D03*
X1739438D03*
X1731558D03*
X1739438Y1372385D03*
X1731558Y1384297D03*
Y1372385D03*
X1727198D03*
Y1384297D03*
X1739438D03*
X1727198Y1396583D03*
X1739438D03*
X1731558D03*
X1727198Y1408495D03*
X1739438D03*
X1731558D03*
G54D52*
X956448Y-30304D03*
Y-33204D03*
X953192Y-25085D03*
X956445Y-25099D03*
X950167Y-26405D03*
X953207Y-27600D03*
X956460Y-27614D03*
X978036Y-64265D03*
X975011Y-65585D03*
X978051Y-66780D03*
X981289Y-64279D03*
X981292Y-69484D03*
Y-72384D03*
X981304Y-66794D03*
X1231351Y-77080D03*
X1234592Y-79984D03*
X1234604Y-77094D03*
X1234592Y-82584D03*
Y-71970D03*
X1231336Y-74565D03*
X1234589Y-74579D03*
X1231336Y-64265D03*
X1234589D03*
X1234592Y-69470D03*
X1231351Y-66780D03*
X1234604D03*
X1228311Y-65585D03*
Y-75885D03*
X1236692Y-35515D03*
X1236707Y-38030D03*
X1233667Y-36835D03*
X1236692Y-25215D03*
X1236707Y-27730D03*
X1233667Y-26535D03*
X1239948Y-32920D03*
X1239945Y-35529D03*
X1239948Y-30420D03*
Y-40934D03*
X1239960Y-38044D03*
X1239948Y-43534D03*
X1239945Y-25215D03*
X1239960Y-27730D03*
X1487851Y-77080D03*
X1491092Y-79984D03*
X1491104Y-77094D03*
X1491092Y-82584D03*
Y-71970D03*
X1487836Y-74565D03*
X1491089Y-74579D03*
X1487836Y-64265D03*
X1491089D03*
X1491092Y-69470D03*
X1487851Y-66780D03*
X1491104D03*
X1484811Y-65585D03*
Y-75885D03*
X1526448Y-33050D03*
X1523192Y-35645D03*
X1526445Y-35659D03*
X1526448Y-30550D03*
X1523207Y-38160D03*
X1526448Y-41064D03*
X1526460Y-38174D03*
X1526448Y-43664D03*
X1520167Y-36965D03*
X1523192Y-25345D03*
X1526445D03*
X1523207Y-27860D03*
X1526460D03*
X1520167Y-26665D03*
X1742336Y-74565D03*
Y-64265D03*
X1739311Y-65585D03*
Y-75885D03*
X1742351Y-77080D03*
X1745592Y-79984D03*
X1745604Y-77094D03*
X1745592Y-82584D03*
Y-71970D03*
X1745589Y-74579D03*
Y-64265D03*
X1745592Y-69470D03*
X1742351Y-66780D03*
X1745604D03*
X1804667Y-37095D03*
Y-26795D03*
X1810948Y-33180D03*
X1807692Y-35775D03*
X1810945Y-35789D03*
X1810948Y-30680D03*
X1807707Y-38290D03*
X1810948Y-41194D03*
X1810960Y-38304D03*
X1810948Y-43794D03*
X1807692Y-25475D03*
X1810945D03*
X1807707Y-27990D03*
X1810960D03*
G54D24*
X46348Y1727941D03*
Y1737941D03*
Y1773941D03*
Y1783941D03*
X333112Y1751624D03*
Y1761624D03*
X333212Y1797624D03*
Y1807624D03*
X619861Y1751765D03*
Y1761765D03*
X619475Y1798845D03*
Y1808845D03*
X907163Y1752566D03*
Y1762566D03*
X907166Y1800435D03*
Y1810435D03*
G54D40*
X266841Y421555D03*
Y550020D03*
X295856Y421555D03*
Y550020D03*
X723927Y421555D03*
Y550020D03*
X752942Y421555D03*
Y550020D03*
X1181014Y421555D03*
Y550020D03*
X1210029Y421555D03*
Y550020D03*
X1638101Y421555D03*
Y550020D03*
X1667116Y421555D03*
Y550020D03*
G54D56*
X1236871Y1715189D03*
X1236864Y1773377D03*
X1235371Y1802909D03*
G54D57*
X1236871Y1744208D03*
%LPC*%
G75*
G54D64*
G01X-20602Y-468335D02*
Y-543335D01*
X479398D01*
Y-468335D01*
X-20602D01*
G01X-8602Y-533335D02*
Y-538335D01*
G01X-10059Y-533335D02*
X-7145D01*
G01X-2235Y-538335D02*
X-4769D01*
Y-533335D01*
X-2235D01*
G01X-3249Y-535752D02*
X-4769D01*
G01X331Y-533335D02*
Y-538335D01*
X2865D01*
G01X6698Y-538502D02*
X6571Y-538418D01*
Y-538252D01*
X6698Y-538168D01*
X6825Y-538252D01*
Y-538418D01*
X6698Y-538502D01*
G01Y-536252D02*
X6571Y-536168D01*
Y-536002D01*
X6698Y-535918D01*
X6825Y-536002D01*
Y-536168D01*
X6698Y-536252D01*
G01X11481Y-540002D02*
X10848Y-539168D01*
X10531Y-538335D01*
Y-535002D01*
X10848Y-534168D01*
X11481Y-533335D01*
G01X16898D02*
X16391Y-533502D01*
X16011Y-533918D01*
X15758Y-534418D01*
X15568Y-535085D01*
X15505Y-535835D01*
X15568Y-536585D01*
X15758Y-537252D01*
X16011Y-537752D01*
X16391Y-538168D01*
X16898Y-538335D01*
X17405Y-538168D01*
X17785Y-537752D01*
X18038Y-537252D01*
X18228Y-536585D01*
X18291Y-535835D01*
X18228Y-535085D01*
X18038Y-534418D01*
X17785Y-533918D01*
X17405Y-533502D01*
X16898Y-533335D01*
G01X20605Y-537335D02*
X20985Y-537918D01*
X21491Y-538252D01*
X22061Y-538335D01*
X22568Y-538252D01*
X23075Y-537835D01*
X23391Y-537335D01*
X23455Y-536835D01*
X23328Y-536252D01*
X22885Y-535835D01*
X22441Y-535668D01*
X21871D01*
G01X22441D02*
X22821Y-535418D01*
X23138Y-535002D01*
X23265Y-534502D01*
X23138Y-534002D01*
X22821Y-533585D01*
X22251Y-533335D01*
X21681Y-533418D01*
X21111Y-533752D01*
G01X27415Y-540002D02*
X28048Y-539168D01*
X28365Y-538335D01*
Y-535002D01*
X28048Y-534168D01*
X27415Y-533335D01*
G01X30805Y-537335D02*
X31185Y-537918D01*
X31691Y-538252D01*
X32261Y-538335D01*
X32768Y-538252D01*
X33275Y-537835D01*
X33591Y-537335D01*
X33655Y-536835D01*
X33528Y-536252D01*
X33085Y-535835D01*
X32641Y-535668D01*
X32071D01*
G01X32641D02*
X33021Y-535418D01*
X33338Y-535002D01*
X33465Y-534502D01*
X33338Y-534002D01*
X33021Y-533585D01*
X32451Y-533335D01*
X31881Y-533418D01*
X31311Y-533752D01*
G01X36095Y-534168D02*
X36475Y-533668D01*
X36918Y-533418D01*
X37425Y-533335D01*
X38058Y-533502D01*
X38501Y-533918D01*
X38628Y-534418D01*
X38565Y-534918D01*
X38311Y-535335D01*
X37045Y-536168D01*
X36475Y-536752D01*
X36095Y-537585D01*
X35968Y-538335D01*
X38628D01*
G01X42271D02*
X42398Y-537252D01*
X42588Y-536335D01*
X42841Y-535502D01*
X43158Y-534585D01*
X43665Y-533335D01*
X41131D01*
G01X46675Y-536668D02*
X48321D01*
G01X51395Y-534168D02*
X51775Y-533668D01*
X52218Y-533418D01*
X52725Y-533335D01*
X53358Y-533502D01*
X53801Y-533918D01*
X53928Y-534418D01*
X53865Y-534918D01*
X53611Y-535335D01*
X52345Y-536168D01*
X51775Y-536752D01*
X51395Y-537585D01*
X51268Y-538335D01*
X53928D01*
G01X56305Y-537335D02*
X56685Y-537918D01*
X57191Y-538252D01*
X57761Y-538335D01*
X58268Y-538252D01*
X58775Y-537835D01*
X59091Y-537335D01*
X59155Y-536835D01*
X59028Y-536252D01*
X58585Y-535835D01*
X58141Y-535668D01*
X57571D01*
G01X58141D02*
X58521Y-535418D01*
X58838Y-535002D01*
X58965Y-534502D01*
X58838Y-534002D01*
X58521Y-533585D01*
X57951Y-533335D01*
X57381Y-533418D01*
X56811Y-533752D01*
G01X63558Y-538335D02*
Y-533335D01*
X61215Y-536918D01*
X64381D01*
G01X66505Y-537585D02*
X66885Y-538002D01*
X67328Y-538252D01*
X67898Y-538335D01*
X68468Y-538168D01*
X68911Y-537835D01*
X69228Y-537252D01*
X69291Y-536585D01*
X69165Y-535918D01*
X68848Y-535502D01*
X68405Y-535168D01*
X67961Y-535085D01*
X67518Y-535168D01*
X66948Y-535502D01*
X67138Y-533335D01*
X68848D01*
G01X76895Y-538335D02*
Y-533335D01*
X79301D01*
G01X78415Y-535752D02*
X76895D01*
G01X81615Y-538335D02*
X83198Y-533335D01*
X84781Y-538335D01*
G01X84211Y-536585D02*
X82185D01*
G01X86968Y-538335D02*
X89628Y-533335D01*
G01X86968D02*
X89628Y-538335D01*
G01X93398Y-538502D02*
X93271Y-538418D01*
Y-538252D01*
X93398Y-538168D01*
X93525Y-538252D01*
Y-538418D01*
X93398Y-538502D01*
G01Y-536252D02*
X93271Y-536168D01*
Y-536002D01*
X93398Y-535918D01*
X93525Y-536002D01*
Y-536168D01*
X93398Y-536252D01*
G01X98181Y-540002D02*
X97548Y-539168D01*
X97231Y-538335D01*
Y-535002D01*
X97548Y-534168D01*
X98181Y-533335D01*
G01X103598D02*
X103091Y-533502D01*
X102711Y-533918D01*
X102458Y-534418D01*
X102268Y-535085D01*
X102205Y-535835D01*
X102268Y-536585D01*
X102458Y-537252D01*
X102711Y-537752D01*
X103091Y-538168D01*
X103598Y-538335D01*
X104105Y-538168D01*
X104485Y-537752D01*
X104738Y-537252D01*
X104928Y-536585D01*
X104991Y-535835D01*
X104928Y-535085D01*
X104738Y-534418D01*
X104485Y-533918D01*
X104105Y-533502D01*
X103598Y-533335D01*
G01X107305Y-537335D02*
X107685Y-537918D01*
X108191Y-538252D01*
X108761Y-538335D01*
X109268Y-538252D01*
X109775Y-537835D01*
X110091Y-537335D01*
X110155Y-536835D01*
X110028Y-536252D01*
X109585Y-535835D01*
X109141Y-535668D01*
X108571D01*
G01X109141D02*
X109521Y-535418D01*
X109838Y-535002D01*
X109965Y-534502D01*
X109838Y-534002D01*
X109521Y-533585D01*
X108951Y-533335D01*
X108381Y-533418D01*
X107811Y-533752D01*
G01X114115Y-540002D02*
X114748Y-539168D01*
X115065Y-538335D01*
Y-535002D01*
X114748Y-534168D01*
X114115Y-533335D01*
G01X117505Y-537335D02*
X117885Y-537918D01*
X118391Y-538252D01*
X118961Y-538335D01*
X119468Y-538252D01*
X119975Y-537835D01*
X120291Y-537335D01*
X120355Y-536835D01*
X120228Y-536252D01*
X119785Y-535835D01*
X119341Y-535668D01*
X118771D01*
G01X119341D02*
X119721Y-535418D01*
X120038Y-535002D01*
X120165Y-534502D01*
X120038Y-534002D01*
X119721Y-533585D01*
X119151Y-533335D01*
X118581Y-533418D01*
X118011Y-533752D01*
G01X122921Y-537752D02*
X123365Y-538168D01*
X123871Y-538335D01*
X124378Y-538168D01*
X124821Y-537668D01*
X125138Y-536918D01*
X125265Y-536168D01*
Y-535252D01*
X125138Y-534502D01*
X124821Y-533835D01*
X124441Y-533502D01*
X123998Y-533335D01*
X123491Y-533502D01*
X123111Y-533835D01*
X122858Y-534335D01*
X122731Y-535002D01*
X122858Y-535585D01*
X123175Y-536168D01*
X123555Y-536502D01*
X123998Y-536585D01*
X124505Y-536418D01*
X124885Y-536002D01*
X125265Y-535252D01*
G01X128971Y-538335D02*
X129098Y-537252D01*
X129288Y-536335D01*
X129541Y-535502D01*
X129858Y-534585D01*
X130365Y-533335D01*
X127831D01*
G01X133375Y-536668D02*
X135021D01*
G01X137905Y-537335D02*
X138285Y-537918D01*
X138791Y-538252D01*
X139361Y-538335D01*
X139868Y-538252D01*
X140375Y-537835D01*
X140691Y-537335D01*
X140755Y-536835D01*
X140628Y-536252D01*
X140185Y-535835D01*
X139741Y-535668D01*
X139171D01*
G01X139741D02*
X140121Y-535418D01*
X140438Y-535002D01*
X140565Y-534502D01*
X140438Y-534002D01*
X140121Y-533585D01*
X139551Y-533335D01*
X138981Y-533418D01*
X138411Y-533752D01*
G01X143195Y-536252D02*
X143638Y-535668D01*
X144018Y-535335D01*
X144525Y-535168D01*
X144968Y-535335D01*
X145285Y-535668D01*
X145538Y-536168D01*
X145601Y-536752D01*
X145538Y-537252D01*
X145285Y-537752D01*
X144905Y-538168D01*
X144461Y-538335D01*
X143955Y-538168D01*
X143511Y-537668D01*
X143258Y-536918D01*
X143195Y-536085D01*
X143321Y-535002D01*
X143511Y-534418D01*
X143828Y-533835D01*
X144271Y-533418D01*
X144715Y-533335D01*
X145158Y-533502D01*
X145475Y-533918D01*
G01X149498Y-538335D02*
Y-533335D01*
X148738Y-534335D01*
G01Y-538335D02*
X150258D01*
G01X155358D02*
Y-533335D01*
X153015Y-536918D01*
X156181D01*
G01X174398Y-468335D02*
Y-543335D01*
G01Y-518335D02*
X277398D01*
Y-493335D01*
G01X174398D02*
X277398D01*
G01Y-468335D02*
Y-543335D01*
G01X279398Y-468335D02*
Y-543335D01*
G01X284905Y-528335D02*
Y-523335D01*
X286171D01*
X286678Y-523585D01*
X287058Y-523918D01*
X287375Y-524418D01*
X287628Y-525002D01*
X287691Y-525835D01*
X287628Y-526668D01*
X287375Y-527252D01*
X287058Y-527752D01*
X286678Y-528085D01*
X286171Y-528335D01*
X284905D01*
G01X289815D02*
X291398Y-523335D01*
X292981Y-528335D01*
G01X292411Y-526585D02*
X290385D01*
G01X296498Y-523335D02*
Y-528335D01*
G01X295041Y-523335D02*
X297955D01*
G01X302865Y-528335D02*
X300331D01*
Y-523335D01*
X302865D01*
G01X301851Y-525752D02*
X300331D01*
G01X306698Y-528502D02*
X306571Y-528418D01*
Y-528252D01*
X306698Y-528168D01*
X306825Y-528252D01*
Y-528418D01*
X306698Y-528502D01*
G01Y-526252D02*
X306571Y-526168D01*
Y-526002D01*
X306698Y-525918D01*
X306825Y-526002D01*
Y-526168D01*
X306698Y-526252D01*
G01X279398Y-518335D02*
X479398D01*
G01X285031Y-503335D02*
Y-498335D01*
X286551D01*
X287058Y-498585D01*
X287438Y-499168D01*
X287565Y-499835D01*
X287438Y-500502D01*
X287121Y-501002D01*
X286551Y-501252D01*
X285031D01*
G01X290258Y-503502D02*
X292538Y-498335D01*
G01X295041Y-503335D02*
Y-498335D01*
X297955Y-503335D01*
Y-498335D01*
G01X301598Y-503502D02*
X301471Y-503418D01*
Y-503252D01*
X301598Y-503168D01*
X301725Y-503252D01*
Y-503418D01*
X301598Y-503502D01*
G01Y-501252D02*
X301471Y-501168D01*
Y-501002D01*
X301598Y-500918D01*
X301725Y-501002D01*
Y-501168D01*
X301598Y-501252D01*
G01X279398Y-493335D02*
X479398D01*
G01X285031Y-478335D02*
Y-473335D01*
X286551D01*
X287058Y-473585D01*
X287438Y-474168D01*
X287565Y-474835D01*
X287438Y-475502D01*
X287121Y-476002D01*
X286551Y-476252D01*
X285031D01*
G01X290131Y-478335D02*
Y-473335D01*
X291715D01*
X292221Y-473585D01*
X292538Y-473918D01*
X292665Y-474585D01*
X292538Y-475252D01*
X292158Y-475668D01*
X291715Y-475918D01*
X290131D01*
G01X291715D02*
X292665Y-478335D01*
G01X296498D02*
X295991Y-478252D01*
X295548Y-477918D01*
X295168Y-477418D01*
X294915Y-476835D01*
X294788Y-476168D01*
Y-475502D01*
X294915Y-474835D01*
X295168Y-474252D01*
X295548Y-473752D01*
X295991Y-473418D01*
X296498Y-473335D01*
X297005Y-473418D01*
X297448Y-473752D01*
X297828Y-474252D01*
X298081Y-474835D01*
X298208Y-475502D01*
Y-476168D01*
X298081Y-476835D01*
X297828Y-477418D01*
X297448Y-477918D01*
X297005Y-478252D01*
X296498Y-478335D01*
G01X300331Y-477335D02*
X300648Y-477835D01*
X301028Y-478168D01*
X301471Y-478335D01*
X301978Y-478168D01*
X302358Y-477835D01*
X302738Y-477335D01*
X302865Y-476668D01*
Y-473335D01*
G01X307965Y-478335D02*
X305431D01*
Y-473335D01*
X307965D01*
G01X306951Y-475752D02*
X305431D01*
G01X313191Y-473752D02*
X312811Y-473502D01*
X312368Y-473335D01*
X311861D01*
X311291Y-473585D01*
X310848Y-474002D01*
X310531Y-474502D01*
X310278Y-475335D01*
X310215Y-476085D01*
X310341Y-476835D01*
X310531Y-477335D01*
X310911Y-477835D01*
X311355Y-478168D01*
X311798Y-478335D01*
X312241D01*
X312685Y-478168D01*
X313065Y-477918D01*
X313381Y-477585D01*
G01X316898Y-473335D02*
Y-478335D01*
G01X315441Y-473335D02*
X318355D01*
G01X321998Y-478502D02*
X321871Y-478418D01*
Y-478252D01*
X321998Y-478168D01*
X322125Y-478252D01*
Y-478418D01*
X321998Y-478502D01*
G01Y-476252D02*
X321871Y-476168D01*
Y-476002D01*
X321998Y-475918D01*
X322125Y-476002D01*
Y-476168D01*
X321998Y-476252D01*
G01X394258Y-543563D02*
Y-518563D01*
G01X397031Y-520835D02*
Y-525835D01*
X399565D01*
G01X402638Y-520835D02*
X404158D01*
G01X403398D02*
Y-525835D01*
G01X402638D02*
X404158D01*
G01X409005Y-523168D02*
X409258Y-522918D01*
X409448Y-522502D01*
X409575Y-521918D01*
X409448Y-521418D01*
X409195Y-521085D01*
X408751Y-520835D01*
X407041D01*
Y-525835D01*
X409131D01*
X409575Y-525502D01*
X409828Y-525002D01*
X409955Y-524418D01*
X409828Y-523835D01*
X409448Y-523335D01*
X409005Y-523168D01*
X407041D01*
G01X413598Y-526002D02*
X413471Y-525918D01*
Y-525752D01*
X413598Y-525668D01*
X413725Y-525752D01*
Y-525918D01*
X413598Y-526002D01*
G01Y-523752D02*
X413471Y-523668D01*
Y-523502D01*
X413598Y-523418D01*
X413725Y-523502D01*
Y-523668D01*
X413598Y-523752D01*
G01X437258Y-518563D02*
Y-543563D01*
G01X437398Y-518335D02*
Y-543335D01*
G01X441298Y-520835D02*
Y-525835D01*
G01X439841Y-520835D02*
X442755D01*
G01X446398Y-525835D02*
X446018Y-525752D01*
X445638Y-525418D01*
X445385Y-524835D01*
X445258Y-524168D01*
X445385Y-523502D01*
X445638Y-522918D01*
X446018Y-522585D01*
X446398Y-522502D01*
X446778Y-522585D01*
X447158Y-522918D01*
X447411Y-523502D01*
X447475Y-524168D01*
X447411Y-524835D01*
X447158Y-525418D01*
X446778Y-525752D01*
X446398Y-525835D01*
G01X451498D02*
X451118Y-525752D01*
X450738Y-525418D01*
X450485Y-524835D01*
X450358Y-524168D01*
X450485Y-523502D01*
X450738Y-522918D01*
X451118Y-522585D01*
X451498Y-522502D01*
X451878Y-522585D01*
X452258Y-522918D01*
X452511Y-523502D01*
X452575Y-524168D01*
X452511Y-524835D01*
X452258Y-525418D01*
X451878Y-525752D01*
X451498Y-525835D01*
G01X456598D02*
Y-520835D01*
G01X461698Y-526002D02*
X461571Y-525918D01*
Y-525752D01*
X461698Y-525668D01*
X461825Y-525752D01*
Y-525918D01*
X461698Y-526002D01*
G01Y-523752D02*
X461571Y-523668D01*
Y-523502D01*
X461698Y-523418D01*
X461825Y-523502D01*
Y-523668D01*
X461698Y-523752D01*
G01X437398Y-493335D02*
Y-518335D01*
G01X440031Y-500835D02*
Y-495835D01*
X441615D01*
X442121Y-496085D01*
X442438Y-496418D01*
X442565Y-497085D01*
X442438Y-497752D01*
X442058Y-498168D01*
X441615Y-498418D01*
X440031D01*
G01X441615D02*
X442565Y-500835D01*
G01X447665D02*
X445131D01*
Y-495835D01*
X447665D01*
G01X446651Y-498252D02*
X445131D01*
G01X449915Y-495835D02*
X451498Y-500835D01*
X453081Y-495835D01*
G01X456598Y-501002D02*
X456471Y-500918D01*
Y-500752D01*
X456598Y-500668D01*
X456725Y-500752D01*
Y-500918D01*
X456598Y-501002D01*
G01Y-498752D02*
X456471Y-498668D01*
Y-498502D01*
X456598Y-498418D01*
X456725Y-498502D01*
Y-498668D01*
X456598Y-498752D01*
G01X445411Y-546502D02*
X445518Y-546377D01*
X445598Y-546168D01*
X445651Y-545877D01*
X445598Y-545627D01*
X445491Y-545460D01*
X445305Y-545335D01*
X444585D01*
Y-547835D01*
X445465D01*
X445651Y-547668D01*
X445758Y-547418D01*
X445811Y-547127D01*
X445758Y-546835D01*
X445598Y-546585D01*
X445411Y-546502D01*
X444585D01*
G01X447878Y-547835D02*
Y-546168D01*
G01Y-546460D02*
X447771Y-546293D01*
X447611Y-546210D01*
X447425Y-546168D01*
X447238Y-546252D01*
X447078Y-546418D01*
X446971Y-546668D01*
X446918Y-547002D01*
X446971Y-547335D01*
X447078Y-547585D01*
X447238Y-547752D01*
X447425Y-547835D01*
X447611Y-547793D01*
X447771Y-547668D01*
X447878Y-547502D01*
G01X449198Y-547543D02*
X449331Y-547710D01*
X449518Y-547835D01*
X449678D01*
X449838Y-547752D01*
X449945Y-547627D01*
X449998Y-547460D01*
X449971Y-547210D01*
X449865Y-547085D01*
X449385Y-546835D01*
X449278Y-546543D01*
X449331Y-546335D01*
X449438Y-546210D01*
X449598Y-546168D01*
X449758Y-546210D01*
X449918Y-546335D01*
G01X451398Y-546710D02*
X452251D01*
X452171Y-546418D01*
X452038Y-546252D01*
X451851Y-546168D01*
X451665Y-546210D01*
X451505Y-546335D01*
X451398Y-546627D01*
X451345Y-546877D01*
Y-547127D01*
X451398Y-547377D01*
X451531Y-547627D01*
X451691Y-547793D01*
X451878Y-547835D01*
X452065Y-547752D01*
X452251Y-547502D01*
G01X453518Y-547835D02*
Y-545335D01*
G01Y-546585D02*
X453651Y-546335D01*
X453811Y-546210D01*
X453971Y-546168D01*
X454211Y-546252D01*
X454371Y-546418D01*
X454478Y-546710D01*
Y-547043D01*
X454425Y-547377D01*
X454318Y-547627D01*
X454131Y-547793D01*
X453971Y-547835D01*
X453811Y-547793D01*
X453651Y-547668D01*
X453518Y-547460D01*
G01X456198Y-547835D02*
X456038Y-547793D01*
X455878Y-547627D01*
X455771Y-547335D01*
X455718Y-547002D01*
X455771Y-546668D01*
X455878Y-546377D01*
X456038Y-546210D01*
X456198Y-546168D01*
X456358Y-546210D01*
X456518Y-546377D01*
X456625Y-546668D01*
X456651Y-547002D01*
X456625Y-547335D01*
X456518Y-547627D01*
X456358Y-547793D01*
X456198Y-547835D01*
G01X458878D02*
Y-546168D01*
G01Y-546460D02*
X458771Y-546293D01*
X458611Y-546210D01*
X458425Y-546168D01*
X458238Y-546252D01*
X458078Y-546418D01*
X457971Y-546668D01*
X457918Y-547002D01*
X457971Y-547335D01*
X458078Y-547585D01*
X458238Y-547752D01*
X458425Y-547835D01*
X458611Y-547793D01*
X458771Y-547668D01*
X458878Y-547502D01*
G01X460225Y-547835D02*
Y-546168D01*
G01Y-546502D02*
X460358Y-546335D01*
X460491Y-546210D01*
X460678Y-546168D01*
X460811Y-546210D01*
X460971Y-546335D01*
G01X463278Y-545335D02*
Y-547835D01*
G01Y-547460D02*
X463171Y-547668D01*
X463011Y-547793D01*
X462825Y-547835D01*
X462611Y-547752D01*
X462451Y-547543D01*
X462345Y-547293D01*
X462318Y-547002D01*
X462345Y-546710D01*
X462451Y-546460D01*
X462611Y-546252D01*
X462825Y-546168D01*
X463011Y-546210D01*
X463145Y-546293D01*
X463278Y-546460D01*
G01X466665Y-547835D02*
Y-545335D01*
X467331D01*
X467545Y-545460D01*
X467678Y-545627D01*
X467731Y-545960D01*
X467678Y-546293D01*
X467518Y-546502D01*
X467331Y-546627D01*
X466665D01*
G01X467331D02*
X467731Y-547835D01*
G01X468998Y-546710D02*
X469851D01*
X469771Y-546418D01*
X469638Y-546252D01*
X469451Y-546168D01*
X469265Y-546210D01*
X469105Y-546335D01*
X468998Y-546627D01*
X468945Y-546877D01*
Y-547127D01*
X468998Y-547377D01*
X469131Y-547627D01*
X469291Y-547793D01*
X469478Y-547835D01*
X469665Y-547752D01*
X469851Y-547502D01*
G01X471118Y-546168D02*
X471598Y-547835D01*
X472078Y-546168D01*
G01X473798Y-547918D02*
X473745Y-547877D01*
Y-547793D01*
X473798Y-547752D01*
X473851Y-547793D01*
Y-547877D01*
X473798Y-547918D01*
G01X475545Y-547543D02*
X475731Y-547752D01*
X475945Y-547835D01*
X476158Y-547752D01*
X476345Y-547502D01*
X476478Y-547127D01*
X476531Y-546752D01*
Y-546293D01*
X476478Y-545918D01*
X476345Y-545585D01*
X476185Y-545418D01*
X475998Y-545335D01*
X475785Y-545418D01*
X475625Y-545585D01*
X475518Y-545835D01*
X475465Y-546168D01*
X475518Y-546460D01*
X475651Y-546752D01*
X475811Y-546918D01*
X475998Y-546960D01*
X476211Y-546877D01*
X476371Y-546668D01*
X476531Y-546293D01*
G01X478411Y-546502D02*
X478518Y-546377D01*
X478598Y-546168D01*
X478651Y-545877D01*
X478598Y-545627D01*
X478491Y-545460D01*
X478305Y-545335D01*
X477585D01*
Y-547835D01*
X478465D01*
X478651Y-547668D01*
X478758Y-547418D01*
X478811Y-547127D01*
X478758Y-546835D01*
X478598Y-546585D01*
X478411Y-546502D01*
X477585D01*
G01X-1490433Y-1677216D02*
Y3837819D01*
X4496476D01*
Y-1677216D01*
X-1490433D01*
G01X-7782Y-515685D02*
X-6215D01*
Y-517575D01*
X-6685Y-518205D01*
X-7234Y-518625D01*
X-8017Y-518835D01*
X-8800Y-518625D01*
X-9349Y-518205D01*
X-9819Y-517575D01*
X-10132Y-516840D01*
X-10289Y-516000D01*
Y-515265D01*
X-10132Y-514635D01*
X-9819Y-513900D01*
X-9349Y-513270D01*
X-8879Y-512850D01*
X-8252Y-512535D01*
X-7704D01*
X-7077Y-512745D01*
X-6607Y-513165D01*
G01X-3675Y-512535D02*
Y-517050D01*
X-3362Y-517995D01*
X-2735Y-518625D01*
X-1952Y-518835D01*
X-1169Y-518625D01*
X-542Y-517995D01*
X-229Y-517050D01*
Y-512535D01*
G01X3408D02*
X5288D01*
G01X4348D02*
Y-518835D01*
G01X3408D02*
X5288D01*
G01X9003Y-517995D02*
X9630Y-518520D01*
X10335Y-518835D01*
X10961D01*
X11588Y-518520D01*
X12058Y-517995D01*
X12293Y-517260D01*
X12136Y-516525D01*
X11745Y-515895D01*
X11040Y-515475D01*
X10100Y-515265D01*
X9551Y-514845D01*
X9316Y-514110D01*
X9473Y-513375D01*
X9865Y-512850D01*
X10413Y-512535D01*
X10961D01*
X11510Y-512745D01*
X11980Y-513270D01*
G01X15303Y-518835D02*
Y-512535D01*
G01X18593D02*
Y-518835D01*
G01Y-515685D02*
X15303D01*
G01X21290Y-518835D02*
X23248Y-512535D01*
X25206Y-518835D01*
G01X24501Y-516630D02*
X21995D01*
G01X27746Y-518835D02*
Y-512535D01*
X31350Y-518835D01*
Y-512535D01*
G01X40425Y-518835D02*
Y-512535D01*
X41991D01*
X42618Y-512850D01*
X43088Y-513270D01*
X43480Y-513900D01*
X43793Y-514635D01*
X43871Y-515685D01*
X43793Y-516735D01*
X43480Y-517470D01*
X43088Y-518100D01*
X42618Y-518520D01*
X41991Y-518835D01*
X40425D01*
G01X47508Y-512535D02*
X49388D01*
G01X48448D02*
Y-518835D01*
G01X47508D02*
X49388D01*
G01X53103Y-517995D02*
X53730Y-518520D01*
X54435Y-518835D01*
X55061D01*
X55688Y-518520D01*
X56158Y-517995D01*
X56393Y-517260D01*
X56236Y-516525D01*
X55845Y-515895D01*
X55140Y-515475D01*
X54200Y-515265D01*
X53651Y-514845D01*
X53416Y-514110D01*
X53573Y-513375D01*
X53965Y-512850D01*
X54513Y-512535D01*
X55061D01*
X55610Y-512745D01*
X56080Y-513270D01*
G01X61048Y-512535D02*
Y-518835D01*
G01X59246Y-512535D02*
X62850D01*
G01X67348Y-519045D02*
X67191Y-518940D01*
Y-518730D01*
X67348Y-518625D01*
X67505Y-518730D01*
Y-518940D01*
X67348Y-519045D01*
G01X73491Y-519990D02*
X73805Y-518625D01*
G01X79948Y-512535D02*
Y-518835D01*
G01X78146Y-512535D02*
X81750D01*
G01X84290Y-518835D02*
X86248Y-512535D01*
X88206Y-518835D01*
G01X87501Y-516630D02*
X84995D01*
G01X92548Y-518835D02*
X91921Y-518730D01*
X91373Y-518310D01*
X90903Y-517680D01*
X90590Y-516945D01*
X90433Y-516105D01*
Y-515265D01*
X90590Y-514425D01*
X90903Y-513690D01*
X91373Y-513060D01*
X91921Y-512640D01*
X92548Y-512535D01*
X93175Y-512640D01*
X93723Y-513060D01*
X94193Y-513690D01*
X94506Y-514425D01*
X94663Y-515265D01*
Y-516105D01*
X94506Y-516945D01*
X94193Y-517680D01*
X93723Y-518310D01*
X93175Y-518730D01*
X92548Y-518835D01*
G01X98848D02*
Y-516000D01*
X97281Y-512535D01*
G01X100415D02*
X98848Y-516000D01*
G01X103425Y-512535D02*
Y-517050D01*
X103738Y-517995D01*
X104365Y-518625D01*
X105148Y-518835D01*
X105931Y-518625D01*
X106558Y-517995D01*
X106871Y-517050D01*
Y-512535D01*
G01X109490Y-518835D02*
X111448Y-512535D01*
X113406Y-518835D01*
G01X112701Y-516630D02*
X110195D01*
G01X115946Y-518835D02*
Y-512535D01*
X119550Y-518835D01*
Y-512535D01*
G01X-6529Y-523060D02*
X-6999Y-522745D01*
X-7547Y-522535D01*
X-8174D01*
X-8879Y-522850D01*
X-9427Y-523375D01*
X-9819Y-524005D01*
X-10132Y-525055D01*
X-10210Y-526000D01*
X-10054Y-526945D01*
X-9819Y-527575D01*
X-9349Y-528205D01*
X-8800Y-528625D01*
X-8252Y-528835D01*
X-7704D01*
X-7155Y-528625D01*
X-6685Y-528310D01*
X-6294Y-527890D01*
G01X-2892Y-522535D02*
X-1012D01*
G01X-1952D02*
Y-528835D01*
G01X-2892D02*
X-1012D01*
G01X4348Y-522535D02*
Y-528835D01*
G01X2546Y-522535D02*
X6150D01*
G01X10648Y-528835D02*
Y-526000D01*
X9081Y-522535D01*
G01X12215D02*
X10648Y-526000D01*
G01X21525Y-527575D02*
X21995Y-528310D01*
X22621Y-528730D01*
X23326Y-528835D01*
X23953Y-528730D01*
X24580Y-528205D01*
X24971Y-527575D01*
X25050Y-526945D01*
X24893Y-526210D01*
X24345Y-525685D01*
X23796Y-525475D01*
X23091D01*
G01X23796D02*
X24266Y-525160D01*
X24658Y-524635D01*
X24815Y-524005D01*
X24658Y-523375D01*
X24266Y-522850D01*
X23561Y-522535D01*
X22856Y-522640D01*
X22151Y-523060D01*
G01X27825Y-527575D02*
X28295Y-528310D01*
X28921Y-528730D01*
X29626Y-528835D01*
X30253Y-528730D01*
X30880Y-528205D01*
X31271Y-527575D01*
X31350Y-526945D01*
X31193Y-526210D01*
X30645Y-525685D01*
X30096Y-525475D01*
X29391D01*
G01X30096D02*
X30566Y-525160D01*
X30958Y-524635D01*
X31115Y-524005D01*
X30958Y-523375D01*
X30566Y-522850D01*
X29861Y-522535D01*
X29156Y-522640D01*
X28451Y-523060D01*
G01X34125Y-527575D02*
X34595Y-528310D01*
X35221Y-528730D01*
X35926Y-528835D01*
X36553Y-528730D01*
X37180Y-528205D01*
X37571Y-527575D01*
X37650Y-526945D01*
X37493Y-526210D01*
X36945Y-525685D01*
X36396Y-525475D01*
X35691D01*
G01X36396D02*
X36866Y-525160D01*
X37258Y-524635D01*
X37415Y-524005D01*
X37258Y-523375D01*
X36866Y-522850D01*
X36161Y-522535D01*
X35456Y-522640D01*
X34751Y-523060D01*
G01X41991Y-528835D02*
X42148Y-527470D01*
X42383Y-526315D01*
X42696Y-525265D01*
X43088Y-524110D01*
X43715Y-522535D01*
X40581D01*
G01X48291Y-528835D02*
X48448Y-527470D01*
X48683Y-526315D01*
X48996Y-525265D01*
X49388Y-524110D01*
X50015Y-522535D01*
X46881D01*
G01X54591Y-529990D02*
X54905Y-528625D01*
G01X61048Y-522535D02*
Y-528835D01*
G01X59246Y-522535D02*
X62850D01*
G01X65390Y-528835D02*
X67348Y-522535D01*
X69306Y-528835D01*
G01X68601Y-526630D02*
X66095D01*
G01X72708Y-522535D02*
X74588D01*
G01X73648D02*
Y-528835D01*
G01X72708D02*
X74588D01*
G01X77598Y-522535D02*
X78695Y-528835D01*
X79948Y-522535D01*
X81201Y-528835D01*
X82298Y-522535D01*
G01X84290Y-528835D02*
X86248Y-522535D01*
X88206Y-528835D01*
G01X87501Y-526630D02*
X84995D01*
G01X90746Y-528835D02*
Y-522535D01*
X94350Y-528835D01*
Y-522535D01*
G01X104756Y-530935D02*
X103973Y-529885D01*
X103581Y-528835D01*
Y-524635D01*
X103973Y-523585D01*
X104756Y-522535D01*
G01X116181Y-528835D02*
Y-522535D01*
X118140D01*
X118766Y-522850D01*
X119158Y-523270D01*
X119315Y-524110D01*
X119158Y-524950D01*
X118688Y-525475D01*
X118140Y-525790D01*
X116181D01*
G01X118140D02*
X119315Y-528835D01*
G01X124048Y-529045D02*
X123891Y-528940D01*
Y-528730D01*
X124048Y-528625D01*
X124205Y-528730D01*
Y-528940D01*
X124048Y-529045D01*
G01X130348Y-528835D02*
X129721Y-528730D01*
X129173Y-528310D01*
X128703Y-527680D01*
X128390Y-526945D01*
X128233Y-526105D01*
Y-525265D01*
X128390Y-524425D01*
X128703Y-523690D01*
X129173Y-523060D01*
X129721Y-522640D01*
X130348Y-522535D01*
X130975Y-522640D01*
X131523Y-523060D01*
X131993Y-523690D01*
X132306Y-524425D01*
X132463Y-525265D01*
Y-526105D01*
X132306Y-526945D01*
X131993Y-527680D01*
X131523Y-528310D01*
X130975Y-528730D01*
X130348Y-528835D01*
G01X136648Y-529045D02*
X136491Y-528940D01*
Y-528730D01*
X136648Y-528625D01*
X136805Y-528730D01*
Y-528940D01*
X136648Y-529045D01*
G01X144671Y-523060D02*
X144201Y-522745D01*
X143653Y-522535D01*
X143026D01*
X142321Y-522850D01*
X141773Y-523375D01*
X141381Y-524005D01*
X141068Y-525055D01*
X140990Y-526000D01*
X141146Y-526945D01*
X141381Y-527575D01*
X141851Y-528205D01*
X142400Y-528625D01*
X142948Y-528835D01*
X143496D01*
X144045Y-528625D01*
X144515Y-528310D01*
X144906Y-527890D01*
G01X149248Y-529045D02*
X149091Y-528940D01*
Y-528730D01*
X149248Y-528625D01*
X149405Y-528730D01*
Y-528940D01*
X149248Y-529045D01*
G01X155940Y-530935D02*
X156723Y-529885D01*
X157115Y-528835D01*
Y-524635D01*
X156723Y-523585D01*
X155940Y-522535D01*
G01X-10054Y-508835D02*
Y-502535D01*
X-6450Y-508835D01*
Y-502535D01*
G01X-1952Y-508835D02*
X-2579Y-508730D01*
X-3127Y-508310D01*
X-3597Y-507680D01*
X-3910Y-506945D01*
X-4067Y-506105D01*
Y-505265D01*
X-3910Y-504425D01*
X-3597Y-503690D01*
X-3127Y-503060D01*
X-2579Y-502640D01*
X-1952Y-502535D01*
X-1325Y-502640D01*
X-777Y-503060D01*
X-307Y-503690D01*
X6Y-504425D01*
X163Y-505265D01*
Y-506105D01*
X6Y-506945D01*
X-307Y-507680D01*
X-777Y-508310D01*
X-1325Y-508730D01*
X-1952Y-508835D01*
G01X4348Y-509045D02*
X4191Y-508940D01*
Y-508730D01*
X4348Y-508625D01*
X4505Y-508730D01*
Y-508940D01*
X4348Y-509045D01*
G01X9160Y-503585D02*
X9630Y-502955D01*
X10178Y-502640D01*
X10805Y-502535D01*
X11588Y-502745D01*
X12136Y-503270D01*
X12293Y-503900D01*
X12215Y-504530D01*
X11901Y-505055D01*
X10335Y-506105D01*
X9630Y-506840D01*
X9160Y-507890D01*
X9003Y-508835D01*
X12293D01*
G01X16948D02*
Y-502535D01*
X16008Y-503795D01*
G01Y-508835D02*
X17888D01*
G01X23248D02*
Y-502535D01*
X22308Y-503795D01*
G01Y-508835D02*
X24188D01*
G01X29391Y-509990D02*
X29705Y-508625D01*
G01X33498Y-502535D02*
X34595Y-508835D01*
X35848Y-502535D01*
X37101Y-508835D01*
X38198Y-502535D01*
G01X43715Y-508835D02*
X40581D01*
Y-502535D01*
X43715D01*
G01X42461Y-505580D02*
X40581D01*
G01X46646Y-508835D02*
Y-502535D01*
X50250Y-508835D01*
Y-502535D01*
G01X53103Y-508835D02*
Y-502535D01*
G01X56393D02*
Y-508835D01*
G01Y-505685D02*
X53103D01*
G01X59325Y-502535D02*
Y-507050D01*
X59638Y-507995D01*
X60265Y-508625D01*
X61048Y-508835D01*
X61831Y-508625D01*
X62458Y-507995D01*
X62771Y-507050D01*
Y-502535D01*
G01X65390Y-508835D02*
X67348Y-502535D01*
X69306Y-508835D01*
G01X68601Y-506630D02*
X66095D01*
G01X78460Y-503585D02*
X78930Y-502955D01*
X79478Y-502640D01*
X80105Y-502535D01*
X80888Y-502745D01*
X81436Y-503270D01*
X81593Y-503900D01*
X81515Y-504530D01*
X81201Y-505055D01*
X79635Y-506105D01*
X78930Y-506840D01*
X78460Y-507890D01*
X78303Y-508835D01*
X81593D01*
G01X84446D02*
Y-502535D01*
X88050Y-508835D01*
Y-502535D01*
G01X90825Y-508835D02*
Y-502535D01*
X92391D01*
X93018Y-502850D01*
X93488Y-503270D01*
X93880Y-503900D01*
X94193Y-504635D01*
X94271Y-505685D01*
X94193Y-506735D01*
X93880Y-507470D01*
X93488Y-508100D01*
X93018Y-508520D01*
X92391Y-508835D01*
X90825D01*
G01X103581D02*
Y-502535D01*
X105540D01*
X106166Y-502850D01*
X106558Y-503270D01*
X106715Y-504110D01*
X106558Y-504950D01*
X106088Y-505475D01*
X105540Y-505790D01*
X103581D01*
G01X105540D02*
X106715Y-508835D01*
G01X109725D02*
Y-502535D01*
X111291D01*
X111918Y-502850D01*
X112388Y-503270D01*
X112780Y-503900D01*
X113093Y-504635D01*
X113171Y-505685D01*
X113093Y-506735D01*
X112780Y-507470D01*
X112388Y-508100D01*
X111918Y-508520D01*
X111291Y-508835D01*
X109725D01*
G01X117748Y-509045D02*
X117591Y-508940D01*
Y-508730D01*
X117748Y-508625D01*
X117905Y-508730D01*
Y-508940D01*
X117748Y-509045D01*
G01X14048Y-498135D02*
X11528Y-497718D01*
X9323Y-496052D01*
X7433Y-493552D01*
X6173Y-490635D01*
X5543Y-487302D01*
Y-483968D01*
X6173Y-480635D01*
X7433Y-477718D01*
X9323Y-475219D01*
X11528Y-473552D01*
X14048Y-473135D01*
X16568Y-473552D01*
X18773Y-475219D01*
X20663Y-477718D01*
X21923Y-480635D01*
X22553Y-483968D01*
Y-487302D01*
X21923Y-490635D01*
X20663Y-493552D01*
X18773Y-496052D01*
X16568Y-497718D01*
X14048Y-498135D01*
G01X16568Y-491468D02*
X20348Y-498135D01*
G01X33893Y-481469D02*
Y-493135D01*
X35153Y-496052D01*
X37043Y-497718D01*
X39248Y-498135D01*
X41453Y-497718D01*
X43343Y-496052D01*
X44603Y-493135D01*
G01Y-498135D02*
Y-481469D01*
G01X70118Y-498135D02*
Y-481469D01*
G01Y-484385D02*
X68858Y-482719D01*
X66968Y-481885D01*
X64763Y-481469D01*
X62558Y-482302D01*
X60668Y-483968D01*
X59408Y-486469D01*
X58778Y-489802D01*
X59408Y-493135D01*
X60668Y-495636D01*
X62558Y-497302D01*
X64763Y-498135D01*
X66968Y-497718D01*
X68858Y-496469D01*
X70118Y-494802D01*
G01X84293Y-498135D02*
Y-481469D01*
G01Y-485635D02*
X85553Y-483552D01*
X87443Y-481885D01*
X89963Y-481469D01*
X92168Y-481885D01*
X94058Y-483552D01*
X95003Y-486469D01*
Y-498135D01*
G01X114848Y-473135D02*
Y-498135D01*
G01X110438Y-481469D02*
X119258D01*
G01X145718Y-498135D02*
Y-481469D01*
G01Y-484385D02*
X144458Y-482719D01*
X142568Y-481885D01*
X140363Y-481469D01*
X138158Y-482302D01*
X136268Y-483968D01*
X135008Y-486469D01*
X134378Y-489802D01*
X135008Y-493135D01*
X136268Y-495636D01*
X138158Y-497302D01*
X140363Y-498135D01*
X142568Y-497718D01*
X144458Y-496469D01*
X145718Y-494802D01*
G01X185398Y-477835D02*
Y-485835D01*
X189398D01*
G01X197198D02*
Y-480502D01*
G01Y-481435D02*
X196798Y-480902D01*
X196198Y-480635D01*
X195498Y-480502D01*
X194798Y-480768D01*
X194198Y-481302D01*
X193798Y-482102D01*
X193598Y-483168D01*
X193798Y-484235D01*
X194198Y-485035D01*
X194798Y-485568D01*
X195498Y-485835D01*
X196198Y-485702D01*
X196798Y-485302D01*
X197198Y-484769D01*
G01X201298Y-488235D02*
X201898Y-488502D01*
X202698Y-488235D01*
X203198Y-487702D01*
X203598Y-487035D01*
X204198Y-484902D01*
X205498Y-480502D01*
G01X202298D02*
X204198Y-484902D01*
G01X209898Y-482235D02*
X213098D01*
X212798Y-481302D01*
X212298Y-480768D01*
X211598Y-480502D01*
X210898Y-480635D01*
X210298Y-481035D01*
X209898Y-481968D01*
X209698Y-482769D01*
Y-483568D01*
X209898Y-484368D01*
X210398Y-485168D01*
X210998Y-485702D01*
X211698Y-485835D01*
X212398Y-485568D01*
X213098Y-484769D01*
G01X217998Y-485835D02*
Y-480502D01*
G01Y-481568D02*
X218498Y-481035D01*
X218998Y-480635D01*
X219698Y-480502D01*
X220198Y-480635D01*
X220798Y-481035D01*
G01X211398Y-535835D02*
Y-532235D01*
X209398Y-527835D01*
G01X213398D02*
X211398Y-532235D01*
G01X217698Y-530502D02*
Y-534235D01*
X218098Y-535168D01*
X218698Y-535702D01*
X219398Y-535835D01*
X220098Y-535702D01*
X220698Y-535168D01*
X221098Y-534235D01*
G01Y-535835D02*
Y-530502D01*
G01X225698Y-535835D02*
Y-530502D01*
G01Y-531835D02*
X226098Y-531168D01*
X226698Y-530635D01*
X227498Y-530502D01*
X228198Y-530635D01*
X228798Y-531168D01*
X229098Y-532102D01*
Y-535835D01*
G01X237198D02*
Y-530502D01*
G01Y-531435D02*
X236798Y-530902D01*
X236198Y-530635D01*
X235498Y-530502D01*
X234798Y-530768D01*
X234198Y-531302D01*
X233798Y-532102D01*
X233598Y-533168D01*
X233798Y-534235D01*
X234198Y-535035D01*
X234798Y-535568D01*
X235498Y-535835D01*
X236198Y-535702D01*
X236798Y-535302D01*
X237198Y-534769D01*
G01X212698Y-505735D02*
X214698D01*
Y-508135D01*
X214098Y-508935D01*
X213398Y-509468D01*
X212398Y-509735D01*
X211398Y-509468D01*
X210698Y-508935D01*
X210098Y-508135D01*
X209698Y-507202D01*
X209498Y-506135D01*
Y-505202D01*
X209698Y-504402D01*
X210098Y-503468D01*
X210698Y-502668D01*
X211298Y-502135D01*
X212098Y-501735D01*
X212798D01*
X213598Y-502002D01*
X214198Y-502535D01*
G01X217798Y-509735D02*
Y-501735D01*
X222398Y-509735D01*
Y-501735D01*
G01X225898Y-509735D02*
Y-501735D01*
X227898D01*
X228698Y-502135D01*
X229298Y-502668D01*
X229798Y-503468D01*
X230198Y-504402D01*
X230298Y-505735D01*
X230198Y-507068D01*
X229798Y-508002D01*
X229298Y-508802D01*
X228698Y-509335D01*
X227898Y-509735D01*
X225898D01*
G01X235898D02*
X236098Y-508002D01*
X236398Y-506535D01*
X236798Y-505202D01*
X237298Y-503735D01*
X238098Y-501735D01*
X234098D01*
G01X244298Y-486335D02*
Y-478335D01*
X243098Y-479935D01*
G01Y-486335D02*
X245498D01*
G01X252098D02*
X252298Y-484602D01*
X252598Y-483135D01*
X252998Y-481802D01*
X253498Y-480335D01*
X254298Y-478335D01*
X250298D01*
G01X311998Y-529168D02*
X312598Y-528368D01*
X313298Y-527968D01*
X314098Y-527835D01*
X315098Y-528102D01*
X315798Y-528768D01*
X315998Y-529568D01*
X315898Y-530369D01*
X315498Y-531035D01*
X313498Y-532368D01*
X312598Y-533302D01*
X311998Y-534635D01*
X311798Y-535835D01*
X315998D01*
G01X321898Y-527835D02*
X321098Y-528102D01*
X320498Y-528768D01*
X320098Y-529568D01*
X319798Y-530635D01*
X319698Y-531835D01*
X319798Y-533035D01*
X320098Y-534102D01*
X320498Y-534902D01*
X321098Y-535568D01*
X321898Y-535835D01*
X322698Y-535568D01*
X323298Y-534902D01*
X323698Y-534102D01*
X323998Y-533035D01*
X324098Y-531835D01*
X323998Y-530635D01*
X323698Y-529568D01*
X323298Y-528768D01*
X322698Y-528102D01*
X321898Y-527835D01*
G01X327998Y-529168D02*
X328598Y-528368D01*
X329298Y-527968D01*
X330098Y-527835D01*
X331098Y-528102D01*
X331798Y-528768D01*
X331998Y-529568D01*
X331898Y-530369D01*
X331498Y-531035D01*
X329498Y-532368D01*
X328598Y-533302D01*
X327998Y-534635D01*
X327798Y-535835D01*
X331998D01*
G01X335698Y-534235D02*
X336298Y-535168D01*
X337098Y-535702D01*
X337998Y-535835D01*
X338798Y-535702D01*
X339598Y-535035D01*
X340098Y-534235D01*
X340198Y-533435D01*
X339998Y-532502D01*
X339298Y-531835D01*
X338598Y-531568D01*
X337698D01*
G01X338598D02*
X339198Y-531168D01*
X339698Y-530502D01*
X339898Y-529702D01*
X339698Y-528902D01*
X339198Y-528235D01*
X338298Y-527835D01*
X337398Y-527968D01*
X336498Y-528502D01*
G01X344098Y-536102D02*
X347698Y-527835D01*
G01X353898D02*
X353098Y-528102D01*
X352498Y-528768D01*
X352098Y-529568D01*
X351798Y-530635D01*
X351698Y-531835D01*
X351798Y-533035D01*
X352098Y-534102D01*
X352498Y-534902D01*
X353098Y-535568D01*
X353898Y-535835D01*
X354698Y-535568D01*
X355298Y-534902D01*
X355698Y-534102D01*
X355998Y-533035D01*
X356098Y-531835D01*
X355998Y-530635D01*
X355698Y-529568D01*
X355298Y-528768D01*
X354698Y-528102D01*
X353898Y-527835D01*
G01X361898Y-535835D02*
Y-527835D01*
X360698Y-529435D01*
G01Y-535835D02*
X363098D01*
G01X368098Y-536102D02*
X371698Y-527835D01*
G01X377898D02*
X377098Y-528102D01*
X376498Y-528768D01*
X376098Y-529568D01*
X375798Y-530635D01*
X375698Y-531835D01*
X375798Y-533035D01*
X376098Y-534102D01*
X376498Y-534902D01*
X377098Y-535568D01*
X377898Y-535835D01*
X378698Y-535568D01*
X379298Y-534902D01*
X379698Y-534102D01*
X379998Y-533035D01*
X380098Y-531835D01*
X379998Y-530635D01*
X379698Y-529568D01*
X379298Y-528768D01*
X378698Y-528102D01*
X377898Y-527835D01*
G01X384198Y-534902D02*
X384898Y-535568D01*
X385698Y-535835D01*
X386498Y-535568D01*
X387198Y-534769D01*
X387698Y-533568D01*
X387898Y-532368D01*
Y-530902D01*
X387698Y-529702D01*
X387198Y-528635D01*
X386598Y-528102D01*
X385898Y-527835D01*
X385098Y-528102D01*
X384498Y-528635D01*
X384098Y-529435D01*
X383898Y-530502D01*
X384098Y-531435D01*
X384598Y-532368D01*
X385198Y-532902D01*
X385898Y-533035D01*
X386698Y-532769D01*
X387298Y-532102D01*
X387898Y-530902D01*
G01X311698Y-510835D02*
Y-502835D01*
X313698D01*
X314498Y-503235D01*
X315098Y-503768D01*
X315598Y-504568D01*
X315998Y-505502D01*
X316098Y-506835D01*
X315998Y-508168D01*
X315598Y-509102D01*
X315098Y-509902D01*
X314498Y-510435D01*
X313698Y-510835D01*
X311698D01*
G01X319398D02*
X321898Y-502835D01*
X324398Y-510835D01*
G01X323498Y-508035D02*
X320298D01*
G01X329898Y-502835D02*
X329098Y-503102D01*
X328498Y-503768D01*
X328098Y-504568D01*
X327798Y-505635D01*
X327698Y-506835D01*
X327798Y-508035D01*
X328098Y-509102D01*
X328498Y-509902D01*
X329098Y-510568D01*
X329898Y-510835D01*
X330698Y-510568D01*
X331298Y-509902D01*
X331698Y-509102D01*
X331998Y-508035D01*
X332098Y-506835D01*
X331998Y-505635D01*
X331698Y-504568D01*
X331298Y-503768D01*
X330698Y-503102D01*
X329898Y-502835D01*
G01X335998Y-510835D02*
Y-502835D01*
X339798D01*
G01X338398Y-506702D02*
X335998D01*
G01X345898Y-502835D02*
X345098Y-503102D01*
X344498Y-503768D01*
X344098Y-504568D01*
X343798Y-505635D01*
X343698Y-506835D01*
X343798Y-508035D01*
X344098Y-509102D01*
X344498Y-509902D01*
X345098Y-510568D01*
X345898Y-510835D01*
X346698Y-510568D01*
X347298Y-509902D01*
X347698Y-509102D01*
X347998Y-508035D01*
X348098Y-506835D01*
X347998Y-505635D01*
X347698Y-504568D01*
X347298Y-503768D01*
X346698Y-503102D01*
X345898Y-502835D01*
G01X353898D02*
Y-510835D01*
G01X351598Y-502835D02*
X356198D01*
G01X363898Y-510835D02*
X359898D01*
Y-502835D01*
X363898D01*
G01X362298Y-506702D02*
X359898D01*
G01X370698Y-506568D02*
X371098Y-506168D01*
X371398Y-505502D01*
X371598Y-504568D01*
X371398Y-503768D01*
X370998Y-503235D01*
X370298Y-502835D01*
X367598D01*
Y-510835D01*
X370898D01*
X371598Y-510302D01*
X371998Y-509502D01*
X372198Y-508568D01*
X371998Y-507635D01*
X371398Y-506835D01*
X370698Y-506568D01*
X367598D01*
G01X376698Y-502835D02*
X379098D01*
G01X377898D02*
Y-510835D01*
G01X376698D02*
X379098D01*
G01X383998D02*
Y-502835D01*
X387798D01*
G01X386398Y-506702D02*
X383998D01*
G01X393898Y-502835D02*
X393098Y-503102D01*
X392498Y-503768D01*
X392098Y-504568D01*
X391798Y-505635D01*
X391698Y-506835D01*
X391798Y-508035D01*
X392098Y-509102D01*
X392498Y-509902D01*
X393098Y-510568D01*
X393898Y-510835D01*
X394698Y-510568D01*
X395298Y-509902D01*
X395698Y-509102D01*
X395998Y-508035D01*
X396098Y-506835D01*
X395998Y-505635D01*
X395698Y-504568D01*
X395298Y-503768D01*
X394698Y-503102D01*
X393898Y-502835D01*
G01X329498Y-485835D02*
Y-477835D01*
X333298D01*
G01X331898Y-481702D02*
X329498D01*
G01X339398Y-477835D02*
X338598Y-478102D01*
X337998Y-478768D01*
X337598Y-479568D01*
X337298Y-480635D01*
X337198Y-481835D01*
X337298Y-483035D01*
X337598Y-484102D01*
X337998Y-484902D01*
X338598Y-485568D01*
X339398Y-485835D01*
X340198Y-485568D01*
X340798Y-484902D01*
X341198Y-484102D01*
X341498Y-483035D01*
X341598Y-481835D01*
X341498Y-480635D01*
X341198Y-479568D01*
X340798Y-478768D01*
X340198Y-478102D01*
X339398Y-477835D01*
G01X347398D02*
Y-485835D01*
G01X345098Y-477835D02*
X349698D01*
G01X352398Y-488502D02*
X358398D01*
G01X361898Y-482235D02*
X365098D01*
X364798Y-481302D01*
X364298Y-480768D01*
X363598Y-480502D01*
X362898Y-480635D01*
X362298Y-481035D01*
X361898Y-481968D01*
X361698Y-482769D01*
Y-483568D01*
X361898Y-484368D01*
X362398Y-485168D01*
X362998Y-485702D01*
X363698Y-485835D01*
X364398Y-485568D01*
X365098Y-484769D01*
G01X369898Y-480502D02*
X372898Y-485835D01*
G01Y-480502D02*
X369898Y-485835D01*
G01X377598Y-488502D02*
Y-480502D01*
G01Y-481702D02*
X378098Y-481035D01*
X378598Y-480635D01*
X379398Y-480502D01*
X380098Y-480635D01*
X380798Y-481302D01*
X381098Y-482235D01*
X381198Y-483168D01*
X381098Y-484102D01*
X380798Y-485035D01*
X380198Y-485568D01*
X379398Y-485835D01*
X378698Y-485702D01*
X377998Y-485302D01*
X377598Y-484769D01*
G01X389198Y-485835D02*
Y-480502D01*
G01Y-481435D02*
X388798Y-480902D01*
X388198Y-480635D01*
X387498Y-480502D01*
X386798Y-480768D01*
X386198Y-481302D01*
X385798Y-482102D01*
X385598Y-483168D01*
X385798Y-484235D01*
X386198Y-485035D01*
X386798Y-485568D01*
X387498Y-485835D01*
X388198Y-485702D01*
X388798Y-485302D01*
X389198Y-484769D01*
G01X393698Y-485835D02*
Y-480502D01*
G01Y-481835D02*
X394098Y-481168D01*
X394698Y-480635D01*
X395498Y-480502D01*
X396198Y-480635D01*
X396798Y-481168D01*
X397098Y-482102D01*
Y-485835D01*
G01X405198Y-477835D02*
Y-485835D01*
G01Y-484635D02*
X404798Y-485302D01*
X404198Y-485702D01*
X403498Y-485835D01*
X402698Y-485568D01*
X402098Y-484902D01*
X401698Y-484102D01*
X401598Y-483168D01*
X401698Y-482235D01*
X402098Y-481435D01*
X402698Y-480768D01*
X403498Y-480502D01*
X404198Y-480635D01*
X404698Y-480902D01*
X405198Y-481435D01*
G01X409898Y-482235D02*
X413098D01*
X412798Y-481302D01*
X412298Y-480768D01*
X411598Y-480502D01*
X410898Y-480635D01*
X410298Y-481035D01*
X409898Y-481968D01*
X409698Y-482769D01*
Y-483568D01*
X409898Y-484368D01*
X410398Y-485168D01*
X410998Y-485702D01*
X411698Y-485835D01*
X412398Y-485568D01*
X413098Y-484769D01*
G01X417998Y-485835D02*
Y-480502D01*
G01Y-481568D02*
X418498Y-481035D01*
X418998Y-480635D01*
X419698Y-480502D01*
X420198Y-480635D01*
X420798Y-481035D01*
G01X424398Y-488502D02*
X430398D01*
G01X433598Y-485835D02*
Y-477835D01*
G01Y-481835D02*
X434098Y-481035D01*
X434698Y-480635D01*
X435298Y-480502D01*
X436198Y-480768D01*
X436798Y-481302D01*
X437198Y-482235D01*
Y-483302D01*
X436998Y-484368D01*
X436598Y-485168D01*
X435898Y-485702D01*
X435298Y-485835D01*
X434698Y-485702D01*
X434098Y-485302D01*
X433598Y-484635D01*
G01X445198Y-477835D02*
Y-485835D01*
G01Y-484635D02*
X444798Y-485302D01*
X444198Y-485702D01*
X443498Y-485835D01*
X442698Y-485568D01*
X442098Y-484902D01*
X441698Y-484102D01*
X441598Y-483168D01*
X441698Y-482235D01*
X442098Y-481435D01*
X442698Y-480768D01*
X443498Y-480502D01*
X444198Y-480635D01*
X444698Y-480902D01*
X445198Y-481435D01*
G01X400398Y-538835D02*
Y-530835D01*
X399198Y-532435D01*
G01Y-538835D02*
X401598D01*
G01X406498Y-535502D02*
X407198Y-534568D01*
X407798Y-534035D01*
X408598Y-533768D01*
X409298Y-534035D01*
X409798Y-534568D01*
X410198Y-535368D01*
X410298Y-536302D01*
X410198Y-537102D01*
X409798Y-537902D01*
X409198Y-538568D01*
X408498Y-538835D01*
X407698Y-538568D01*
X406998Y-537769D01*
X406598Y-536568D01*
X406498Y-535235D01*
X406698Y-533502D01*
X406998Y-532568D01*
X407498Y-531635D01*
X408198Y-530968D01*
X408898Y-530835D01*
X409598Y-531102D01*
X410098Y-531768D01*
G01X416398Y-539102D02*
X416198Y-538968D01*
Y-538702D01*
X416398Y-538568D01*
X416598Y-538702D01*
Y-538968D01*
X416398Y-539102D01*
G01X422498Y-535502D02*
X423198Y-534568D01*
X423798Y-534035D01*
X424598Y-533768D01*
X425298Y-534035D01*
X425798Y-534568D01*
X426198Y-535368D01*
X426298Y-536302D01*
X426198Y-537102D01*
X425798Y-537902D01*
X425198Y-538568D01*
X424498Y-538835D01*
X423698Y-538568D01*
X422998Y-537769D01*
X422598Y-536568D01*
X422498Y-535235D01*
X422698Y-533502D01*
X422998Y-532568D01*
X423498Y-531635D01*
X424198Y-530968D01*
X424898Y-530835D01*
X425598Y-531102D01*
X426098Y-531768D01*
G01X445398Y-538835D02*
Y-530835D01*
X444198Y-532435D01*
G01Y-538835D02*
X446598D01*
G01X453198D02*
X453398Y-537102D01*
X453698Y-535635D01*
X454098Y-534302D01*
X454598Y-532835D01*
X455398Y-530835D01*
X451398D01*
G01X461398Y-539102D02*
X461198Y-538968D01*
Y-538702D01*
X461398Y-538568D01*
X461598Y-538702D01*
Y-538968D01*
X461398Y-539102D01*
G01X467498Y-532168D02*
X468098Y-531368D01*
X468798Y-530968D01*
X469598Y-530835D01*
X470598Y-531102D01*
X471298Y-531768D01*
X471498Y-532568D01*
X471398Y-533369D01*
X470998Y-534035D01*
X468998Y-535368D01*
X468098Y-536302D01*
X467498Y-537635D01*
X467298Y-538835D01*
X471498D01*
G01X465498Y-513835D02*
Y-505835D01*
X469298D01*
G01X467898Y-509702D02*
X465498D01*
M02*
